FILE_TYPE=EXPANDEDPARTLIST;
{ Packager-XL run on 24-Aug-2023 AT 15:36:33 }
DIRECTIVES
 PST_VERSION='PST_HDL_CENTRIC_VERSION_0';
 ROOT_DRAWING='S9S_MB_2U';
 POST_TIME='24-Aug-2023 AT 15:36:33';
 SOURCE_TOOL='PACKAGER_XL';
END_DIRECTIVES;

PART_NAME
 BT1 'CONN2_AAABAT029Y19-CONN2_AAA-BA':;

SECTION_NUMBER 1
 '@S9S_MB_2U_LIB.S9S_MB_2U(SCH_1):PAGE177_I63@PURE_QUANTA.CONN2_AAABAT029Y19(CHIPS)':
 C_PATH='@s9s_mb_2u_lib.s9s_mb_2u(sch_1):page177_i63@pure_quanta.conn2_aaabat029~
y19(chips)',
 P_PATH='@s9s_mb_2u_lib.s9s_mb_2u(sch_1):page185_i63@pure_quanta.conn2_aaabat029~
y19(chips)',
 PATH='I63',
 DRAWING='@S9S_MB_2U_LIB.S9S_MB_2U(SCH_1):PAGE177',
 PHYS_PAGE='185',
 XY='(2725,350)',
 ROT='2',
 VER='1',
 CDS_LIB='pure_quanta',
 CDS_PART_NAME='CONN2_AAABAT029Y19-CONN2_AAA-BA',
 PART_TYPE='THLF',
 MATERIAL='IO',
 VALUE='CONN2_AAA-BAT-029-Y19',
 PRIM_FILE='./archive_libs/logical/conn2_aaabat029y19/chips/chips.prt';

PART_NAME
 C1 'Q_CAP_C0402-10UF,6.3V,20%,X6S,A':;

SECTION_NUMBER 1
 '@S9S_MB_2U_LIB.S9S_MB_2U(SCH_1):PAGE37_I15@PURE_QUANTA.Q_CAP(CHIPS)':
 C_PATH='@s9s_mb_2u_lib.s9s_mb_2u(sch_1):page37_i15@pure_quanta.q_cap(chips)',
 P_PATH='@s9s_mb_2u_lib.s9s_mb_2u(sch_1):page37_i15@pure_quanta.q_cap(chips)',
 PATH='I15',
 DRAWING='@S9S_MB_2U_LIB.S9S_MB_2U(SCH_1):PAGE37',
 PHYS_PAGE='37',
 XY='(625,1600)',
 ROT='0',
 VER='1',
 PACK_TYPE='C0402',
 CDS_LIB='pure_quanta',
 CDS_PART_NAME='Q_CAP_C0402-10UF,6.3V,20%,X6S,A',
 TOLERANCE='20%',
 MATERIAL='X6S',
 VOLTAGE='6.3V',
 VALUE='10UF',
 PRIM_FILE='./archive_libs/logical/q_cap/chips/chips.prt';

PART_NAME
 C2 'Q_CAP_C0402-2.2UF,6.3V,20%,X6SA':;

SECTION_NUMBER 1
 '@S9S_MB_2U_LIB.S9S_MB_2U(SCH_1):PAGE82_I192@PURE_QUANTA.Q_CAP(CHIPS)':
 C_PATH='@s9s_mb_2u_lib.s9s_mb_2u(sch_1):page82_i192@pure_quanta.q_cap(chips)',
 P_PATH='@s9s_mb_2u_lib.s9s_mb_2u(sch_1):page82_i192@pure_quanta.q_cap(chips)',
 PATH='I192',
 DRAWING='@S9S_MB_2U_LIB.S9S_MB_2U(SCH_1):PAGE82',
 PHYS_PAGE='82',
 XY='(1075,425)',
 ROT='0',
 VER='1',
 PACK_TYPE='C0402',
 CDS_LIB='pure_quanta',
 CDS_PART_NAME='Q_CAP_C0402-2.2UF,6.3V,20%,X6SA',
 TOLERANCE='20%',
 MATERIAL='X6S',
 VOLTAGE='6.3V',
 VALUE='2.2UF',
 PRIM_FILE='./archive_libs/logical/q_cap/chips/chips.prt';

PART_NAME
 C3 'Q_CAP_C0805-10UF,16V,10%,X6S,CA':;

SECTION_NUMBER 1
 '@S9S_MB_2U_LIB.S9S_MB_2U(SCH_1):PAGE82_I188@PURE_QUANTA.Q_CAP(CHIPS)':
 C_PATH='@s9s_mb_2u_lib.s9s_mb_2u(sch_1):page82_i188@pure_quanta.q_cap(chips)',
 P_PATH='@s9s_mb_2u_lib.s9s_mb_2u(sch_1):page82_i188@pure_quanta.q_cap(chips)',
 PATH='I188',
 DRAWING='@S9S_MB_2U_LIB.S9S_MB_2U(SCH_1):PAGE82',
 PHYS_PAGE='82',
 XY='(2075,425)',
 ROT='0',
 VER='1',
 PACK_TYPE='C0805',
 CDS_LIB='pure_quanta',
 CDS_PART_NAME='Q_CAP_C0805-10UF,16V,10%,X6S,CA',
 TOLERANCE='10%',
 MATERIAL='X6S',
 VOLTAGE='16V',
 VALUE='10UF',
 PRIM_FILE='./archive_libs/logical/q_cap/chips/chips.prt';

PART_NAME
 C4 'Q_CAP_C0805-10UF,16V,10%,X6S,CA':;

SECTION_NUMBER 1
 '@S9S_MB_2U_LIB.S9S_MB_2U(SCH_1):PAGE82_I190@PURE_QUANTA.Q_CAP(CHIPS)':
 C_PATH='@s9s_mb_2u_lib.s9s_mb_2u(sch_1):page82_i190@pure_quanta.q_cap(chips)',
 P_PATH='@s9s_mb_2u_lib.s9s_mb_2u(sch_1):page82_i190@pure_quanta.q_cap(chips)',
 PATH='I190',
 DRAWING='@S9S_MB_2U_LIB.S9S_MB_2U(SCH_1):PAGE82',
 PHYS_PAGE='82',
 XY='(2700,425)',
 ROT='0',
 VER='1',
 PACK_TYPE='C0805',
 CDS_LIB='pure_quanta',
 CDS_PART_NAME='Q_CAP_C0805-10UF,16V,10%,X6S,CA',
 TOLERANCE='10%',
 MATERIAL='X6S',
 VOLTAGE='16V',
 VALUE='10UF',
 PRIM_FILE='./archive_libs/logical/q_cap/chips/chips.prt';

PART_NAME
 C5 'Q_CAP_C0402-2.2UF,6.3V,20%,X6SA':;

SECTION_NUMBER 1
 '@S9S_MB_2U_LIB.S9S_MB_2U(SCH_1):PAGE83_I120@PURE_QUANTA.Q_CAP(CHIPS)':
 C_PATH='@s9s_mb_2u_lib.s9s_mb_2u(sch_1):page83_i120@pure_quanta.q_cap(chips)',
 P_PATH='@s9s_mb_2u_lib.s9s_mb_2u(sch_1):page83_i120@pure_quanta.q_cap(chips)',
 PATH='I120',
 DRAWING='@S9S_MB_2U_LIB.S9S_MB_2U(SCH_1):PAGE83',
 PHYS_PAGE='83',
 XY='(1725,325)',
 ROT='0',
 VER='1',
 PACK_TYPE='C0402',
 CDS_LIB='pure_quanta',
 CDS_PART_NAME='Q_CAP_C0402-2.2UF,6.3V,20%,X6SA',
 TOLERANCE='20%',
 MATERIAL='X6S',
 VOLTAGE='6.3V',
 VALUE='2.2UF',
 PRIM_FILE='./archive_libs/logical/q_cap/chips/chips.prt';

PART_NAME
 C6 'Q_CAP_C0805-10UF,16V,10%,X6S,CA':;

SECTION_NUMBER 1
 '@S9S_MB_2U_LIB.S9S_MB_2U(SCH_1):PAGE83_I122@PURE_QUANTA.Q_CAP(CHIPS)':
 C_PATH='@s9s_mb_2u_lib.s9s_mb_2u(sch_1):page83_i122@pure_quanta.q_cap(chips)',
 P_PATH='@s9s_mb_2u_lib.s9s_mb_2u(sch_1):page83_i122@pure_quanta.q_cap(chips)',
 PATH='I122',
 DRAWING='@S9S_MB_2U_LIB.S9S_MB_2U(SCH_1):PAGE83',
 PHYS_PAGE='83',
 XY='(2725,325)',
 ROT='0',
 VER='1',
 PACK_TYPE='C0805',
 CDS_LIB='pure_quanta',
 CDS_PART_NAME='Q_CAP_C0805-10UF,16V,10%,X6S,CA',
 TOLERANCE='10%',
 MATERIAL='X6S',
 VOLTAGE='16V',
 VALUE='10UF',
 PRIM_FILE='./archive_libs/logical/q_cap/chips/chips.prt';

PART_NAME
 C7 'Q_CAP_C0805-10UF,16V,10%,X6S,CA':;

SECTION_NUMBER 1
 '@S9S_MB_2U_LIB.S9S_MB_2U(SCH_1):PAGE83_I144@PURE_QUANTA.Q_CAP(CHIPS)':
 C_PATH='@s9s_mb_2u_lib.s9s_mb_2u(sch_1):page83_i144@pure_quanta.q_cap(chips)',
 P_PATH='@s9s_mb_2u_lib.s9s_mb_2u(sch_1):page83_i144@pure_quanta.q_cap(chips)',
 PATH='I144',
 DRAWING='@S9S_MB_2U_LIB.S9S_MB_2U(SCH_1):PAGE83',
 PHYS_PAGE='83',
 XY='(3350,325)',
 ROT='0',
 VER='1',
 PACK_TYPE='C0805',
 CDS_LIB='pure_quanta',
 CDS_PART_NAME='Q_CAP_C0805-10UF,16V,10%,X6S,CA',
 TOLERANCE='10%',
 MATERIAL='X6S',
 VOLTAGE='16V',
 VALUE='10UF',
 PRIM_FILE='./archive_libs/logical/q_cap/chips/chips.prt';

PART_NAME
 C8 'Q_CAP_C0402-2.2UF,6.3V,20%,X6SA':;

SECTION_NUMBER 1
 '@S9S_MB_2U_LIB.S9S_MB_2U(SCH_1):PAGE84_I121@PURE_QUANTA.Q_CAP(CHIPS)':
 C_PATH='@s9s_mb_2u_lib.s9s_mb_2u(sch_1):page84_i121@pure_quanta.q_cap(chips)',
 P_PATH='@s9s_mb_2u_lib.s9s_mb_2u(sch_1):page84_i121@pure_quanta.q_cap(chips)',
 PATH='I121',
 DRAWING='@S9S_MB_2U_LIB.S9S_MB_2U(SCH_1):PAGE84',
 PHYS_PAGE='84',
 XY='(1625,25)',
 ROT='0',
 VER='1',
 PACK_TYPE='C0402',
 CDS_LIB='pure_quanta',
 CDS_PART_NAME='Q_CAP_C0402-2.2UF,6.3V,20%,X6SA',
 TOLERANCE='20%',
 MATERIAL='X6S',
 VOLTAGE='6.3V',
 VALUE='2.2UF',
 PRIM_FILE='./archive_libs/logical/q_cap/chips/chips.prt';

PART_NAME
 C9 'Q_CAP_C0805-10UF,16V,10%,X6S,CA':;

SECTION_NUMBER 1
 '@S9S_MB_2U_LIB.S9S_MB_2U(SCH_1):PAGE84_I122@PURE_QUANTA.Q_CAP(CHIPS)':
 C_PATH='@s9s_mb_2u_lib.s9s_mb_2u(sch_1):page84_i122@pure_quanta.q_cap(chips)',
 P_PATH='@s9s_mb_2u_lib.s9s_mb_2u(sch_1):page84_i122@pure_quanta.q_cap(chips)',
 PATH='I122',
 DRAWING='@S9S_MB_2U_LIB.S9S_MB_2U(SCH_1):PAGE84',
 PHYS_PAGE='84',
 XY='(2625,25)',
 ROT='0',
 VER='1',
 PACK_TYPE='C0805',
 CDS_LIB='pure_quanta',
 CDS_PART_NAME='Q_CAP_C0805-10UF,16V,10%,X6S,CA',
 TOLERANCE='10%',
 MATERIAL='X6S',
 VOLTAGE='16V',
 VALUE='10UF',
 PRIM_FILE='./archive_libs/logical/q_cap/chips/chips.prt';

PART_NAME
 C10 'Q_CAP_C0805-10UF,16V,10%,X6S,CA':;

SECTION_NUMBER 1
 '@S9S_MB_2U_LIB.S9S_MB_2U(SCH_1):PAGE84_I144@PURE_QUANTA.Q_CAP(CHIPS)':
 C_PATH='@s9s_mb_2u_lib.s9s_mb_2u(sch_1):page84_i144@pure_quanta.q_cap(chips)',
 P_PATH='@s9s_mb_2u_lib.s9s_mb_2u(sch_1):page84_i144@pure_quanta.q_cap(chips)',
 PATH='I144',
 DRAWING='@S9S_MB_2U_LIB.S9S_MB_2U(SCH_1):PAGE84',
 PHYS_PAGE='84',
 XY='(3250,25)',
 ROT='0',
 VER='1',
 PACK_TYPE='C0805',
 CDS_LIB='pure_quanta',
 CDS_PART_NAME='Q_CAP_C0805-10UF,16V,10%,X6S,CA',
 TOLERANCE='10%',
 MATERIAL='X6S',
 VOLTAGE='16V',
 VALUE='10UF',
 PRIM_FILE='./archive_libs/logical/q_cap/chips/chips.prt';

PART_NAME
 C11 'Q_CAP_C0402-2.2UF,6.3V,20%,X6SA':;

SECTION_NUMBER 1
 '@S9S_MB_2U_LIB.S9S_MB_2U(SCH_1):PAGE85_I121@PURE_QUANTA.Q_CAP(CHIPS)':
 C_PATH='@s9s_mb_2u_lib.s9s_mb_2u(sch_1):page85_i121@pure_quanta.q_cap(chips)',
 P_PATH='@s9s_mb_2u_lib.s9s_mb_2u(sch_1):page85_i121@pure_quanta.q_cap(chips)',
 PATH='I121',
 DRAWING='@S9S_MB_2U_LIB.S9S_MB_2U(SCH_1):PAGE85',
 PHYS_PAGE='85',
 XY='(1200,525)',
 ROT='0',
 VER='1',
 PACK_TYPE='C0402',
 CDS_LIB='pure_quanta',
 CDS_PART_NAME='Q_CAP_C0402-2.2UF,6.3V,20%,X6SA',
 TOLERANCE='20%',
 MATERIAL='X6S',
 VOLTAGE='6.3V',
 VALUE='2.2UF',
 PRIM_FILE='./archive_libs/logical/q_cap/chips/chips.prt';

PART_NAME
 C12 'Q_CAP_C0805-10UF,16V,10%,X6S,CA':;

SECTION_NUMBER 1
 '@S9S_MB_2U_LIB.S9S_MB_2U(SCH_1):PAGE85_I125@PURE_QUANTA.Q_CAP(CHIPS)':
 C_PATH='@s9s_mb_2u_lib.s9s_mb_2u(sch_1):page85_i125@pure_quanta.q_cap(chips)',
 P_PATH='@s9s_mb_2u_lib.s9s_mb_2u(sch_1):page85_i125@pure_quanta.q_cap(chips)',
 PATH='I125',
 DRAWING='@S9S_MB_2U_LIB.S9S_MB_2U(SCH_1):PAGE85',
 PHYS_PAGE='85',
 XY='(2200,525)',
 ROT='0',
 VER='1',
 PACK_TYPE='C0805',
 CDS_LIB='pure_quanta',
 CDS_PART_NAME='Q_CAP_C0805-10UF,16V,10%,X6S,CA',
 TOLERANCE='10%',
 MATERIAL='X6S',
 VOLTAGE='16V',
 VALUE='10UF',
 PRIM_FILE='./archive_libs/logical/q_cap/chips/chips.prt';

PART_NAME
 C13 'Q_CAP_C0805-10UF,16V,10%,X6S,CA':;

SECTION_NUMBER 1
 '@S9S_MB_2U_LIB.S9S_MB_2U(SCH_1):PAGE85_I127@PURE_QUANTA.Q_CAP(CHIPS)':
 C_PATH='@s9s_mb_2u_lib.s9s_mb_2u(sch_1):page85_i127@pure_quanta.q_cap(chips)',
 P_PATH='@s9s_mb_2u_lib.s9s_mb_2u(sch_1):page85_i127@pure_quanta.q_cap(chips)',
 PATH='I127',
 DRAWING='@S9S_MB_2U_LIB.S9S_MB_2U(SCH_1):PAGE85',
 PHYS_PAGE='85',
 XY='(2825,525)',
 ROT='0',
 VER='1',
 PACK_TYPE='C0805',
 CDS_LIB='pure_quanta',
 CDS_PART_NAME='Q_CAP_C0805-10UF,16V,10%,X6S,CA',
 TOLERANCE='10%',
 MATERIAL='X6S',
 VOLTAGE='16V',
 VALUE='10UF',
 PRIM_FILE='./archive_libs/logical/q_cap/chips/chips.prt';

PART_NAME
 C14 'Q_CAP_C0402-2.2UF,6.3V,20%,X6SA':;

SECTION_NUMBER 1
 '@S9S_MB_2U_LIB.S9S_MB_2U(SCH_1):PAGE86_I120@PURE_QUANTA.Q_CAP(CHIPS)':
 C_PATH='@s9s_mb_2u_lib.s9s_mb_2u(sch_1):page86_i120@pure_quanta.q_cap(chips)',
 P_PATH='@s9s_mb_2u_lib.s9s_mb_2u(sch_1):page86_i120@pure_quanta.q_cap(chips)',
 PATH='I120',
 DRAWING='@S9S_MB_2U_LIB.S9S_MB_2U(SCH_1):PAGE86',
 PHYS_PAGE='86',
 XY='(500,275)',
 ROT='0',
 VER='1',
 PACK_TYPE='C0402',
 CDS_LIB='pure_quanta',
 CDS_PART_NAME='Q_CAP_C0402-2.2UF,6.3V,20%,X6SA',
 TOLERANCE='20%',
 MATERIAL='X6S',
 VOLTAGE='6.3V',
 VALUE='2.2UF',
 PRIM_FILE='./archive_libs/logical/q_cap/chips/chips.prt';

PART_NAME
 C15 'Q_CAP_C0805-10UF,16V,10%,X6S,CA':;

SECTION_NUMBER 1
 '@S9S_MB_2U_LIB.S9S_MB_2U(SCH_1):PAGE86_I121@PURE_QUANTA.Q_CAP(CHIPS)':
 C_PATH='@s9s_mb_2u_lib.s9s_mb_2u(sch_1):page86_i121@pure_quanta.q_cap(chips)',
 P_PATH='@s9s_mb_2u_lib.s9s_mb_2u(sch_1):page86_i121@pure_quanta.q_cap(chips)',
 PATH='I121',
 DRAWING='@S9S_MB_2U_LIB.S9S_MB_2U(SCH_1):PAGE86',
 PHYS_PAGE='86',
 XY='(1500,275)',
 ROT='0',
 VER='1',
 PACK_TYPE='C0805',
 CDS_LIB='pure_quanta',
 CDS_PART_NAME='Q_CAP_C0805-10UF,16V,10%,X6S,CA',
 TOLERANCE='10%',
 MATERIAL='X6S',
 VOLTAGE='16V',
 VALUE='10UF',
 PRIM_FILE='./archive_libs/logical/q_cap/chips/chips.prt';

PART_NAME
 C16 'Q_CAP_C0805-10UF,16V,10%,X6S,CA':;

SECTION_NUMBER 1
 '@S9S_MB_2U_LIB.S9S_MB_2U(SCH_1):PAGE86_I123@PURE_QUANTA.Q_CAP(CHIPS)':
 C_PATH='@s9s_mb_2u_lib.s9s_mb_2u(sch_1):page86_i123@pure_quanta.q_cap(chips)',
 P_PATH='@s9s_mb_2u_lib.s9s_mb_2u(sch_1):page86_i123@pure_quanta.q_cap(chips)',
 PATH='I123',
 DRAWING='@S9S_MB_2U_LIB.S9S_MB_2U(SCH_1):PAGE86',
 PHYS_PAGE='86',
 XY='(2125,275)',
 ROT='0',
 VER='1',
 PACK_TYPE='C0805',
 CDS_LIB='pure_quanta',
 CDS_PART_NAME='Q_CAP_C0805-10UF,16V,10%,X6S,CA',
 TOLERANCE='10%',
 MATERIAL='X6S',
 VOLTAGE='16V',
 VALUE='10UF',
 PRIM_FILE='./archive_libs/logical/q_cap/chips/chips.prt';

PART_NAME
 C17 'Q_CAP_C0402-2.2UF,6.3V,20%,X6SA':;

SECTION_NUMBER 1
 '@S9S_MB_2U_LIB.S9S_MB_2U(SCH_1):PAGE87_I120@PURE_QUANTA.Q_CAP(CHIPS)':
 C_PATH='@s9s_mb_2u_lib.s9s_mb_2u(sch_1):page87_i120@pure_quanta.q_cap(chips)',
 P_PATH='@s9s_mb_2u_lib.s9s_mb_2u(sch_1):page87_i120@pure_quanta.q_cap(chips)',
 PATH='I120',
 DRAWING='@S9S_MB_2U_LIB.S9S_MB_2U(SCH_1):PAGE87',
 PHYS_PAGE='87',
 XY='(1275,325)',
 ROT='0',
 VER='1',
 PACK_TYPE='C0402',
 CDS_LIB='pure_quanta',
 CDS_PART_NAME='Q_CAP_C0402-2.2UF,6.3V,20%,X6SA',
 TOLERANCE='20%',
 MATERIAL='X6S',
 VOLTAGE='6.3V',
 VALUE='2.2UF',
 PRIM_FILE='./archive_libs/logical/q_cap/chips/chips.prt';

PART_NAME
 C18 'Q_CAP_C0805-10UF,16V,10%,X6S,CA':;

SECTION_NUMBER 1
 '@S9S_MB_2U_LIB.S9S_MB_2U(SCH_1):PAGE87_I124@PURE_QUANTA.Q_CAP(CHIPS)':
 C_PATH='@s9s_mb_2u_lib.s9s_mb_2u(sch_1):page87_i124@pure_quanta.q_cap(chips)',
 P_PATH='@s9s_mb_2u_lib.s9s_mb_2u(sch_1):page87_i124@pure_quanta.q_cap(chips)',
 PATH='I124',
 DRAWING='@S9S_MB_2U_LIB.S9S_MB_2U(SCH_1):PAGE87',
 PHYS_PAGE='87',
 XY='(2275,325)',
 ROT='0',
 VER='1',
 PACK_TYPE='C0805',
 CDS_LIB='pure_quanta',
 CDS_PART_NAME='Q_CAP_C0805-10UF,16V,10%,X6S,CA',
 TOLERANCE='10%',
 MATERIAL='X6S',
 VOLTAGE='16V',
 VALUE='10UF',
 PRIM_FILE='./archive_libs/logical/q_cap/chips/chips.prt';

PART_NAME
 C19 'Q_CAP_C0805-10UF,16V,10%,X6S,CA':;

SECTION_NUMBER 1
 '@S9S_MB_2U_LIB.S9S_MB_2U(SCH_1):PAGE87_I127@PURE_QUANTA.Q_CAP(CHIPS)':
 C_PATH='@s9s_mb_2u_lib.s9s_mb_2u(sch_1):page87_i127@pure_quanta.q_cap(chips)',
 P_PATH='@s9s_mb_2u_lib.s9s_mb_2u(sch_1):page87_i127@pure_quanta.q_cap(chips)',
 PATH='I127',
 DRAWING='@S9S_MB_2U_LIB.S9S_MB_2U(SCH_1):PAGE87',
 PHYS_PAGE='87',
 XY='(2900,325)',
 ROT='0',
 VER='1',
 PACK_TYPE='C0805',
 CDS_LIB='pure_quanta',
 CDS_PART_NAME='Q_CAP_C0805-10UF,16V,10%,X6S,CA',
 TOLERANCE='10%',
 MATERIAL='X6S',
 VOLTAGE='16V',
 VALUE='10UF',
 PRIM_FILE='./archive_libs/logical/q_cap/chips/chips.prt';

PART_NAME
 C20 'Q_CAP_C0402-2.2UF,6.3V,20%,X6SA':;

SECTION_NUMBER 1
 '@S9S_MB_2U_LIB.S9S_MB_2U(SCH_1):PAGE88_I123@PURE_QUANTA.Q_CAP(CHIPS)':
 C_PATH='@s9s_mb_2u_lib.s9s_mb_2u(sch_1):page88_i123@pure_quanta.q_cap(chips)',
 P_PATH='@s9s_mb_2u_lib.s9s_mb_2u(sch_1):page88_i123@pure_quanta.q_cap(chips)',
 PATH='I123',
 DRAWING='@S9S_MB_2U_LIB.S9S_MB_2U(SCH_1):PAGE88',
 PHYS_PAGE='88',
 XY='(1475,175)',
 ROT='0',
 VER='1',
 PACK_TYPE='C0402',
 CDS_LIB='pure_quanta',
 CDS_PART_NAME='Q_CAP_C0402-2.2UF,6.3V,20%,X6SA',
 TOLERANCE='20%',
 MATERIAL='X6S',
 VOLTAGE='6.3V',
 VALUE='2.2UF',
 PRIM_FILE='./archive_libs/logical/q_cap/chips/chips.prt';

PART_NAME
 C21 'Q_CAP_C0805-10UF,16V,10%,X6S,CA':;

SECTION_NUMBER 1
 '@S9S_MB_2U_LIB.S9S_MB_2U(SCH_1):PAGE88_I126@PURE_QUANTA.Q_CAP(CHIPS)':
 C_PATH='@s9s_mb_2u_lib.s9s_mb_2u(sch_1):page88_i126@pure_quanta.q_cap(chips)',
 P_PATH='@s9s_mb_2u_lib.s9s_mb_2u(sch_1):page88_i126@pure_quanta.q_cap(chips)',
 PATH='I126',
 DRAWING='@S9S_MB_2U_LIB.S9S_MB_2U(SCH_1):PAGE88',
 PHYS_PAGE='88',
 XY='(2475,175)',
 ROT='0',
 VER='1',
 PACK_TYPE='C0805',
 CDS_LIB='pure_quanta',
 CDS_PART_NAME='Q_CAP_C0805-10UF,16V,10%,X6S,CA',
 TOLERANCE='10%',
 MATERIAL='X6S',
 VOLTAGE='16V',
 VALUE='10UF',
 PRIM_FILE='./archive_libs/logical/q_cap/chips/chips.prt';

PART_NAME
 C22 'Q_CAP_C0805-10UF,16V,10%,X6S,CA':;

SECTION_NUMBER 1
 '@S9S_MB_2U_LIB.S9S_MB_2U(SCH_1):PAGE88_I166@PURE_QUANTA.Q_CAP(CHIPS)':
 C_PATH='@s9s_mb_2u_lib.s9s_mb_2u(sch_1):page88_i166@pure_quanta.q_cap(chips)',
 P_PATH='@s9s_mb_2u_lib.s9s_mb_2u(sch_1):page88_i166@pure_quanta.q_cap(chips)',
 PATH='I166',
 DRAWING='@S9S_MB_2U_LIB.S9S_MB_2U(SCH_1):PAGE88',
 PHYS_PAGE='88',
 XY='(3100,175)',
 ROT='0',
 VER='1',
 PACK_TYPE='C0805',
 CDS_LIB='pure_quanta',
 CDS_PART_NAME='Q_CAP_C0805-10UF,16V,10%,X6S,CA',
 TOLERANCE='10%',
 MATERIAL='X6S',
 VOLTAGE='16V',
 VALUE='10UF',
 PRIM_FILE='./archive_libs/logical/q_cap/chips/chips.prt';

PART_NAME
 C23 'Q_CAP_C0402-2.2UF,6.3V,20%,X6SA':;

SECTION_NUMBER 1
 '@S9S_MB_2U_LIB.S9S_MB_2U(SCH_1):PAGE89_I121@PURE_QUANTA.Q_CAP(CHIPS)':
 C_PATH='@s9s_mb_2u_lib.s9s_mb_2u(sch_1):page89_i121@pure_quanta.q_cap(chips)',
 P_PATH='@s9s_mb_2u_lib.s9s_mb_2u(sch_1):page89_i121@pure_quanta.q_cap(chips)',
 PATH='I121',
 DRAWING='@S9S_MB_2U_LIB.S9S_MB_2U(SCH_1):PAGE89',
 PHYS_PAGE='89',
 XY='(1025,325)',
 ROT='0',
 VER='1',
 PACK_TYPE='C0402',
 CDS_LIB='pure_quanta',
 CDS_PART_NAME='Q_CAP_C0402-2.2UF,6.3V,20%,X6SA',
 TOLERANCE='20%',
 MATERIAL='X6S',
 VOLTAGE='6.3V',
 VALUE='2.2UF',
 PRIM_FILE='./archive_libs/logical/q_cap/chips/chips.prt';

PART_NAME
 C24 'Q_CAP_C0805-10UF,16V,10%,X6S,CA':;

SECTION_NUMBER 1
 '@S9S_MB_2U_LIB.S9S_MB_2U(SCH_1):PAGE89_I125@PURE_QUANTA.Q_CAP(CHIPS)':
 C_PATH='@s9s_mb_2u_lib.s9s_mb_2u(sch_1):page89_i125@pure_quanta.q_cap(chips)',
 P_PATH='@s9s_mb_2u_lib.s9s_mb_2u(sch_1):page89_i125@pure_quanta.q_cap(chips)',
 PATH='I125',
 DRAWING='@S9S_MB_2U_LIB.S9S_MB_2U(SCH_1):PAGE89',
 PHYS_PAGE='89',
 XY='(2025,325)',
 ROT='0',
 VER='1',
 PACK_TYPE='C0805',
 CDS_LIB='pure_quanta',
 CDS_PART_NAME='Q_CAP_C0805-10UF,16V,10%,X6S,CA',
 TOLERANCE='10%',
 MATERIAL='X6S',
 VOLTAGE='16V',
 VALUE='10UF',
 PRIM_FILE='./archive_libs/logical/q_cap/chips/chips.prt';

PART_NAME
 C25 'Q_CAP_C0805-10UF,16V,10%,X6S,CA':;

SECTION_NUMBER 1
 '@S9S_MB_2U_LIB.S9S_MB_2U(SCH_1):PAGE89_I127@PURE_QUANTA.Q_CAP(CHIPS)':
 C_PATH='@s9s_mb_2u_lib.s9s_mb_2u(sch_1):page89_i127@pure_quanta.q_cap(chips)',
 P_PATH='@s9s_mb_2u_lib.s9s_mb_2u(sch_1):page89_i127@pure_quanta.q_cap(chips)',
 PATH='I127',
 DRAWING='@S9S_MB_2U_LIB.S9S_MB_2U(SCH_1):PAGE89',
 PHYS_PAGE='89',
 XY='(2650,325)',
 ROT='0',
 VER='1',
 PACK_TYPE='C0805',
 CDS_LIB='pure_quanta',
 CDS_PART_NAME='Q_CAP_C0805-10UF,16V,10%,X6S,CA',
 TOLERANCE='10%',
 MATERIAL='X6S',
 VOLTAGE='16V',
 VALUE='10UF',
 PRIM_FILE='./archive_libs/logical/q_cap/chips/chips.prt';

PART_NAME
 C26 'Q_CAP_C0402-2.2UF,6.3V,20%,X6SA':;

SECTION_NUMBER 1
 '@S9S_MB_2U_LIB.S9S_MB_2U(SCH_1):PAGE90_I122@PURE_QUANTA.Q_CAP(CHIPS)':
 C_PATH='@s9s_mb_2u_lib.s9s_mb_2u(sch_1):page90_i122@pure_quanta.q_cap(chips)',
 P_PATH='@s9s_mb_2u_lib.s9s_mb_2u(sch_1):page90_i122@pure_quanta.q_cap(chips)',
 PATH='I122',
 DRAWING='@S9S_MB_2U_LIB.S9S_MB_2U(SCH_1):PAGE90',
 PHYS_PAGE='90',
 XY='(1725,150)',
 ROT='0',
 VER='1',
 PACK_TYPE='C0402',
 CDS_LIB='pure_quanta',
 CDS_PART_NAME='Q_CAP_C0402-2.2UF,6.3V,20%,X6SA',
 TOLERANCE='20%',
 MATERIAL='X6S',
 VOLTAGE='6.3V',
 VALUE='2.2UF',
 PRIM_FILE='./archive_libs/logical/q_cap/chips/chips.prt';

PART_NAME
 C27 'Q_CAP_C0805-10UF,16V,10%,X6S,CA':;

SECTION_NUMBER 1
 '@S9S_MB_2U_LIB.S9S_MB_2U(SCH_1):PAGE90_I123@PURE_QUANTA.Q_CAP(CHIPS)':
 C_PATH='@s9s_mb_2u_lib.s9s_mb_2u(sch_1):page90_i123@pure_quanta.q_cap(chips)',
 P_PATH='@s9s_mb_2u_lib.s9s_mb_2u(sch_1):page90_i123@pure_quanta.q_cap(chips)',
 PATH='I123',
 DRAWING='@S9S_MB_2U_LIB.S9S_MB_2U(SCH_1):PAGE90',
 PHYS_PAGE='90',
 XY='(2725,150)',
 ROT='0',
 VER='1',
 PACK_TYPE='C0805',
 CDS_LIB='pure_quanta',
 CDS_PART_NAME='Q_CAP_C0805-10UF,16V,10%,X6S,CA',
 TOLERANCE='10%',
 MATERIAL='X6S',
 VOLTAGE='16V',
 VALUE='10UF',
 PRIM_FILE='./archive_libs/logical/q_cap/chips/chips.prt';

PART_NAME
 C28 'Q_CAP_C0805-10UF,16V,10%,X6S,CA':;

SECTION_NUMBER 1
 '@S9S_MB_2U_LIB.S9S_MB_2U(SCH_1):PAGE90_I145@PURE_QUANTA.Q_CAP(CHIPS)':
 C_PATH='@s9s_mb_2u_lib.s9s_mb_2u(sch_1):page90_i145@pure_quanta.q_cap(chips)',
 P_PATH='@s9s_mb_2u_lib.s9s_mb_2u(sch_1):page90_i145@pure_quanta.q_cap(chips)',
 PATH='I145',
 DRAWING='@S9S_MB_2U_LIB.S9S_MB_2U(SCH_1):PAGE90',
 PHYS_PAGE='90',
 XY='(3350,150)',
 ROT='0',
 VER='1',
 PACK_TYPE='C0805',
 CDS_LIB='pure_quanta',
 CDS_PART_NAME='Q_CAP_C0805-10UF,16V,10%,X6S,CA',
 TOLERANCE='10%',
 MATERIAL='X6S',
 VOLTAGE='16V',
 VALUE='10UF',
 PRIM_FILE='./archive_libs/logical/q_cap/chips/chips.prt';

PART_NAME
 C29 'Q_CAP_C0402-2.2UF,6.3V,20%,X6SA':;

SECTION_NUMBER 1
 '@S9S_MB_2U_LIB.S9S_MB_2U(SCH_1):PAGE91_I123@PURE_QUANTA.Q_CAP(CHIPS)':
 C_PATH='@s9s_mb_2u_lib.s9s_mb_2u(sch_1):page91_i123@pure_quanta.q_cap(chips)',
 P_PATH='@s9s_mb_2u_lib.s9s_mb_2u(sch_1):page91_i123@pure_quanta.q_cap(chips)',
 PATH='I123',
 DRAWING='@S9S_MB_2U_LIB.S9S_MB_2U(SCH_1):PAGE91',
 PHYS_PAGE='91',
 XY='(1500,250)',
 ROT='0',
 VER='1',
 PACK_TYPE='C0402',
 CDS_LIB='pure_quanta',
 CDS_PART_NAME='Q_CAP_C0402-2.2UF,6.3V,20%,X6SA',
 TOLERANCE='20%',
 MATERIAL='X6S',
 VOLTAGE='6.3V',
 VALUE='2.2UF',
 PRIM_FILE='./archive_libs/logical/q_cap/chips/chips.prt';

PART_NAME
 C30 'Q_CAP_C0805-10UF,16V,10%,X6S,CA':;

SECTION_NUMBER 1
 '@S9S_MB_2U_LIB.S9S_MB_2U(SCH_1):PAGE91_I124@PURE_QUANTA.Q_CAP(CHIPS)':
 C_PATH='@s9s_mb_2u_lib.s9s_mb_2u(sch_1):page91_i124@pure_quanta.q_cap(chips)',
 P_PATH='@s9s_mb_2u_lib.s9s_mb_2u(sch_1):page91_i124@pure_quanta.q_cap(chips)',
 PATH='I124',
 DRAWING='@S9S_MB_2U_LIB.S9S_MB_2U(SCH_1):PAGE91',
 PHYS_PAGE='91',
 XY='(2500,250)',
 ROT='0',
 VER='1',
 PACK_TYPE='C0805',
 CDS_LIB='pure_quanta',
 CDS_PART_NAME='Q_CAP_C0805-10UF,16V,10%,X6S,CA',
 TOLERANCE='10%',
 MATERIAL='X6S',
 VOLTAGE='16V',
 VALUE='10UF',
 PRIM_FILE='./archive_libs/logical/q_cap/chips/chips.prt';

PART_NAME
 C31 'Q_CAP_C0805-10UF,16V,10%,X6S,CA':;

SECTION_NUMBER 1
 '@S9S_MB_2U_LIB.S9S_MB_2U(SCH_1):PAGE91_I146@PURE_QUANTA.Q_CAP(CHIPS)':
 C_PATH='@s9s_mb_2u_lib.s9s_mb_2u(sch_1):page91_i146@pure_quanta.q_cap(chips)',
 P_PATH='@s9s_mb_2u_lib.s9s_mb_2u(sch_1):page91_i146@pure_quanta.q_cap(chips)',
 PATH='I146',
 DRAWING='@S9S_MB_2U_LIB.S9S_MB_2U(SCH_1):PAGE91',
 PHYS_PAGE='91',
 XY='(3125,250)',
 ROT='0',
 VER='1',
 PACK_TYPE='C0805',
 CDS_LIB='pure_quanta',
 CDS_PART_NAME='Q_CAP_C0805-10UF,16V,10%,X6S,CA',
 TOLERANCE='10%',
 MATERIAL='X6S',
 VOLTAGE='16V',
 VALUE='10UF',
 PRIM_FILE='./archive_libs/logical/q_cap/chips/chips.prt';

PART_NAME
 C32 'Q_CAP_C0402-2.2UF,6.3V,20%,X6SA':;

SECTION_NUMBER 1
 '@S9S_MB_2U_LIB.S9S_MB_2U(SCH_1):PAGE92_I122@PURE_QUANTA.Q_CAP(CHIPS)':
 C_PATH='@s9s_mb_2u_lib.s9s_mb_2u(sch_1):page92_i122@pure_quanta.q_cap(chips)',
 P_PATH='@s9s_mb_2u_lib.s9s_mb_2u(sch_1):page92_i122@pure_quanta.q_cap(chips)',
 PATH='I122',
 DRAWING='@S9S_MB_2U_LIB.S9S_MB_2U(SCH_1):PAGE92',
 PHYS_PAGE='92',
 XY='(625,525)',
 ROT='0',
 VER='1',
 PACK_TYPE='C0402',
 CDS_LIB='pure_quanta',
 CDS_PART_NAME='Q_CAP_C0402-2.2UF,6.3V,20%,X6SA',
 TOLERANCE='20%',
 MATERIAL='X6S',
 VOLTAGE='6.3V',
 VALUE='2.2UF',
 PRIM_FILE='./archive_libs/logical/q_cap/chips/chips.prt';

PART_NAME
 C33 'Q_CAP_C0805-10UF,16V,10%,X6S,CA':;

SECTION_NUMBER 1
 '@S9S_MB_2U_LIB.S9S_MB_2U(SCH_1):PAGE92_I127@PURE_QUANTA.Q_CAP(CHIPS)':
 C_PATH='@s9s_mb_2u_lib.s9s_mb_2u(sch_1):page92_i127@pure_quanta.q_cap(chips)',
 P_PATH='@s9s_mb_2u_lib.s9s_mb_2u(sch_1):page92_i127@pure_quanta.q_cap(chips)',
 PATH='I127',
 DRAWING='@S9S_MB_2U_LIB.S9S_MB_2U(SCH_1):PAGE92',
 PHYS_PAGE='92',
 XY='(1625,525)',
 ROT='0',
 VER='1',
 PACK_TYPE='C0805',
 CDS_LIB='pure_quanta',
 CDS_PART_NAME='Q_CAP_C0805-10UF,16V,10%,X6S,CA',
 TOLERANCE='10%',
 MATERIAL='X6S',
 VOLTAGE='16V',
 VALUE='10UF',
 PRIM_FILE='./archive_libs/logical/q_cap/chips/chips.prt';

PART_NAME
 C34 'Q_CAP_C0805-10UF,16V,10%,X6S,CA':;

SECTION_NUMBER 1
 '@S9S_MB_2U_LIB.S9S_MB_2U(SCH_1):PAGE92_I130@PURE_QUANTA.Q_CAP(CHIPS)':
 C_PATH='@s9s_mb_2u_lib.s9s_mb_2u(sch_1):page92_i130@pure_quanta.q_cap(chips)',
 P_PATH='@s9s_mb_2u_lib.s9s_mb_2u(sch_1):page92_i130@pure_quanta.q_cap(chips)',
 PATH='I130',
 DRAWING='@S9S_MB_2U_LIB.S9S_MB_2U(SCH_1):PAGE92',
 PHYS_PAGE='92',
 XY='(2250,525)',
 ROT='0',
 VER='1',
 PACK_TYPE='C0805',
 CDS_LIB='pure_quanta',
 CDS_PART_NAME='Q_CAP_C0805-10UF,16V,10%,X6S,CA',
 TOLERANCE='10%',
 MATERIAL='X6S',
 VOLTAGE='16V',
 VALUE='10UF',
 PRIM_FILE='./archive_libs/logical/q_cap/chips/chips.prt';

PART_NAME
 C35 'Q_CAP_C0402-2.2UF,6.3V,20%,X6SA':;

SECTION_NUMBER 1
 '@S9S_MB_2U_LIB.S9S_MB_2U(SCH_1):PAGE93_I122@PURE_QUANTA.Q_CAP(CHIPS)':
 C_PATH='@s9s_mb_2u_lib.s9s_mb_2u(sch_1):page93_i122@pure_quanta.q_cap(chips)',
 P_PATH='@s9s_mb_2u_lib.s9s_mb_2u(sch_1):page93_i122@pure_quanta.q_cap(chips)',
 PATH='I122',
 DRAWING='@S9S_MB_2U_LIB.S9S_MB_2U(SCH_1):PAGE93',
 PHYS_PAGE='93',
 XY='(1300,550)',
 ROT='0',
 VER='1',
 PACK_TYPE='C0402',
 CDS_LIB='pure_quanta',
 CDS_PART_NAME='Q_CAP_C0402-2.2UF,6.3V,20%,X6SA',
 TOLERANCE='20%',
 MATERIAL='X6S',
 VOLTAGE='6.3V',
 VALUE='2.2UF',
 PRIM_FILE='./archive_libs/logical/q_cap/chips/chips.prt';

PART_NAME
 C36 'Q_CAP_C0805-10UF,16V,10%,X6S,CA':;

SECTION_NUMBER 1
 '@S9S_MB_2U_LIB.S9S_MB_2U(SCH_1):PAGE93_I126@PURE_QUANTA.Q_CAP(CHIPS)':
 C_PATH='@s9s_mb_2u_lib.s9s_mb_2u(sch_1):page93_i126@pure_quanta.q_cap(chips)',
 P_PATH='@s9s_mb_2u_lib.s9s_mb_2u(sch_1):page93_i126@pure_quanta.q_cap(chips)',
 PATH='I126',
 DRAWING='@S9S_MB_2U_LIB.S9S_MB_2U(SCH_1):PAGE93',
 PHYS_PAGE='93',
 XY='(2300,550)',
 ROT='0',
 VER='1',
 PACK_TYPE='C0805',
 CDS_LIB='pure_quanta',
 CDS_PART_NAME='Q_CAP_C0805-10UF,16V,10%,X6S,CA',
 TOLERANCE='10%',
 MATERIAL='X6S',
 VOLTAGE='16V',
 VALUE='10UF',
 PRIM_FILE='./archive_libs/logical/q_cap/chips/chips.prt';

PART_NAME
 C37 'Q_CAP_C0805-10UF,16V,10%,X6S,CA':;

SECTION_NUMBER 1
 '@S9S_MB_2U_LIB.S9S_MB_2U(SCH_1):PAGE93_I128@PURE_QUANTA.Q_CAP(CHIPS)':
 C_PATH='@s9s_mb_2u_lib.s9s_mb_2u(sch_1):page93_i128@pure_quanta.q_cap(chips)',
 P_PATH='@s9s_mb_2u_lib.s9s_mb_2u(sch_1):page93_i128@pure_quanta.q_cap(chips)',
 PATH='I128',
 DRAWING='@S9S_MB_2U_LIB.S9S_MB_2U(SCH_1):PAGE93',
 PHYS_PAGE='93',
 XY='(2925,550)',
 ROT='0',
 VER='1',
 PACK_TYPE='C0805',
 CDS_LIB='pure_quanta',
 CDS_PART_NAME='Q_CAP_C0805-10UF,16V,10%,X6S,CA',
 TOLERANCE='10%',
 MATERIAL='X6S',
 VOLTAGE='16V',
 VALUE='10UF',
 PRIM_FILE='./archive_libs/logical/q_cap/chips/chips.prt';

PART_NAME
 C38 'Q_CAP_C0402-2.2UF,6.3V,20%,X6SA':;

SECTION_NUMBER 1
 '@S9S_MB_2U_LIB.S9S_MB_2U(SCH_1):PAGE94_I123@PURE_QUANTA.Q_CAP(CHIPS)':
 C_PATH='@s9s_mb_2u_lib.s9s_mb_2u(sch_1):page94_i123@pure_quanta.q_cap(chips)',
 P_PATH='@s9s_mb_2u_lib.s9s_mb_2u(sch_1):page94_i123@pure_quanta.q_cap(chips)',
 PATH='I123',
 DRAWING='@S9S_MB_2U_LIB.S9S_MB_2U(SCH_1):PAGE94',
 PHYS_PAGE='94',
 XY='(1200,475)',
 ROT='0',
 VER='1',
 PACK_TYPE='C0402',
 CDS_LIB='pure_quanta',
 CDS_PART_NAME='Q_CAP_C0402-2.2UF,6.3V,20%,X6SA',
 TOLERANCE='20%',
 MATERIAL='X6S',
 VOLTAGE='6.3V',
 VALUE='2.2UF',
 PRIM_FILE='./archive_libs/logical/q_cap/chips/chips.prt';

PART_NAME
 C39 'Q_CAP_C0805-10UF,16V,10%,X6S,CA':;

SECTION_NUMBER 1
 '@S9S_MB_2U_LIB.S9S_MB_2U(SCH_1):PAGE94_I125@PURE_QUANTA.Q_CAP(CHIPS)':
 C_PATH='@s9s_mb_2u_lib.s9s_mb_2u(sch_1):page94_i125@pure_quanta.q_cap(chips)',
 P_PATH='@s9s_mb_2u_lib.s9s_mb_2u(sch_1):page94_i125@pure_quanta.q_cap(chips)',
 PATH='I125',
 DRAWING='@S9S_MB_2U_LIB.S9S_MB_2U(SCH_1):PAGE94',
 PHYS_PAGE='94',
 XY='(2200,475)',
 ROT='0',
 VER='1',
 PACK_TYPE='C0805',
 CDS_LIB='pure_quanta',
 CDS_PART_NAME='Q_CAP_C0805-10UF,16V,10%,X6S,CA',
 TOLERANCE='10%',
 MATERIAL='X6S',
 VOLTAGE='16V',
 VALUE='10UF',
 PRIM_FILE='./archive_libs/logical/q_cap/chips/chips.prt';

PART_NAME
 C40 'Q_CAP_C0805-10UF,16V,10%,X6S,CA':;

SECTION_NUMBER 1
 '@S9S_MB_2U_LIB.S9S_MB_2U(SCH_1):PAGE94_I162@PURE_QUANTA.Q_CAP(CHIPS)':
 C_PATH='@s9s_mb_2u_lib.s9s_mb_2u(sch_1):page94_i162@pure_quanta.q_cap(chips)',
 P_PATH='@s9s_mb_2u_lib.s9s_mb_2u(sch_1):page94_i162@pure_quanta.q_cap(chips)',
 PATH='I162',
 DRAWING='@S9S_MB_2U_LIB.S9S_MB_2U(SCH_1):PAGE94',
 PHYS_PAGE='94',
 XY='(2825,475)',
 ROT='0',
 VER='1',
 PACK_TYPE='C0805',
 CDS_LIB='pure_quanta',
 CDS_PART_NAME='Q_CAP_C0805-10UF,16V,10%,X6S,CA',
 TOLERANCE='10%',
 MATERIAL='X6S',
 VOLTAGE='16V',
 VALUE='10UF',
 PRIM_FILE='./archive_libs/logical/q_cap/chips/chips.prt';

PART_NAME
 C41 'Q_CAP_C0402-2.2UF,6.3V,20%,X6SA':;

SECTION_NUMBER 1
 '@S9S_MB_2U_LIB.S9S_MB_2U(SCH_1):PAGE95_I121@PURE_QUANTA.Q_CAP(CHIPS)':
 C_PATH='@s9s_mb_2u_lib.s9s_mb_2u(sch_1):page95_i121@pure_quanta.q_cap(chips)',
 P_PATH='@s9s_mb_2u_lib.s9s_mb_2u(sch_1):page95_i121@pure_quanta.q_cap(chips)',
 PATH='I121',
 DRAWING='@S9S_MB_2U_LIB.S9S_MB_2U(SCH_1):PAGE95',
 PHYS_PAGE='95',
 XY='(2325,-550)',
 ROT='0',
 VER='1',
 PACK_TYPE='C0402',
 CDS_LIB='pure_quanta',
 CDS_PART_NAME='Q_CAP_C0402-2.2UF,6.3V,20%,X6SA',
 TOLERANCE='20%',
 MATERIAL='X6S',
 VOLTAGE='6.3V',
 VALUE='2.2UF',
 PRIM_FILE='./archive_libs/logical/q_cap/chips/chips.prt';

PART_NAME
 C42 'Q_CAP_C0805-10UF,16V,10%,X6S,CA':;

SECTION_NUMBER 1
 '@S9S_MB_2U_LIB.S9S_MB_2U(SCH_1):PAGE95_I125@PURE_QUANTA.Q_CAP(CHIPS)':
 C_PATH='@s9s_mb_2u_lib.s9s_mb_2u(sch_1):page95_i125@pure_quanta.q_cap(chips)',
 P_PATH='@s9s_mb_2u_lib.s9s_mb_2u(sch_1):page95_i125@pure_quanta.q_cap(chips)',
 PATH='I125',
 DRAWING='@S9S_MB_2U_LIB.S9S_MB_2U(SCH_1):PAGE95',
 PHYS_PAGE='95',
 XY='(3325,-550)',
 ROT='0',
 VER='1',
 PACK_TYPE='C0805',
 CDS_LIB='pure_quanta',
 CDS_PART_NAME='Q_CAP_C0805-10UF,16V,10%,X6S,CA',
 TOLERANCE='10%',
 MATERIAL='X6S',
 VOLTAGE='16V',
 VALUE='10UF',
 PRIM_FILE='./archive_libs/logical/q_cap/chips/chips.prt';

PART_NAME
 C43 'Q_CAP_C0805-10UF,16V,10%,X6S,CA':;

SECTION_NUMBER 1
 '@S9S_MB_2U_LIB.S9S_MB_2U(SCH_1):PAGE95_I128@PURE_QUANTA.Q_CAP(CHIPS)':
 C_PATH='@s9s_mb_2u_lib.s9s_mb_2u(sch_1):page95_i128@pure_quanta.q_cap(chips)',
 P_PATH='@s9s_mb_2u_lib.s9s_mb_2u(sch_1):page95_i128@pure_quanta.q_cap(chips)',
 PATH='I128',
 DRAWING='@S9S_MB_2U_LIB.S9S_MB_2U(SCH_1):PAGE95',
 PHYS_PAGE='95',
 XY='(3950,-550)',
 ROT='0',
 VER='1',
 PACK_TYPE='C0805',
 CDS_LIB='pure_quanta',
 CDS_PART_NAME='Q_CAP_C0805-10UF,16V,10%,X6S,CA',
 TOLERANCE='10%',
 MATERIAL='X6S',
 VOLTAGE='16V',
 VALUE='10UF',
 PRIM_FILE='./archive_libs/logical/q_cap/chips/chips.prt';

PART_NAME
 C44 'Q_CAP_C0402-2.2UF,6.3V,20%,X6SA':;

SECTION_NUMBER 1
 '@S9S_MB_2U_LIB.S9S_MB_2U(SCH_1):PAGE96_I121@PURE_QUANTA.Q_CAP(CHIPS)':
 C_PATH='@s9s_mb_2u_lib.s9s_mb_2u(sch_1):page96_i121@pure_quanta.q_cap(chips)',
 P_PATH='@s9s_mb_2u_lib.s9s_mb_2u(sch_1):page96_i121@pure_quanta.q_cap(chips)',
 PATH='I121',
 DRAWING='@S9S_MB_2U_LIB.S9S_MB_2U(SCH_1):PAGE96',
 PHYS_PAGE='96',
 XY='(875,100)',
 ROT='0',
 VER='1',
 PACK_TYPE='C0402',
 CDS_LIB='pure_quanta',
 CDS_PART_NAME='Q_CAP_C0402-2.2UF,6.3V,20%,X6SA',
 TOLERANCE='20%',
 MATERIAL='X6S',
 VOLTAGE='6.3V',
 VALUE='2.2UF',
 PRIM_FILE='./archive_libs/logical/q_cap/chips/chips.prt';

PART_NAME
 C45 'Q_CAP_C0805-10UF,16V,10%,X6S,CA':;

SECTION_NUMBER 1
 '@S9S_MB_2U_LIB.S9S_MB_2U(SCH_1):PAGE96_I125@PURE_QUANTA.Q_CAP(CHIPS)':
 C_PATH='@s9s_mb_2u_lib.s9s_mb_2u(sch_1):page96_i125@pure_quanta.q_cap(chips)',
 P_PATH='@s9s_mb_2u_lib.s9s_mb_2u(sch_1):page96_i125@pure_quanta.q_cap(chips)',
 PATH='I125',
 DRAWING='@S9S_MB_2U_LIB.S9S_MB_2U(SCH_1):PAGE96',
 PHYS_PAGE='96',
 XY='(1875,100)',
 ROT='0',
 VER='1',
 PACK_TYPE='C0805',
 CDS_LIB='pure_quanta',
 CDS_PART_NAME='Q_CAP_C0805-10UF,16V,10%,X6S,CA',
 TOLERANCE='10%',
 MATERIAL='X6S',
 VOLTAGE='16V',
 VALUE='10UF',
 PRIM_FILE='./archive_libs/logical/q_cap/chips/chips.prt';

PART_NAME
 C46 'Q_CAP_C0805-10UF,16V,10%,X6S,CA':;

SECTION_NUMBER 1
 '@S9S_MB_2U_LIB.S9S_MB_2U(SCH_1):PAGE96_I127@PURE_QUANTA.Q_CAP(CHIPS)':
 C_PATH='@s9s_mb_2u_lib.s9s_mb_2u(sch_1):page96_i127@pure_quanta.q_cap(chips)',
 P_PATH='@s9s_mb_2u_lib.s9s_mb_2u(sch_1):page96_i127@pure_quanta.q_cap(chips)',
 PATH='I127',
 DRAWING='@S9S_MB_2U_LIB.S9S_MB_2U(SCH_1):PAGE96',
 PHYS_PAGE='96',
 XY='(2500,100)',
 ROT='0',
 VER='1',
 PACK_TYPE='C0805',
 CDS_LIB='pure_quanta',
 CDS_PART_NAME='Q_CAP_C0805-10UF,16V,10%,X6S,CA',
 TOLERANCE='10%',
 MATERIAL='X6S',
 VOLTAGE='16V',
 VALUE='10UF',
 PRIM_FILE='./archive_libs/logical/q_cap/chips/chips.prt';

PART_NAME
 C47 'Q_CAP_C0402-2.2UF,6.3V,20%,X6SA':;

SECTION_NUMBER 1
 '@S9S_MB_2U_LIB.S9S_MB_2U(SCH_1):PAGE97_I56@PURE_QUANTA.Q_CAP(CHIPS)':
 C_PATH='@s9s_mb_2u_lib.s9s_mb_2u(sch_1):page97_i56@pure_quanta.q_cap(chips)',
 P_PATH='@s9s_mb_2u_lib.s9s_mb_2u(sch_1):page97_i56@pure_quanta.q_cap(chips)',
 PATH='I56',
 DRAWING='@S9S_MB_2U_LIB.S9S_MB_2U(SCH_1):PAGE97',
 PHYS_PAGE='97',
 XY='(1375,300)',
 ROT='0',
 VER='1',
 PACK_TYPE='C0402',
 CDS_LIB='pure_quanta',
 CDS_PART_NAME='Q_CAP_C0402-2.2UF,6.3V,20%,X6SA',
 TOLERANCE='20%',
 MATERIAL='X6S',
 VOLTAGE='6.3V',
 VALUE='2.2UF',
 PRIM_FILE='./archive_libs/logical/q_cap/chips/chips.prt';

PART_NAME
 C48 'Q_CAP_C0805-10UF,16V,10%,X6S,CA':;

SECTION_NUMBER 1
 '@S9S_MB_2U_LIB.S9S_MB_2U(SCH_1):PAGE97_I59@PURE_QUANTA.Q_CAP(CHIPS)':
 C_PATH='@s9s_mb_2u_lib.s9s_mb_2u(sch_1):page97_i59@pure_quanta.q_cap(chips)',
 P_PATH='@s9s_mb_2u_lib.s9s_mb_2u(sch_1):page97_i59@pure_quanta.q_cap(chips)',
 PATH='I59',
 DRAWING='@S9S_MB_2U_LIB.S9S_MB_2U(SCH_1):PAGE97',
 PHYS_PAGE='97',
 XY='(2375,300)',
 ROT='0',
 VER='1',
 PACK_TYPE='C0805',
 CDS_LIB='pure_quanta',
 CDS_PART_NAME='Q_CAP_C0805-10UF,16V,10%,X6S,CA',
 TOLERANCE='10%',
 MATERIAL='X6S',
 VOLTAGE='16V',
 VALUE='10UF',
 PRIM_FILE='./archive_libs/logical/q_cap/chips/chips.prt';

PART_NAME
 C49 'Q_CAP_C0805-10UF,16V,10%,X6S,CA':;

SECTION_NUMBER 1
 '@S9S_MB_2U_LIB.S9S_MB_2U(SCH_1):PAGE97_I62@PURE_QUANTA.Q_CAP(CHIPS)':
 C_PATH='@s9s_mb_2u_lib.s9s_mb_2u(sch_1):page97_i62@pure_quanta.q_cap(chips)',
 P_PATH='@s9s_mb_2u_lib.s9s_mb_2u(sch_1):page97_i62@pure_quanta.q_cap(chips)',
 PATH='I62',
 DRAWING='@S9S_MB_2U_LIB.S9S_MB_2U(SCH_1):PAGE97',
 PHYS_PAGE='97',
 XY='(3000,300)',
 ROT='0',
 VER='1',
 PACK_TYPE='C0805',
 CDS_LIB='pure_quanta',
 CDS_PART_NAME='Q_CAP_C0805-10UF,16V,10%,X6S,CA',
 TOLERANCE='10%',
 MATERIAL='X6S',
 VOLTAGE='16V',
 VALUE='10UF',
 PRIM_FILE='./archive_libs/logical/q_cap/chips/chips.prt';

PART_NAME
 C50 'Q_CAP_C0402-2.2UF,6.3V,20%,X6SA':;

SECTION_NUMBER 1
 '@S9S_MB_2U_LIB.S9S_MB_2U(SCH_1):PAGE98_I122@PURE_QUANTA.Q_CAP(CHIPS)':
 C_PATH='@s9s_mb_2u_lib.s9s_mb_2u(sch_1):page98_i122@pure_quanta.q_cap(chips)',
 P_PATH='@s9s_mb_2u_lib.s9s_mb_2u(sch_1):page98_i122@pure_quanta.q_cap(chips)',
 PATH='I122',
 DRAWING='@S9S_MB_2U_LIB.S9S_MB_2U(SCH_1):PAGE98',
 PHYS_PAGE='98',
 XY='(1750,200)',
 ROT='0',
 VER='1',
 PACK_TYPE='C0402',
 CDS_LIB='pure_quanta',
 CDS_PART_NAME='Q_CAP_C0402-2.2UF,6.3V,20%,X6SA',
 TOLERANCE='20%',
 MATERIAL='X6S',
 VOLTAGE='6.3V',
 VALUE='2.2UF',
 PRIM_FILE='./archive_libs/logical/q_cap/chips/chips.prt';

PART_NAME
 C51 'Q_CAP_C0805-10UF,16V,10%,X6S,CA':;

SECTION_NUMBER 1
 '@S9S_MB_2U_LIB.S9S_MB_2U(SCH_1):PAGE98_I123@PURE_QUANTA.Q_CAP(CHIPS)':
 C_PATH='@s9s_mb_2u_lib.s9s_mb_2u(sch_1):page98_i123@pure_quanta.q_cap(chips)',
 P_PATH='@s9s_mb_2u_lib.s9s_mb_2u(sch_1):page98_i123@pure_quanta.q_cap(chips)',
 PATH='I123',
 DRAWING='@S9S_MB_2U_LIB.S9S_MB_2U(SCH_1):PAGE98',
 PHYS_PAGE='98',
 XY='(2750,200)',
 ROT='0',
 VER='1',
 PACK_TYPE='C0805',
 CDS_LIB='pure_quanta',
 CDS_PART_NAME='Q_CAP_C0805-10UF,16V,10%,X6S,CA',
 TOLERANCE='10%',
 MATERIAL='X6S',
 VOLTAGE='16V',
 VALUE='10UF',
 PRIM_FILE='./archive_libs/logical/q_cap/chips/chips.prt';

PART_NAME
 C52 'Q_CAP_C0805-10UF,16V,10%,X6S,CA':;

SECTION_NUMBER 1
 '@S9S_MB_2U_LIB.S9S_MB_2U(SCH_1):PAGE98_I145@PURE_QUANTA.Q_CAP(CHIPS)':
 C_PATH='@s9s_mb_2u_lib.s9s_mb_2u(sch_1):page98_i145@pure_quanta.q_cap(chips)',
 P_PATH='@s9s_mb_2u_lib.s9s_mb_2u(sch_1):page98_i145@pure_quanta.q_cap(chips)',
 PATH='I145',
 DRAWING='@S9S_MB_2U_LIB.S9S_MB_2U(SCH_1):PAGE98',
 PHYS_PAGE='98',
 XY='(3375,200)',
 ROT='0',
 VER='1',
 PACK_TYPE='C0805',
 CDS_LIB='pure_quanta',
 CDS_PART_NAME='Q_CAP_C0805-10UF,16V,10%,X6S,CA',
 TOLERANCE='10%',
 MATERIAL='X6S',
 VOLTAGE='16V',
 VALUE='10UF',
 PRIM_FILE='./archive_libs/logical/q_cap/chips/chips.prt';

PART_NAME
 C53 'Q_CAP_C0402-2.2UF,6.3V,20%,X6SA':;

SECTION_NUMBER 1
 '@S9S_MB_2U_LIB.S9S_MB_2U(SCH_1):PAGE99_I122@PURE_QUANTA.Q_CAP(CHIPS)':
 C_PATH='@s9s_mb_2u_lib.s9s_mb_2u(sch_1):page99_i122@pure_quanta.q_cap(chips)',
 P_PATH='@s9s_mb_2u_lib.s9s_mb_2u(sch_1):page99_i122@pure_quanta.q_cap(chips)',
 PATH='I122',
 DRAWING='@S9S_MB_2U_LIB.S9S_MB_2U(SCH_1):PAGE99',
 PHYS_PAGE='99',
 XY='(1500,-75)',
 ROT='0',
 VER='1',
 PACK_TYPE='C0402',
 CDS_LIB='pure_quanta',
 CDS_PART_NAME='Q_CAP_C0402-2.2UF,6.3V,20%,X6SA',
 TOLERANCE='20%',
 MATERIAL='X6S',
 VOLTAGE='6.3V',
 VALUE='2.2UF',
 PRIM_FILE='./archive_libs/logical/q_cap/chips/chips.prt';

PART_NAME
 C54 'Q_CAP_C0805-10UF,16V,10%,X6S,CA':;

SECTION_NUMBER 1
 '@S9S_MB_2U_LIB.S9S_MB_2U(SCH_1):PAGE99_I126@PURE_QUANTA.Q_CAP(CHIPS)':
 C_PATH='@s9s_mb_2u_lib.s9s_mb_2u(sch_1):page99_i126@pure_quanta.q_cap(chips)',
 P_PATH='@s9s_mb_2u_lib.s9s_mb_2u(sch_1):page99_i126@pure_quanta.q_cap(chips)',
 PATH='I126',
 DRAWING='@S9S_MB_2U_LIB.S9S_MB_2U(SCH_1):PAGE99',
 PHYS_PAGE='99',
 XY='(2500,-75)',
 ROT='0',
 VER='1',
 PACK_TYPE='C0805',
 CDS_LIB='pure_quanta',
 CDS_PART_NAME='Q_CAP_C0805-10UF,16V,10%,X6S,CA',
 TOLERANCE='10%',
 MATERIAL='X6S',
 VOLTAGE='16V',
 VALUE='10UF',
 PRIM_FILE='./archive_libs/logical/q_cap/chips/chips.prt';

PART_NAME
 C55 'Q_CAP_C0805-10UF,16V,10%,X6S,CA':;

SECTION_NUMBER 1
 '@S9S_MB_2U_LIB.S9S_MB_2U(SCH_1):PAGE99_I128@PURE_QUANTA.Q_CAP(CHIPS)':
 C_PATH='@s9s_mb_2u_lib.s9s_mb_2u(sch_1):page99_i128@pure_quanta.q_cap(chips)',
 P_PATH='@s9s_mb_2u_lib.s9s_mb_2u(sch_1):page99_i128@pure_quanta.q_cap(chips)',
 PATH='I128',
 DRAWING='@S9S_MB_2U_LIB.S9S_MB_2U(SCH_1):PAGE99',
 PHYS_PAGE='99',
 XY='(3125,-75)',
 ROT='0',
 VER='1',
 PACK_TYPE='C0805',
 CDS_LIB='pure_quanta',
 CDS_PART_NAME='Q_CAP_C0805-10UF,16V,10%,X6S,CA',
 TOLERANCE='10%',
 MATERIAL='X6S',
 VOLTAGE='16V',
 VALUE='10UF',
 PRIM_FILE='./archive_libs/logical/q_cap/chips/chips.prt';

PART_NAME
 C56 'Q_CAP_C0402-2.2UF,6.3V,20%,X6SA':;

SECTION_NUMBER 1
 '@S9S_MB_2U_LIB.S9S_MB_2U(SCH_1):PAGE100_I121@PURE_QUANTA.Q_CAP(CHIPS)':
 C_PATH='@s9s_mb_2u_lib.s9s_mb_2u(sch_1):page100_i121@pure_quanta.q_cap(chips)',
 P_PATH='@s9s_mb_2u_lib.s9s_mb_2u(sch_1):page100_i121@pure_quanta.q_cap(chips)',
 PATH='I121',
 DRAWING='@S9S_MB_2U_LIB.S9S_MB_2U(SCH_1):PAGE100',
 PHYS_PAGE='100',
 XY='(1150,525)',
 ROT='0',
 VER='1',
 PACK_TYPE='C0402',
 CDS_LIB='pure_quanta',
 CDS_PART_NAME='Q_CAP_C0402-2.2UF,6.3V,20%,X6SA',
 TOLERANCE='20%',
 MATERIAL='X6S',
 VOLTAGE='6.3V',
 VALUE='2.2UF',
 PRIM_FILE='./archive_libs/logical/q_cap/chips/chips.prt';

PART_NAME
 C57 'Q_CAP_C0805-10UF,16V,10%,X6S,CA':;

SECTION_NUMBER 1
 '@S9S_MB_2U_LIB.S9S_MB_2U(SCH_1):PAGE100_I122@PURE_QUANTA.Q_CAP(CHIPS)':
 C_PATH='@s9s_mb_2u_lib.s9s_mb_2u(sch_1):page100_i122@pure_quanta.q_cap(chips)',
 P_PATH='@s9s_mb_2u_lib.s9s_mb_2u(sch_1):page100_i122@pure_quanta.q_cap(chips)',
 PATH='I122',
 DRAWING='@S9S_MB_2U_LIB.S9S_MB_2U(SCH_1):PAGE100',
 PHYS_PAGE='100',
 XY='(2150,525)',
 ROT='0',
 VER='1',
 PACK_TYPE='C0805',
 CDS_LIB='pure_quanta',
 CDS_PART_NAME='Q_CAP_C0805-10UF,16V,10%,X6S,CA',
 TOLERANCE='10%',
 MATERIAL='X6S',
 VOLTAGE='16V',
 VALUE='10UF',
 PRIM_FILE='./archive_libs/logical/q_cap/chips/chips.prt';

PART_NAME
 C58 'Q_CAP_C0805-10UF,16V,10%,X6S,CA':;

SECTION_NUMBER 1
 '@S9S_MB_2U_LIB.S9S_MB_2U(SCH_1):PAGE100_I124@PURE_QUANTA.Q_CAP(CHIPS)':
 C_PATH='@s9s_mb_2u_lib.s9s_mb_2u(sch_1):page100_i124@pure_quanta.q_cap(chips)',
 P_PATH='@s9s_mb_2u_lib.s9s_mb_2u(sch_1):page100_i124@pure_quanta.q_cap(chips)',
 PATH='I124',
 DRAWING='@S9S_MB_2U_LIB.S9S_MB_2U(SCH_1):PAGE100',
 PHYS_PAGE='100',
 XY='(2775,525)',
 ROT='0',
 VER='1',
 PACK_TYPE='C0805',
 CDS_LIB='pure_quanta',
 CDS_PART_NAME='Q_CAP_C0805-10UF,16V,10%,X6S,CA',
 TOLERANCE='10%',
 MATERIAL='X6S',
 VOLTAGE='16V',
 VALUE='10UF',
 PRIM_FILE='./archive_libs/logical/q_cap/chips/chips.prt';

PART_NAME
 C59 'Q_CAP_C0402-2.2UF,6.3V,20%,X6SA':;

SECTION_NUMBER 1
 '@S9S_MB_2U_LIB.S9S_MB_2U(SCH_1):PAGE101_I121@PURE_QUANTA.Q_CAP(CHIPS)':
 C_PATH='@s9s_mb_2u_lib.s9s_mb_2u(sch_1):page101_i121@pure_quanta.q_cap(chips)',
 P_PATH='@s9s_mb_2u_lib.s9s_mb_2u(sch_1):page101_i121@pure_quanta.q_cap(chips)',
 PATH='I121',
 DRAWING='@S9S_MB_2U_LIB.S9S_MB_2U(SCH_1):PAGE101',
 PHYS_PAGE='101',
 XY='(-900,775)',
 ROT='0',
 VER='1',
 PACK_TYPE='C0402',
 CDS_LIB='pure_quanta',
 CDS_PART_NAME='Q_CAP_C0402-2.2UF,6.3V,20%,X6SA',
 TOLERANCE='20%',
 MATERIAL='X6S',
 VOLTAGE='6.3V',
 VALUE='2.2UF',
 PRIM_FILE='./archive_libs/logical/q_cap/chips/chips.prt';

PART_NAME
 C60 'Q_CAP_C0805-10UF,16V,10%,X6S,CA':;

SECTION_NUMBER 1
 '@S9S_MB_2U_LIB.S9S_MB_2U(SCH_1):PAGE101_I125@PURE_QUANTA.Q_CAP(CHIPS)':
 C_PATH='@s9s_mb_2u_lib.s9s_mb_2u(sch_1):page101_i125@pure_quanta.q_cap(chips)',
 P_PATH='@s9s_mb_2u_lib.s9s_mb_2u(sch_1):page101_i125@pure_quanta.q_cap(chips)',
 PATH='I125',
 DRAWING='@S9S_MB_2U_LIB.S9S_MB_2U(SCH_1):PAGE101',
 PHYS_PAGE='101',
 XY='(100,775)',
 ROT='0',
 VER='1',
 PACK_TYPE='C0805',
 CDS_LIB='pure_quanta',
 CDS_PART_NAME='Q_CAP_C0805-10UF,16V,10%,X6S,CA',
 TOLERANCE='10%',
 MATERIAL='X6S',
 VOLTAGE='16V',
 VALUE='10UF',
 PRIM_FILE='./archive_libs/logical/q_cap/chips/chips.prt';

PART_NAME
 C61 'Q_CAP_C0805-10UF,16V,10%,X6S,CA':;

SECTION_NUMBER 1
 '@S9S_MB_2U_LIB.S9S_MB_2U(SCH_1):PAGE101_I127@PURE_QUANTA.Q_CAP(CHIPS)':
 C_PATH='@s9s_mb_2u_lib.s9s_mb_2u(sch_1):page101_i127@pure_quanta.q_cap(chips)',
 P_PATH='@s9s_mb_2u_lib.s9s_mb_2u(sch_1):page101_i127@pure_quanta.q_cap(chips)',
 PATH='I127',
 DRAWING='@S9S_MB_2U_LIB.S9S_MB_2U(SCH_1):PAGE101',
 PHYS_PAGE='101',
 XY='(725,775)',
 ROT='0',
 VER='1',
 PACK_TYPE='C0805',
 CDS_LIB='pure_quanta',
 CDS_PART_NAME='Q_CAP_C0805-10UF,16V,10%,X6S,CA',
 TOLERANCE='10%',
 MATERIAL='X6S',
 VOLTAGE='16V',
 VALUE='10UF',
 PRIM_FILE='./archive_libs/logical/q_cap/chips/chips.prt';

PART_NAME
 C62 'Q_CAP_C0402-2.2UF,6.3V,20%,X6SA':;

SECTION_NUMBER 1
 '@S9S_MB_2U_LIB.S9S_MB_2U(SCH_1):PAGE102_I124@PURE_QUANTA.Q_CAP(CHIPS)':
 C_PATH='@s9s_mb_2u_lib.s9s_mb_2u(sch_1):page102_i124@pure_quanta.q_cap(chips)',
 P_PATH='@s9s_mb_2u_lib.s9s_mb_2u(sch_1):page102_i124@pure_quanta.q_cap(chips)',
 PATH='I124',
 DRAWING='@S9S_MB_2U_LIB.S9S_MB_2U(SCH_1):PAGE102',
 PHYS_PAGE='102',
 XY='(550,300)',
 ROT='0',
 VER='1',
 PACK_TYPE='C0402',
 CDS_LIB='pure_quanta',
 CDS_PART_NAME='Q_CAP_C0402-2.2UF,6.3V,20%,X6SA',
 TOLERANCE='20%',
 MATERIAL='X6S',
 VOLTAGE='6.3V',
 VALUE='2.2UF',
 PRIM_FILE='./archive_libs/logical/q_cap/chips/chips.prt';

PART_NAME
 C63 'Q_CAP_C0805-10UF,16V,10%,X6S,CA':;

SECTION_NUMBER 1
 '@S9S_MB_2U_LIB.S9S_MB_2U(SCH_1):PAGE102_I127@PURE_QUANTA.Q_CAP(CHIPS)':
 C_PATH='@s9s_mb_2u_lib.s9s_mb_2u(sch_1):page102_i127@pure_quanta.q_cap(chips)',
 P_PATH='@s9s_mb_2u_lib.s9s_mb_2u(sch_1):page102_i127@pure_quanta.q_cap(chips)',
 PATH='I127',
 DRAWING='@S9S_MB_2U_LIB.S9S_MB_2U(SCH_1):PAGE102',
 PHYS_PAGE='102',
 XY='(1550,300)',
 ROT='0',
 VER='1',
 PACK_TYPE='C0805',
 CDS_LIB='pure_quanta',
 CDS_PART_NAME='Q_CAP_C0805-10UF,16V,10%,X6S,CA',
 TOLERANCE='10%',
 MATERIAL='X6S',
 VOLTAGE='16V',
 VALUE='10UF',
 PRIM_FILE='./archive_libs/logical/q_cap/chips/chips.prt';

PART_NAME
 C64 'Q_CAP_C0805-10UF,16V,10%,X6S,CA':;

SECTION_NUMBER 1
 '@S9S_MB_2U_LIB.S9S_MB_2U(SCH_1):PAGE102_I167@PURE_QUANTA.Q_CAP(CHIPS)':
 C_PATH='@s9s_mb_2u_lib.s9s_mb_2u(sch_1):page102_i167@pure_quanta.q_cap(chips)',
 P_PATH='@s9s_mb_2u_lib.s9s_mb_2u(sch_1):page102_i167@pure_quanta.q_cap(chips)',
 PATH='I167',
 DRAWING='@S9S_MB_2U_LIB.S9S_MB_2U(SCH_1):PAGE102',
 PHYS_PAGE='102',
 XY='(2175,300)',
 ROT='0',
 VER='1',
 PACK_TYPE='C0805',
 CDS_LIB='pure_quanta',
 CDS_PART_NAME='Q_CAP_C0805-10UF,16V,10%,X6S,CA',
 TOLERANCE='10%',
 MATERIAL='X6S',
 VOLTAGE='16V',
 VALUE='10UF',
 PRIM_FILE='./archive_libs/logical/q_cap/chips/chips.prt';

PART_NAME
 C65 'Q_CAP_C0402-2.2UF,6.3V,20%,X6SA':;

SECTION_NUMBER 1
 '@S9S_MB_2U_LIB.S9S_MB_2U(SCH_1):PAGE103_I122@PURE_QUANTA.Q_CAP(CHIPS)':
 C_PATH='@s9s_mb_2u_lib.s9s_mb_2u(sch_1):page103_i122@pure_quanta.q_cap(chips)',
 P_PATH='@s9s_mb_2u_lib.s9s_mb_2u(sch_1):page103_i122@pure_quanta.q_cap(chips)',
 PATH='I122',
 DRAWING='@S9S_MB_2U_LIB.S9S_MB_2U(SCH_1):PAGE103',
 PHYS_PAGE='103',
 XY='(475,25)',
 ROT='0',
 VER='1',
 PACK_TYPE='C0402',
 CDS_LIB='pure_quanta',
 CDS_PART_NAME='Q_CAP_C0402-2.2UF,6.3V,20%,X6SA',
 TOLERANCE='20%',
 MATERIAL='X6S',
 VOLTAGE='6.3V',
 VALUE='2.2UF',
 PRIM_FILE='./archive_libs/logical/q_cap/chips/chips.prt';

PART_NAME
 C66 'Q_CAP_C0805-10UF,16V,10%,X6S,CA':;

SECTION_NUMBER 1
 '@S9S_MB_2U_LIB.S9S_MB_2U(SCH_1):PAGE103_I126@PURE_QUANTA.Q_CAP(CHIPS)':
 C_PATH='@s9s_mb_2u_lib.s9s_mb_2u(sch_1):page103_i126@pure_quanta.q_cap(chips)',
 P_PATH='@s9s_mb_2u_lib.s9s_mb_2u(sch_1):page103_i126@pure_quanta.q_cap(chips)',
 PATH='I126',
 DRAWING='@S9S_MB_2U_LIB.S9S_MB_2U(SCH_1):PAGE103',
 PHYS_PAGE='103',
 XY='(1475,25)',
 ROT='0',
 VER='1',
 PACK_TYPE='C0805',
 CDS_LIB='pure_quanta',
 CDS_PART_NAME='Q_CAP_C0805-10UF,16V,10%,X6S,CA',
 TOLERANCE='10%',
 MATERIAL='X6S',
 VOLTAGE='16V',
 VALUE='10UF',
 PRIM_FILE='./archive_libs/logical/q_cap/chips/chips.prt';

PART_NAME
 C67 'Q_CAP_C0805-10UF,16V,10%,X6S,CA':;

SECTION_NUMBER 1
 '@S9S_MB_2U_LIB.S9S_MB_2U(SCH_1):PAGE103_I128@PURE_QUANTA.Q_CAP(CHIPS)':
 C_PATH='@s9s_mb_2u_lib.s9s_mb_2u(sch_1):page103_i128@pure_quanta.q_cap(chips)',
 P_PATH='@s9s_mb_2u_lib.s9s_mb_2u(sch_1):page103_i128@pure_quanta.q_cap(chips)',
 PATH='I128',
 DRAWING='@S9S_MB_2U_LIB.S9S_MB_2U(SCH_1):PAGE103',
 PHYS_PAGE='103',
 XY='(2100,25)',
 ROT='0',
 VER='1',
 PACK_TYPE='C0805',
 CDS_LIB='pure_quanta',
 CDS_PART_NAME='Q_CAP_C0805-10UF,16V,10%,X6S,CA',
 TOLERANCE='10%',
 MATERIAL='X6S',
 VOLTAGE='16V',
 VALUE='10UF',
 PRIM_FILE='./archive_libs/logical/q_cap/chips/chips.prt';

PART_NAME
 C68 'Q_CAP_C0402-2.2UF,6.3V,20%,X6SA':;

SECTION_NUMBER 1
 '@S9S_MB_2U_LIB.S9S_MB_2U(SCH_1):PAGE104_I122@PURE_QUANTA.Q_CAP(CHIPS)':
 C_PATH='@s9s_mb_2u_lib.s9s_mb_2u(sch_1):page104_i122@pure_quanta.q_cap(chips)',
 P_PATH='@s9s_mb_2u_lib.s9s_mb_2u(sch_1):page104_i122@pure_quanta.q_cap(chips)',
 PATH='I122',
 DRAWING='@S9S_MB_2U_LIB.S9S_MB_2U(SCH_1):PAGE104',
 PHYS_PAGE='104',
 XY='(50,250)',
 ROT='0',
 VER='1',
 PACK_TYPE='C0402',
 CDS_LIB='pure_quanta',
 CDS_PART_NAME='Q_CAP_C0402-2.2UF,6.3V,20%,X6SA',
 TOLERANCE='20%',
 MATERIAL='X6S',
 VOLTAGE='6.3V',
 VALUE='2.2UF',
 PRIM_FILE='./archive_libs/logical/q_cap/chips/chips.prt';

PART_NAME
 C69 'Q_CAP_C0805-10UF,16V,10%,X6S,CA':;

SECTION_NUMBER 1
 '@S9S_MB_2U_LIB.S9S_MB_2U(SCH_1):PAGE104_I127@PURE_QUANTA.Q_CAP(CHIPS)':
 C_PATH='@s9s_mb_2u_lib.s9s_mb_2u(sch_1):page104_i127@pure_quanta.q_cap(chips)',
 P_PATH='@s9s_mb_2u_lib.s9s_mb_2u(sch_1):page104_i127@pure_quanta.q_cap(chips)',
 PATH='I127',
 DRAWING='@S9S_MB_2U_LIB.S9S_MB_2U(SCH_1):PAGE104',
 PHYS_PAGE='104',
 XY='(1050,250)',
 ROT='0',
 VER='1',
 PACK_TYPE='C0805',
 CDS_LIB='pure_quanta',
 CDS_PART_NAME='Q_CAP_C0805-10UF,16V,10%,X6S,CA',
 TOLERANCE='10%',
 MATERIAL='X6S',
 VOLTAGE='16V',
 VALUE='10UF',
 PRIM_FILE='./archive_libs/logical/q_cap/chips/chips.prt';

PART_NAME
 C70 'Q_CAP_C0805-10UF,16V,10%,X6S,CA':;

SECTION_NUMBER 1
 '@S9S_MB_2U_LIB.S9S_MB_2U(SCH_1):PAGE104_I129@PURE_QUANTA.Q_CAP(CHIPS)':
 C_PATH='@s9s_mb_2u_lib.s9s_mb_2u(sch_1):page104_i129@pure_quanta.q_cap(chips)',
 P_PATH='@s9s_mb_2u_lib.s9s_mb_2u(sch_1):page104_i129@pure_quanta.q_cap(chips)',
 PATH='I129',
 DRAWING='@S9S_MB_2U_LIB.S9S_MB_2U(SCH_1):PAGE104',
 PHYS_PAGE='104',
 XY='(1675,250)',
 ROT='0',
 VER='1',
 PACK_TYPE='C0805',
 CDS_LIB='pure_quanta',
 CDS_PART_NAME='Q_CAP_C0805-10UF,16V,10%,X6S,CA',
 TOLERANCE='10%',
 MATERIAL='X6S',
 VOLTAGE='16V',
 VALUE='10UF',
 PRIM_FILE='./archive_libs/logical/q_cap/chips/chips.prt';

PART_NAME
 C71 'Q_CAP_C0402-10UF,6.3V,20%,X6S,A':;

SECTION_NUMBER 1
 '@S9S_MB_2U_LIB.S9S_MB_2U(SCH_1):PAGE68_I4@PURE_QUANTA.Q_CAP(CHIPS)':
 C_PATH='@s9s_mb_2u_lib.s9s_mb_2u(sch_1):page68_i4@pure_quanta.q_cap(chips)',
 P_PATH='@s9s_mb_2u_lib.s9s_mb_2u(sch_1):page68_i4@pure_quanta.q_cap(chips)',
 PATH='I4',
 DRAWING='@S9S_MB_2U_LIB.S9S_MB_2U(SCH_1):PAGE68',
 PHYS_PAGE='68',
 XY='(1350,1075)',
 ROT='0',
 VER='1',
 PACK_TYPE='C0402',
 CDS_LIB='pure_quanta',
 CDS_PART_NAME='Q_CAP_C0402-10UF,6.3V,20%,X6S,A',
 TOLERANCE='20%',
 MATERIAL='X6S',
 VOLTAGE='6.3V',
 VALUE='10UF',
 PRIM_FILE='./archive_libs/logical/q_cap/chips/chips.prt';

PART_NAME
 C72 'Q_CAP_C0402-2.2UF,6.3V,20%,X6SA':;

SECTION_NUMBER 1
 '@S9S_MB_2U_LIB.S9S_MB_2U(SCH_1):PAGE113_I116@PURE_QUANTA.Q_CAP(CHIPS)':
 C_PATH='@s9s_mb_2u_lib.s9s_mb_2u(sch_1):page113_i116@pure_quanta.q_cap(chips)',
 P_PATH='@s9s_mb_2u_lib.s9s_mb_2u(sch_1):page113_i116@pure_quanta.q_cap(chips)',
 PATH='I116',
 DRAWING='@S9S_MB_2U_LIB.S9S_MB_2U(SCH_1):PAGE113',
 PHYS_PAGE='113',
 XY='(-525,575)',
 ROT='0',
 VER='1',
 PACK_TYPE='C0402',
 CDS_LIB='pure_quanta',
 CDS_PART_NAME='Q_CAP_C0402-2.2UF,6.3V,20%,X6SA',
 TOLERANCE='20%',
 MATERIAL='X6S',
 VOLTAGE='6.3V',
 VALUE='2.2UF',
 PRIM_FILE='./archive_libs/logical/q_cap/chips/chips.prt';

PART_NAME
 C73 'Q_CAP_C0805-10UF,16V,10%,X6S,CA':;

SECTION_NUMBER 1
 '@S9S_MB_2U_LIB.S9S_MB_2U(SCH_1):PAGE113_I120@PURE_QUANTA.Q_CAP(CHIPS)':
 C_PATH='@s9s_mb_2u_lib.s9s_mb_2u(sch_1):page113_i120@pure_quanta.q_cap(chips)',
 P_PATH='@s9s_mb_2u_lib.s9s_mb_2u(sch_1):page113_i120@pure_quanta.q_cap(chips)',
 PATH='I120',
 DRAWING='@S9S_MB_2U_LIB.S9S_MB_2U(SCH_1):PAGE113',
 PHYS_PAGE='113',
 XY='(475,575)',
 ROT='0',
 VER='1',
 PACK_TYPE='C0805',
 CDS_LIB='pure_quanta',
 CDS_PART_NAME='Q_CAP_C0805-10UF,16V,10%,X6S,CA',
 TOLERANCE='10%',
 MATERIAL='X6S',
 VOLTAGE='16V',
 VALUE='10UF',
 PRIM_FILE='./archive_libs/logical/q_cap/chips/chips.prt';

PART_NAME
 C74 'Q_CAP_C0805-10UF,16V,10%,X6S,CA':;

SECTION_NUMBER 1
 '@S9S_MB_2U_LIB.S9S_MB_2U(SCH_1):PAGE113_I122@PURE_QUANTA.Q_CAP(CHIPS)':
 C_PATH='@s9s_mb_2u_lib.s9s_mb_2u(sch_1):page113_i122@pure_quanta.q_cap(chips)',
 P_PATH='@s9s_mb_2u_lib.s9s_mb_2u(sch_1):page113_i122@pure_quanta.q_cap(chips)',
 PATH='I122',
 DRAWING='@S9S_MB_2U_LIB.S9S_MB_2U(SCH_1):PAGE113',
 PHYS_PAGE='113',
 XY='(1100,575)',
 ROT='0',
 VER='1',
 PACK_TYPE='C0805',
 CDS_LIB='pure_quanta',
 CDS_PART_NAME='Q_CAP_C0805-10UF,16V,10%,X6S,CA',
 TOLERANCE='10%',
 MATERIAL='X6S',
 VOLTAGE='16V',
 VALUE='10UF',
 PRIM_FILE='./archive_libs/logical/q_cap/chips/chips.prt';

PART_NAME
 C75 'Q_CAP_C0402-2.2UF,6.3V,20%,X6SA':;

SECTION_NUMBER 1
 '@S9S_MB_2U_LIB.S9S_MB_2U(SCH_1):PAGE112_I124@PURE_QUANTA.Q_CAP(CHIPS)':
 C_PATH='@s9s_mb_2u_lib.s9s_mb_2u(sch_1):page112_i124@pure_quanta.q_cap(chips)',
 P_PATH='@s9s_mb_2u_lib.s9s_mb_2u(sch_1):page112_i124@pure_quanta.q_cap(chips)',
 PATH='I124',
 DRAWING='@S9S_MB_2U_LIB.S9S_MB_2U(SCH_1):PAGE112',
 PHYS_PAGE='112',
 XY='(125,425)',
 ROT='0',
 VER='1',
 PACK_TYPE='C0402',
 CDS_LIB='pure_quanta',
 CDS_PART_NAME='Q_CAP_C0402-2.2UF,6.3V,20%,X6SA',
 TOLERANCE='20%',
 MATERIAL='X6S',
 VOLTAGE='6.3V',
 VALUE='2.2UF',
 PRIM_FILE='./archive_libs/logical/q_cap/chips/chips.prt';

PART_NAME
 C76 'Q_CAP_C0805-10UF,16V,10%,X6S,CA':;

SECTION_NUMBER 1
 '@S9S_MB_2U_LIB.S9S_MB_2U(SCH_1):PAGE112_I125@PURE_QUANTA.Q_CAP(CHIPS)':
 C_PATH='@s9s_mb_2u_lib.s9s_mb_2u(sch_1):page112_i125@pure_quanta.q_cap(chips)',
 P_PATH='@s9s_mb_2u_lib.s9s_mb_2u(sch_1):page112_i125@pure_quanta.q_cap(chips)',
 PATH='I125',
 DRAWING='@S9S_MB_2U_LIB.S9S_MB_2U(SCH_1):PAGE112',
 PHYS_PAGE='112',
 XY='(1125,425)',
 ROT='0',
 VER='1',
 PACK_TYPE='C0805',
 CDS_LIB='pure_quanta',
 CDS_PART_NAME='Q_CAP_C0805-10UF,16V,10%,X6S,CA',
 TOLERANCE='10%',
 MATERIAL='X6S',
 VOLTAGE='16V',
 VALUE='10UF',
 PRIM_FILE='./archive_libs/logical/q_cap/chips/chips.prt';

PART_NAME
 C77 'Q_CAP_C0805-10UF,16V,10%,X6S,CA':;

SECTION_NUMBER 1
 '@S9S_MB_2U_LIB.S9S_MB_2U(SCH_1):PAGE112_I126@PURE_QUANTA.Q_CAP(CHIPS)':
 C_PATH='@s9s_mb_2u_lib.s9s_mb_2u(sch_1):page112_i126@pure_quanta.q_cap(chips)',
 P_PATH='@s9s_mb_2u_lib.s9s_mb_2u(sch_1):page112_i126@pure_quanta.q_cap(chips)',
 PATH='I126',
 DRAWING='@S9S_MB_2U_LIB.S9S_MB_2U(SCH_1):PAGE112',
 PHYS_PAGE='112',
 XY='(1750,425)',
 ROT='0',
 VER='1',
 PACK_TYPE='C0805',
 CDS_LIB='pure_quanta',
 CDS_PART_NAME='Q_CAP_C0805-10UF,16V,10%,X6S,CA',
 TOLERANCE='10%',
 MATERIAL='X6S',
 VOLTAGE='16V',
 VALUE='10UF',
 PRIM_FILE='./archive_libs/logical/q_cap/chips/chips.prt';

PART_NAME
 C78 'Q_CAP_C0402-2.2UF,6.3V,20%,X6SA':;

SECTION_NUMBER 1
 '@S9S_MB_2U_LIB.S9S_MB_2U(SCH_1):PAGE111_I54@PURE_QUANTA.Q_CAP(CHIPS)':
 C_PATH='@s9s_mb_2u_lib.s9s_mb_2u(sch_1):page111_i54@pure_quanta.q_cap(chips)',
 P_PATH='@s9s_mb_2u_lib.s9s_mb_2u(sch_1):page111_i54@pure_quanta.q_cap(chips)',
 PATH='I54',
 DRAWING='@S9S_MB_2U_LIB.S9S_MB_2U(SCH_1):PAGE111',
 PHYS_PAGE='111',
 XY='(225,525)',
 ROT='0',
 VER='1',
 PACK_TYPE='C0402',
 CDS_LIB='pure_quanta',
 CDS_PART_NAME='Q_CAP_C0402-2.2UF,6.3V,20%,X6SA',
 TOLERANCE='20%',
 MATERIAL='X6S',
 VOLTAGE='6.3V',
 VALUE='2.2UF',
 PRIM_FILE='./archive_libs/logical/q_cap/chips/chips.prt';

PART_NAME
 C79 'Q_CAP_C0805-10UF,16V,10%,X6S,CA':;

SECTION_NUMBER 1
 '@S9S_MB_2U_LIB.S9S_MB_2U(SCH_1):PAGE111_I56@PURE_QUANTA.Q_CAP(CHIPS)':
 C_PATH='@s9s_mb_2u_lib.s9s_mb_2u(sch_1):page111_i56@pure_quanta.q_cap(chips)',
 P_PATH='@s9s_mb_2u_lib.s9s_mb_2u(sch_1):page111_i56@pure_quanta.q_cap(chips)',
 PATH='I56',
 DRAWING='@S9S_MB_2U_LIB.S9S_MB_2U(SCH_1):PAGE111',
 PHYS_PAGE='111',
 XY='(1225,525)',
 ROT='0',
 VER='1',
 PACK_TYPE='C0805',
 CDS_LIB='pure_quanta',
 CDS_PART_NAME='Q_CAP_C0805-10UF,16V,10%,X6S,CA',
 TOLERANCE='10%',
 MATERIAL='X6S',
 VOLTAGE='16V',
 VALUE='10UF',
 PRIM_FILE='./archive_libs/logical/q_cap/chips/chips.prt';

PART_NAME
 C80 'Q_CAP_C0805-10UF,16V,10%,X6S,CA':;

SECTION_NUMBER 1
 '@S9S_MB_2U_LIB.S9S_MB_2U(SCH_1):PAGE111_I59@PURE_QUANTA.Q_CAP(CHIPS)':
 C_PATH='@s9s_mb_2u_lib.s9s_mb_2u(sch_1):page111_i59@pure_quanta.q_cap(chips)',
 P_PATH='@s9s_mb_2u_lib.s9s_mb_2u(sch_1):page111_i59@pure_quanta.q_cap(chips)',
 PATH='I59',
 DRAWING='@S9S_MB_2U_LIB.S9S_MB_2U(SCH_1):PAGE111',
 PHYS_PAGE='111',
 XY='(1850,525)',
 ROT='0',
 VER='1',
 PACK_TYPE='C0805',
 CDS_LIB='pure_quanta',
 CDS_PART_NAME='Q_CAP_C0805-10UF,16V,10%,X6S,CA',
 TOLERANCE='10%',
 MATERIAL='X6S',
 VOLTAGE='16V',
 VALUE='10UF',
 PRIM_FILE='./archive_libs/logical/q_cap/chips/chips.prt';

PART_NAME
 C81 'Q_CAP_C0402-2.2UF,6.3V,20%,X6SA':;

SECTION_NUMBER 1
 '@S9S_MB_2U_LIB.S9S_MB_2U(SCH_1):PAGE110_I120@PURE_QUANTA.Q_CAP(CHIPS)':
 C_PATH='@s9s_mb_2u_lib.s9s_mb_2u(sch_1):page110_i120@pure_quanta.q_cap(chips)',
 P_PATH='@s9s_mb_2u_lib.s9s_mb_2u(sch_1):page110_i120@pure_quanta.q_cap(chips)',
 PATH='I120',
 DRAWING='@S9S_MB_2U_LIB.S9S_MB_2U(SCH_1):PAGE110',
 PHYS_PAGE='110',
 XY='(800,75)',
 ROT='0',
 VER='1',
 PACK_TYPE='C0402',
 CDS_LIB='pure_quanta',
 CDS_PART_NAME='Q_CAP_C0402-2.2UF,6.3V,20%,X6SA',
 TOLERANCE='20%',
 MATERIAL='X6S',
 VOLTAGE='6.3V',
 VALUE='2.2UF',
 PRIM_FILE='./archive_libs/logical/q_cap/chips/chips.prt';

PART_NAME
 C82 'Q_CAP_C0805-10UF,16V,10%,X6S,CA':;

SECTION_NUMBER 1
 '@S9S_MB_2U_LIB.S9S_MB_2U(SCH_1):PAGE110_I124@PURE_QUANTA.Q_CAP(CHIPS)':
 C_PATH='@s9s_mb_2u_lib.s9s_mb_2u(sch_1):page110_i124@pure_quanta.q_cap(chips)',
 P_PATH='@s9s_mb_2u_lib.s9s_mb_2u(sch_1):page110_i124@pure_quanta.q_cap(chips)',
 PATH='I124',
 DRAWING='@S9S_MB_2U_LIB.S9S_MB_2U(SCH_1):PAGE110',
 PHYS_PAGE='110',
 XY='(1800,75)',
 ROT='0',
 VER='1',
 PACK_TYPE='C0805',
 CDS_LIB='pure_quanta',
 CDS_PART_NAME='Q_CAP_C0805-10UF,16V,10%,X6S,CA',
 TOLERANCE='10%',
 MATERIAL='X6S',
 VOLTAGE='16V',
 VALUE='10UF',
 PRIM_FILE='./archive_libs/logical/q_cap/chips/chips.prt';

PART_NAME
 C83 'Q_CAP_C0805-10UF,16V,10%,X6S,CA':;

SECTION_NUMBER 1
 '@S9S_MB_2U_LIB.S9S_MB_2U(SCH_1):PAGE110_I126@PURE_QUANTA.Q_CAP(CHIPS)':
 C_PATH='@s9s_mb_2u_lib.s9s_mb_2u(sch_1):page110_i126@pure_quanta.q_cap(chips)',
 P_PATH='@s9s_mb_2u_lib.s9s_mb_2u(sch_1):page110_i126@pure_quanta.q_cap(chips)',
 PATH='I126',
 DRAWING='@S9S_MB_2U_LIB.S9S_MB_2U(SCH_1):PAGE110',
 PHYS_PAGE='110',
 XY='(2425,75)',
 ROT='0',
 VER='1',
 PACK_TYPE='C0805',
 CDS_LIB='pure_quanta',
 CDS_PART_NAME='Q_CAP_C0805-10UF,16V,10%,X6S,CA',
 TOLERANCE='10%',
 MATERIAL='X6S',
 VOLTAGE='16V',
 VALUE='10UF',
 PRIM_FILE='./archive_libs/logical/q_cap/chips/chips.prt';

PART_NAME
 C84 'Q_CAP_C0402-2.2UF,6.3V,20%,X6SA':;

SECTION_NUMBER 1
 '@S9S_MB_2U_LIB.S9S_MB_2U(SCH_1):PAGE109_I121@PURE_QUANTA.Q_CAP(CHIPS)':
 C_PATH='@s9s_mb_2u_lib.s9s_mb_2u(sch_1):page109_i121@pure_quanta.q_cap(chips)',
 P_PATH='@s9s_mb_2u_lib.s9s_mb_2u(sch_1):page109_i121@pure_quanta.q_cap(chips)',
 PATH='I121',
 DRAWING='@S9S_MB_2U_LIB.S9S_MB_2U(SCH_1):PAGE109',
 PHYS_PAGE='109',
 XY='(925,325)',
 ROT='0',
 VER='1',
 PACK_TYPE='C0402',
 CDS_LIB='pure_quanta',
 CDS_PART_NAME='Q_CAP_C0402-2.2UF,6.3V,20%,X6SA',
 TOLERANCE='20%',
 MATERIAL='X6S',
 VOLTAGE='6.3V',
 VALUE='2.2UF',
 PRIM_FILE='./archive_libs/logical/q_cap/chips/chips.prt';

PART_NAME
 C85 'Q_CAP_C0805-10UF,16V,10%,X6S,CA':;

SECTION_NUMBER 1
 '@S9S_MB_2U_LIB.S9S_MB_2U(SCH_1):PAGE109_I125@PURE_QUANTA.Q_CAP(CHIPS)':
 C_PATH='@s9s_mb_2u_lib.s9s_mb_2u(sch_1):page109_i125@pure_quanta.q_cap(chips)',
 P_PATH='@s9s_mb_2u_lib.s9s_mb_2u(sch_1):page109_i125@pure_quanta.q_cap(chips)',
 PATH='I125',
 DRAWING='@S9S_MB_2U_LIB.S9S_MB_2U(SCH_1):PAGE109',
 PHYS_PAGE='109',
 XY='(1925,325)',
 ROT='0',
 VER='1',
 PACK_TYPE='C0805',
 CDS_LIB='pure_quanta',
 CDS_PART_NAME='Q_CAP_C0805-10UF,16V,10%,X6S,CA',
 TOLERANCE='10%',
 MATERIAL='X6S',
 VOLTAGE='16V',
 VALUE='10UF',
 PRIM_FILE='./archive_libs/logical/q_cap/chips/chips.prt';

PART_NAME
 C86 'Q_CAP_C0805-10UF,16V,10%,X6S,CA':;

SECTION_NUMBER 1
 '@S9S_MB_2U_LIB.S9S_MB_2U(SCH_1):PAGE109_I128@PURE_QUANTA.Q_CAP(CHIPS)':
 C_PATH='@s9s_mb_2u_lib.s9s_mb_2u(sch_1):page109_i128@pure_quanta.q_cap(chips)',
 P_PATH='@s9s_mb_2u_lib.s9s_mb_2u(sch_1):page109_i128@pure_quanta.q_cap(chips)',
 PATH='I128',
 DRAWING='@S9S_MB_2U_LIB.S9S_MB_2U(SCH_1):PAGE109',
 PHYS_PAGE='109',
 XY='(2550,325)',
 ROT='0',
 VER='1',
 PACK_TYPE='C0805',
 CDS_LIB='pure_quanta',
 CDS_PART_NAME='Q_CAP_C0805-10UF,16V,10%,X6S,CA',
 TOLERANCE='10%',
 MATERIAL='X6S',
 VOLTAGE='16V',
 VALUE='10UF',
 PRIM_FILE='./archive_libs/logical/q_cap/chips/chips.prt';

PART_NAME
 C87 'Q_CAP_C0402-2.2UF,6.3V,20%,X6SA':;

SECTION_NUMBER 1
 '@S9S_MB_2U_LIB.S9S_MB_2U(SCH_1):PAGE108_I121@PURE_QUANTA.Q_CAP(CHIPS)':
 C_PATH='@s9s_mb_2u_lib.s9s_mb_2u(sch_1):page108_i121@pure_quanta.q_cap(chips)',
 P_PATH='@s9s_mb_2u_lib.s9s_mb_2u(sch_1):page108_i121@pure_quanta.q_cap(chips)',
 PATH='I121',
 DRAWING='@S9S_MB_2U_LIB.S9S_MB_2U(SCH_1):PAGE108',
 PHYS_PAGE='108',
 XY='(650,1475)',
 ROT='0',
 VER='1',
 PACK_TYPE='C0402',
 CDS_LIB='pure_quanta',
 CDS_PART_NAME='Q_CAP_C0402-2.2UF,6.3V,20%,X6SA',
 TOLERANCE='20%',
 MATERIAL='X6S',
 VOLTAGE='6.3V',
 VALUE='2.2UF',
 PRIM_FILE='./archive_libs/logical/q_cap/chips/chips.prt';

PART_NAME
 C88 'Q_CAP_C0805-10UF,16V,10%,X6S,CA':;

SECTION_NUMBER 1
 '@S9S_MB_2U_LIB.S9S_MB_2U(SCH_1):PAGE108_I123@PURE_QUANTA.Q_CAP(CHIPS)':
 C_PATH='@s9s_mb_2u_lib.s9s_mb_2u(sch_1):page108_i123@pure_quanta.q_cap(chips)',
 P_PATH='@s9s_mb_2u_lib.s9s_mb_2u(sch_1):page108_i123@pure_quanta.q_cap(chips)',
 PATH='I123',
 DRAWING='@S9S_MB_2U_LIB.S9S_MB_2U(SCH_1):PAGE108',
 PHYS_PAGE='108',
 XY='(1650,1475)',
 ROT='0',
 VER='1',
 PACK_TYPE='C0805',
 CDS_LIB='pure_quanta',
 CDS_PART_NAME='Q_CAP_C0805-10UF,16V,10%,X6S,CA',
 TOLERANCE='10%',
 MATERIAL='X6S',
 VOLTAGE='16V',
 VALUE='10UF',
 PRIM_FILE='./archive_libs/logical/q_cap/chips/chips.prt';

PART_NAME
 C89 'Q_CAP_C0805-10UF,16V,10%,X6S,CA':;

SECTION_NUMBER 1
 '@S9S_MB_2U_LIB.S9S_MB_2U(SCH_1):PAGE108_I160@PURE_QUANTA.Q_CAP(CHIPS)':
 C_PATH='@s9s_mb_2u_lib.s9s_mb_2u(sch_1):page108_i160@pure_quanta.q_cap(chips)',
 P_PATH='@s9s_mb_2u_lib.s9s_mb_2u(sch_1):page108_i160@pure_quanta.q_cap(chips)',
 PATH='I160',
 DRAWING='@S9S_MB_2U_LIB.S9S_MB_2U(SCH_1):PAGE108',
 PHYS_PAGE='108',
 XY='(2275,1475)',
 ROT='0',
 VER='1',
 PACK_TYPE='C0805',
 CDS_LIB='pure_quanta',
 CDS_PART_NAME='Q_CAP_C0805-10UF,16V,10%,X6S,CA',
 TOLERANCE='10%',
 MATERIAL='X6S',
 VOLTAGE='16V',
 VALUE='10UF',
 PRIM_FILE='./archive_libs/logical/q_cap/chips/chips.prt';

PART_NAME
 C90 'Q_CAP_C0402-2.2UF,6.3V,20%,X6SA':;

SECTION_NUMBER 1
 '@S9S_MB_2U_LIB.S9S_MB_2U(SCH_1):PAGE107_I122@PURE_QUANTA.Q_CAP(CHIPS)':
 C_PATH='@s9s_mb_2u_lib.s9s_mb_2u(sch_1):page107_i122@pure_quanta.q_cap(chips)',
 P_PATH='@s9s_mb_2u_lib.s9s_mb_2u(sch_1):page107_i122@pure_quanta.q_cap(chips)',
 PATH='I122',
 DRAWING='@S9S_MB_2U_LIB.S9S_MB_2U(SCH_1):PAGE107',
 PHYS_PAGE='107',
 XY='(875,500)',
 ROT='0',
 VER='1',
 PACK_TYPE='C0402',
 CDS_LIB='pure_quanta',
 CDS_PART_NAME='Q_CAP_C0402-2.2UF,6.3V,20%,X6SA',
 TOLERANCE='20%',
 MATERIAL='X6S',
 VOLTAGE='6.3V',
 VALUE='2.2UF',
 PRIM_FILE='./archive_libs/logical/q_cap/chips/chips.prt';

PART_NAME
 C91 'Q_CAP_C0805-10UF,16V,10%,X6S,CA':;

SECTION_NUMBER 1
 '@S9S_MB_2U_LIB.S9S_MB_2U(SCH_1):PAGE107_I126@PURE_QUANTA.Q_CAP(CHIPS)':
 C_PATH='@s9s_mb_2u_lib.s9s_mb_2u(sch_1):page107_i126@pure_quanta.q_cap(chips)',
 P_PATH='@s9s_mb_2u_lib.s9s_mb_2u(sch_1):page107_i126@pure_quanta.q_cap(chips)',
 PATH='I126',
 DRAWING='@S9S_MB_2U_LIB.S9S_MB_2U(SCH_1):PAGE107',
 PHYS_PAGE='107',
 XY='(1875,500)',
 ROT='0',
 VER='1',
 PACK_TYPE='C0805',
 CDS_LIB='pure_quanta',
 CDS_PART_NAME='Q_CAP_C0805-10UF,16V,10%,X6S,CA',
 TOLERANCE='10%',
 MATERIAL='X6S',
 VOLTAGE='16V',
 VALUE='10UF',
 PRIM_FILE='./archive_libs/logical/q_cap/chips/chips.prt';

PART_NAME
 C92 'Q_CAP_C0805-10UF,16V,10%,X6S,CA':;

SECTION_NUMBER 1
 '@S9S_MB_2U_LIB.S9S_MB_2U(SCH_1):PAGE107_I128@PURE_QUANTA.Q_CAP(CHIPS)':
 C_PATH='@s9s_mb_2u_lib.s9s_mb_2u(sch_1):page107_i128@pure_quanta.q_cap(chips)',
 P_PATH='@s9s_mb_2u_lib.s9s_mb_2u(sch_1):page107_i128@pure_quanta.q_cap(chips)',
 PATH='I128',
 DRAWING='@S9S_MB_2U_LIB.S9S_MB_2U(SCH_1):PAGE107',
 PHYS_PAGE='107',
 XY='(2500,500)',
 ROT='0',
 VER='1',
 PACK_TYPE='C0805',
 CDS_LIB='pure_quanta',
 CDS_PART_NAME='Q_CAP_C0805-10UF,16V,10%,X6S,CA',
 TOLERANCE='10%',
 MATERIAL='X6S',
 VOLTAGE='16V',
 VALUE='10UF',
 PRIM_FILE='./archive_libs/logical/q_cap/chips/chips.prt';

PART_NAME
 C93 'Q_CAP_C0402-2.2UF,6.3V,20%,X6SA':;

SECTION_NUMBER 1
 '@S9S_MB_2U_LIB.S9S_MB_2U(SCH_1):PAGE106_I122@PURE_QUANTA.Q_CAP(CHIPS)':
 C_PATH='@s9s_mb_2u_lib.s9s_mb_2u(sch_1):page106_i122@pure_quanta.q_cap(chips)',
 P_PATH='@s9s_mb_2u_lib.s9s_mb_2u(sch_1):page106_i122@pure_quanta.q_cap(chips)',
 PATH='I122',
 DRAWING='@S9S_MB_2U_LIB.S9S_MB_2U(SCH_1):PAGE106',
 PHYS_PAGE='106',
 XY='(625,100)',
 ROT='0',
 VER='1',
 PACK_TYPE='C0402',
 CDS_LIB='pure_quanta',
 CDS_PART_NAME='Q_CAP_C0402-2.2UF,6.3V,20%,X6SA',
 TOLERANCE='20%',
 MATERIAL='X6S',
 VOLTAGE='6.3V',
 VALUE='2.2UF',
 PRIM_FILE='./archive_libs/logical/q_cap/chips/chips.prt';

PART_NAME
 C94 'Q_CAP_C0805-10UF,16V,10%,X6S,CA':;

SECTION_NUMBER 1
 '@S9S_MB_2U_LIB.S9S_MB_2U(SCH_1):PAGE106_I127@PURE_QUANTA.Q_CAP(CHIPS)':
 C_PATH='@s9s_mb_2u_lib.s9s_mb_2u(sch_1):page106_i127@pure_quanta.q_cap(chips)',
 P_PATH='@s9s_mb_2u_lib.s9s_mb_2u(sch_1):page106_i127@pure_quanta.q_cap(chips)',
 PATH='I127',
 DRAWING='@S9S_MB_2U_LIB.S9S_MB_2U(SCH_1):PAGE106',
 PHYS_PAGE='106',
 XY='(1625,100)',
 ROT='0',
 VER='1',
 PACK_TYPE='C0805',
 CDS_LIB='pure_quanta',
 CDS_PART_NAME='Q_CAP_C0805-10UF,16V,10%,X6S,CA',
 TOLERANCE='10%',
 MATERIAL='X6S',
 VOLTAGE='16V',
 VALUE='10UF',
 PRIM_FILE='./archive_libs/logical/q_cap/chips/chips.prt';

PART_NAME
 C95 'Q_CAP_C0805-10UF,16V,10%,X6S,CA':;

SECTION_NUMBER 1
 '@S9S_MB_2U_LIB.S9S_MB_2U(SCH_1):PAGE106_I130@PURE_QUANTA.Q_CAP(CHIPS)':
 C_PATH='@s9s_mb_2u_lib.s9s_mb_2u(sch_1):page106_i130@pure_quanta.q_cap(chips)',
 P_PATH='@s9s_mb_2u_lib.s9s_mb_2u(sch_1):page106_i130@pure_quanta.q_cap(chips)',
 PATH='I130',
 DRAWING='@S9S_MB_2U_LIB.S9S_MB_2U(SCH_1):PAGE106',
 PHYS_PAGE='106',
 XY='(2250,100)',
 ROT='0',
 VER='1',
 PACK_TYPE='C0805',
 CDS_LIB='pure_quanta',
 CDS_PART_NAME='Q_CAP_C0805-10UF,16V,10%,X6S,CA',
 TOLERANCE='10%',
 MATERIAL='X6S',
 VOLTAGE='16V',
 VALUE='10UF',
 PRIM_FILE='./archive_libs/logical/q_cap/chips/chips.prt';

PART_NAME
 C96 'Q_CAP_C0402-2.2UF,6.3V,20%,X6SA':;

SECTION_NUMBER 1
 '@S9S_MB_2U_LIB.S9S_MB_2U(SCH_1):PAGE105_I123@PURE_QUANTA.Q_CAP(CHIPS)':
 C_PATH='@s9s_mb_2u_lib.s9s_mb_2u(sch_1):page105_i123@pure_quanta.q_cap(chips)',
 P_PATH='@s9s_mb_2u_lib.s9s_mb_2u(sch_1):page105_i123@pure_quanta.q_cap(chips)',
 PATH='I123',
 DRAWING='@S9S_MB_2U_LIB.S9S_MB_2U(SCH_1):PAGE105',
 PHYS_PAGE='105',
 XY='(525,400)',
 ROT='0',
 VER='1',
 PACK_TYPE='C0402',
 CDS_LIB='pure_quanta',
 CDS_PART_NAME='Q_CAP_C0402-2.2UF,6.3V,20%,X6SA',
 TOLERANCE='20%',
 MATERIAL='X6S',
 VOLTAGE='6.3V',
 VALUE='2.2UF',
 PRIM_FILE='./archive_libs/logical/q_cap/chips/chips.prt';

PART_NAME
 C97 'Q_CAP_C0805-10UF,16V,10%,X6S,CA':;

SECTION_NUMBER 1
 '@S9S_MB_2U_LIB.S9S_MB_2U(SCH_1):PAGE105_I124@PURE_QUANTA.Q_CAP(CHIPS)':
 C_PATH='@s9s_mb_2u_lib.s9s_mb_2u(sch_1):page105_i124@pure_quanta.q_cap(chips)',
 P_PATH='@s9s_mb_2u_lib.s9s_mb_2u(sch_1):page105_i124@pure_quanta.q_cap(chips)',
 PATH='I124',
 DRAWING='@S9S_MB_2U_LIB.S9S_MB_2U(SCH_1):PAGE105',
 PHYS_PAGE='105',
 XY='(1525,400)',
 ROT='0',
 VER='1',
 PACK_TYPE='C0805',
 CDS_LIB='pure_quanta',
 CDS_PART_NAME='Q_CAP_C0805-10UF,16V,10%,X6S,CA',
 TOLERANCE='10%',
 MATERIAL='X6S',
 VOLTAGE='16V',
 VALUE='10UF',
 PRIM_FILE='./archive_libs/logical/q_cap/chips/chips.prt';

PART_NAME
 C98 'Q_CAP_C0805-10UF,16V,10%,X6S,CA':;

SECTION_NUMBER 1
 '@S9S_MB_2U_LIB.S9S_MB_2U(SCH_1):PAGE105_I146@PURE_QUANTA.Q_CAP(CHIPS)':
 C_PATH='@s9s_mb_2u_lib.s9s_mb_2u(sch_1):page105_i146@pure_quanta.q_cap(chips)',
 P_PATH='@s9s_mb_2u_lib.s9s_mb_2u(sch_1):page105_i146@pure_quanta.q_cap(chips)',
 PATH='I146',
 DRAWING='@S9S_MB_2U_LIB.S9S_MB_2U(SCH_1):PAGE105',
 PHYS_PAGE='105',
 XY='(2150,400)',
 ROT='0',
 VER='1',
 PACK_TYPE='C0805',
 CDS_LIB='pure_quanta',
 CDS_PART_NAME='Q_CAP_C0805-10UF,16V,10%,X6S,CA',
 TOLERANCE='10%',
 MATERIAL='X6S',
 VOLTAGE='16V',
 VALUE='10UF',
 PRIM_FILE='./archive_libs/logical/q_cap/chips/chips.prt';

PART_NAME
 C101 'Q_CAP_C0805-47UF,4V,20%,X6S,CHA':;

SECTION_NUMBER 1
 '@S9S_MB_2U_LIB.S9S_MB_2U(SCH_1):PAGE74_I13@PURE_QUANTA.Q_CAP(CHIPS)':
 C_PATH='@s9s_mb_2u_lib.s9s_mb_2u(sch_1):page74_i13@pure_quanta.q_cap(chips)',
 P_PATH='@s9s_mb_2u_lib.s9s_mb_2u(sch_1):page74_i13@pure_quanta.q_cap(chips)',
 PATH='I13',
 DRAWING='@S9S_MB_2U_LIB.S9S_MB_2U(SCH_1):PAGE74',
 PHYS_PAGE='74',
 XY='(-4250,-50)',
 ROT='0',
 VER='1',
 PACK_TYPE='C0805',
 CDS_LIB='pure_quanta',
 CDS_PART_NAME='Q_CAP_C0805-47UF,4V,20%,X6S,CHA',
 TOLERANCE='20%',
 MATERIAL='X6S',
 VOLTAGE='4V',
 VALUE='47UF',
 PRIM_FILE='./archive_libs/logical/q_cap/chips/chips.prt';

PART_NAME
 C103 'Q_CAP_0402-27PF  ,50V ,5% ,EMPA':;

SECTION_NUMBER 1
 '@S9S_MB_2U_LIB.S9S_MB_2U(SCH_1):PAGE171_I77@PURE_QUANTA.Q_CAP(CHIPS)':
 C_PATH='@s9s_mb_2u_lib.s9s_mb_2u(sch_1):page171_i77@pure_quanta.q_cap(chips)',
 P_PATH='@s9s_mb_2u_lib.s9s_mb_2u(sch_1):page179_i77@pure_quanta.q_cap(chips)',
 PATH='I77',
 DRAWING='@S9S_MB_2U_LIB.S9S_MB_2U(SCH_1):PAGE171',
 PHYS_PAGE='179',
 XY='(-1300,-775)',
 ROT='2',
 VER='1',
 PACK_TYPE='0402',
 CDS_LIB='pure_quanta',
 CDS_PART_NAME='Q_CAP_0402-27PF  ,50V ,5% ,EMPA',
 TOLERANCE='5% ',
 MATERIAL='EMPTY',
 VOLTAGE='50V ',
 VALUE='27PF  ',
 PRIM_FILE='./archive_libs/logical/q_cap/chips/chips.prt';

PART_NAME
 C104 'Q_CAP_0402-27PF  ,50V ,5% ,EMPA':;

SECTION_NUMBER 1
 '@S9S_MB_2U_LIB.S9S_MB_2U(SCH_1):PAGE171_I76@PURE_QUANTA.Q_CAP(CHIPS)':
 C_PATH='@s9s_mb_2u_lib.s9s_mb_2u(sch_1):page171_i76@pure_quanta.q_cap(chips)',
 P_PATH='@s9s_mb_2u_lib.s9s_mb_2u(sch_1):page179_i76@pure_quanta.q_cap(chips)',
 PATH='I76',
 DRAWING='@S9S_MB_2U_LIB.S9S_MB_2U(SCH_1):PAGE171',
 PHYS_PAGE='179',
 XY='(-375,-775)',
 ROT='0',
 VER='1',
 PACK_TYPE='0402',
 CDS_LIB='pure_quanta',
 CDS_PART_NAME='Q_CAP_0402-27PF  ,50V ,5% ,EMPA',
 TOLERANCE='5% ',
 MATERIAL='EMPTY',
 VOLTAGE='50V ',
 VALUE='27PF  ',
 PRIM_FILE='./archive_libs/logical/q_cap/chips/chips.prt';

PART_NAME
 C107 'Q_CAP_C0402-1UF,25V,10%,X6S,CHA':;

SECTION_NUMBER 1
 '@S9S_MB_2U_LIB.S9S_MB_2U(SCH_1):PAGE199_I82@PURE_QUANTA.Q_CAP(CHIPS)':
 C_PATH='@s9s_mb_2u_lib.s9s_mb_2u(sch_1):page199_i82@pure_quanta.q_cap(chips)',
 P_PATH='@s9s_mb_2u_lib.s9s_mb_2u(sch_1):page210_i82@pure_quanta.q_cap(chips)',
 PATH='I82',
 DRAWING='@S9S_MB_2U_LIB.S9S_MB_2U(SCH_1):PAGE199',
 BOM_COST='VR_SYSTEM ',
 PHYS_PAGE='210',
 XY='(-11500,7450)',
 ROT='0',
 VER='1',
 PACK_TYPE='C0402',
 LOCATION='C107',
 CDS_LIB='pure_quanta',
 CDS_PART_NAME='Q_CAP_C0402-1UF,25V,10%,X6S,CHA',
 TOLERANCE='10%',
 MATERIAL='X6S',
 VOLTAGE='25V',
 VALUE='1UF',
 PRIM_FILE='./archive_libs/logical/q_cap/chips/chips.prt';

PART_NAME
 C108 'Q_CAP_C0603-10UF,6.3V,20%,X6S,A':;

SECTION_NUMBER 1
 '@S9S_MB_2U_LIB.S9S_MB_2U(SCH_1):PAGE199_I19@PURE_QUANTA.Q_CAP(CHIPS)':
 C_PATH='@s9s_mb_2u_lib.s9s_mb_2u(sch_1):page199_i19@pure_quanta.q_cap(chips)',
 P_PATH='@s9s_mb_2u_lib.s9s_mb_2u(sch_1):page210_i19@pure_quanta.q_cap(chips)',
 PATH='I19',
 DRAWING='@S9S_MB_2U_LIB.S9S_MB_2U(SCH_1):PAGE199',
 PHYS_PAGE='210',
 XY='(-11850,7450)',
 ROT='0',
 VER='1',
 PACK_TYPE='C0603',
 CDS_LIB='pure_quanta',
 CDS_PART_NAME='Q_CAP_C0603-10UF,6.3V,20%,X6S,A',
 TOLERANCE='20%',
 MATERIAL='X6S',
 VOLTAGE='6.3V',
 VALUE='10UF',
 PRIM_FILE='./archive_libs/logical/q_cap/chips/chips.prt';

PART_NAME
 C110 'Q_CAP_C0402-0.047UF,25V,10%,X7A':;

SECTION_NUMBER 1
 '@S9S_MB_2U_LIB.S9S_MB_2U(SCH_1):PAGE199_I76@PURE_QUANTA.Q_CAP(CHIPS)':
 C_PATH='@s9s_mb_2u_lib.s9s_mb_2u(sch_1):page199_i76@pure_quanta.q_cap(chips)',
 P_PATH='@s9s_mb_2u_lib.s9s_mb_2u(sch_1):page210_i76@pure_quanta.q_cap(chips)',
 PATH='I76',
 DRAWING='@S9S_MB_2U_LIB.S9S_MB_2U(SCH_1):PAGE199',
 PHYS_PAGE='210',
 XY='(-11150,7450)',
 ROT='0',
 VER='1',
 PACK_TYPE='C0402',
 LOCATION='C110',
 CDS_LIB='pure_quanta',
 CDS_PART_NAME='Q_CAP_C0402-0.047UF,25V,10%,X7A',
 TOLERANCE='10%',
 MATERIAL='X7R',
 VOLTAGE='25V',
 VALUE='0.047UF',
 PRIM_FILE='./archive_libs/logical/q_cap/chips/chips.prt';

PART_NAME
 C111 'Q_CAP_C0402-0.047UF,25V,10%,X7A':;

SECTION_NUMBER 1
 '@S9S_MB_2U_LIB.S9S_MB_2U(SCH_1):PAGE199_I81@PURE_QUANTA.Q_CAP(CHIPS)':
 C_PATH='@s9s_mb_2u_lib.s9s_mb_2u(sch_1):page199_i81@pure_quanta.q_cap(chips)',
 P_PATH='@s9s_mb_2u_lib.s9s_mb_2u(sch_1):page210_i81@pure_quanta.q_cap(chips)',
 PATH='I81',
 DRAWING='@S9S_MB_2U_LIB.S9S_MB_2U(SCH_1):PAGE199',
 PHYS_PAGE='210',
 XY='(-11150,6225)',
 ROT='0',
 VER='1',
 PACK_TYPE='C0402',
 LOCATION='C111',
 CDS_LIB='pure_quanta',
 CDS_PART_NAME='Q_CAP_C0402-0.047UF,25V,10%,X7A',
 TOLERANCE='10%',
 MATERIAL='X7R',
 VOLTAGE='25V',
 VALUE='0.047UF',
 PRIM_FILE='./archive_libs/logical/q_cap/chips/chips.prt';

PART_NAME
 C112 'Q_CAP_C0402-0.047UF,25V,10%,X7A':;

SECTION_NUMBER 1
 '@S9S_MB_2U_LIB.S9S_MB_2U(SCH_1):PAGE199_I80@PURE_QUANTA.Q_CAP(CHIPS)':
 C_PATH='@s9s_mb_2u_lib.s9s_mb_2u(sch_1):page199_i80@pure_quanta.q_cap(chips)',
 P_PATH='@s9s_mb_2u_lib.s9s_mb_2u(sch_1):page210_i80@pure_quanta.q_cap(chips)',
 PATH='I80',
 DRAWING='@S9S_MB_2U_LIB.S9S_MB_2U(SCH_1):PAGE199',
 PHYS_PAGE='210',
 XY='(-10900,6225)',
 ROT='0',
 VER='1',
 PACK_TYPE='C0402',
 LOCATION='C112',
 CDS_LIB='pure_quanta',
 CDS_PART_NAME='Q_CAP_C0402-0.047UF,25V,10%,X7A',
 TOLERANCE='10%',
 MATERIAL='X7R',
 VOLTAGE='25V',
 VALUE='0.047UF',
 PRIM_FILE='./archive_libs/logical/q_cap/chips/chips.prt';

PART_NAME
 C114 'Q_CAP_C0402-0.047UF,25V,10%,X7A':;

SECTION_NUMBER 1
 '@S9S_MB_2U_LIB.S9S_MB_2U(SCH_1):PAGE199_I79@PURE_QUANTA.Q_CAP(CHIPS)':
 C_PATH='@s9s_mb_2u_lib.s9s_mb_2u(sch_1):page199_i79@pure_quanta.q_cap(chips)',
 P_PATH='@s9s_mb_2u_lib.s9s_mb_2u(sch_1):page210_i79@pure_quanta.q_cap(chips)',
 PATH='I79',
 DRAWING='@S9S_MB_2U_LIB.S9S_MB_2U(SCH_1):PAGE199',
 PHYS_PAGE='210',
 XY='(-8850,6225)',
 ROT='0',
 VER='1',
 PACK_TYPE='C0402',
 LOCATION='C114',
 CDS_LIB='pure_quanta',
 CDS_PART_NAME='Q_CAP_C0402-0.047UF,25V,10%,X7A',
 TOLERANCE='10%',
 MATERIAL='X7R',
 VOLTAGE='25V',
 VALUE='0.047UF',
 PRIM_FILE='./archive_libs/logical/q_cap/chips/chips.prt';

PART_NAME
 C115 'Q_CAP_C0402-0.047UF,25V,10%,X7A':;

SECTION_NUMBER 1
 '@S9S_MB_2U_LIB.S9S_MB_2U(SCH_1):PAGE199_I89@PURE_QUANTA.Q_CAP(CHIPS)':
 C_PATH='@s9s_mb_2u_lib.s9s_mb_2u(sch_1):page199_i89@pure_quanta.q_cap(chips)',
 P_PATH='@s9s_mb_2u_lib.s9s_mb_2u(sch_1):page210_i89@pure_quanta.q_cap(chips)',
 PATH='I89',
 DRAWING='@S9S_MB_2U_LIB.S9S_MB_2U(SCH_1):PAGE199',
 PHYS_PAGE='210',
 XY='(-11150,4925)',
 ROT='0',
 VER='1',
 PACK_TYPE='C0402',
 LOCATION='C115',
 CDS_LIB='pure_quanta',
 CDS_PART_NAME='Q_CAP_C0402-0.047UF,25V,10%,X7A',
 TOLERANCE='10%',
 MATERIAL='X7R',
 VOLTAGE='25V',
 VALUE='0.047UF',
 PRIM_FILE='./archive_libs/logical/q_cap/chips/chips.prt';

PART_NAME
 C116 'Q_CAP_C0402-0.047UF,25V,10%,X7A':;

SECTION_NUMBER 1
 '@S9S_MB_2U_LIB.S9S_MB_2U(SCH_1):PAGE199_I88@PURE_QUANTA.Q_CAP(CHIPS)':
 C_PATH='@s9s_mb_2u_lib.s9s_mb_2u(sch_1):page199_i88@pure_quanta.q_cap(chips)',
 P_PATH='@s9s_mb_2u_lib.s9s_mb_2u(sch_1):page210_i88@pure_quanta.q_cap(chips)',
 PATH='I88',
 DRAWING='@S9S_MB_2U_LIB.S9S_MB_2U(SCH_1):PAGE199',
 PHYS_PAGE='210',
 XY='(-10900,4925)',
 ROT='0',
 VER='1',
 PACK_TYPE='C0402',
 LOCATION='C116',
 CDS_LIB='pure_quanta',
 CDS_PART_NAME='Q_CAP_C0402-0.047UF,25V,10%,X7A',
 TOLERANCE='10%',
 MATERIAL='X7R',
 VOLTAGE='25V',
 VALUE='0.047UF',
 PRIM_FILE='./archive_libs/logical/q_cap/chips/chips.prt';

PART_NAME
 C117 'Q_CAP_C0402-0.047UF,25V,10%,X7A':;

SECTION_NUMBER 1
 '@S9S_MB_2U_LIB.S9S_MB_2U(SCH_1):PAGE199_I87@PURE_QUANTA.Q_CAP(CHIPS)':
 C_PATH='@s9s_mb_2u_lib.s9s_mb_2u(sch_1):page199_i87@pure_quanta.q_cap(chips)',
 P_PATH='@s9s_mb_2u_lib.s9s_mb_2u(sch_1):page210_i87@pure_quanta.q_cap(chips)',
 PATH='I87',
 DRAWING='@S9S_MB_2U_LIB.S9S_MB_2U(SCH_1):PAGE199',
 PHYS_PAGE='210',
 XY='(-10650,4925)',
 ROT='0',
 VER='1',
 PACK_TYPE='C0402',
 LOCATION='C117',
 CDS_LIB='pure_quanta',
 CDS_PART_NAME='Q_CAP_C0402-0.047UF,25V,10%,X7A',
 TOLERANCE='10%',
 MATERIAL='X7R',
 VOLTAGE='25V',
 VALUE='0.047UF',
 PRIM_FILE='./archive_libs/logical/q_cap/chips/chips.prt';

PART_NAME
 C119 'Q_CAP_C0402-0.047UF,25V,10%,X7A':;

SECTION_NUMBER 1
 '@S9S_MB_2U_LIB.S9S_MB_2U(SCH_1):PAGE199_I86@PURE_QUANTA.Q_CAP(CHIPS)':
 C_PATH='@s9s_mb_2u_lib.s9s_mb_2u(sch_1):page199_i86@pure_quanta.q_cap(chips)',
 P_PATH='@s9s_mb_2u_lib.s9s_mb_2u(sch_1):page210_i86@pure_quanta.q_cap(chips)',
 PATH='I86',
 DRAWING='@S9S_MB_2U_LIB.S9S_MB_2U(SCH_1):PAGE199',
 PHYS_PAGE='210',
 XY='(-10400,4925)',
 ROT='0',
 VER='1',
 PACK_TYPE='C0402',
 LOCATION='C119',
 CDS_LIB='pure_quanta',
 CDS_PART_NAME='Q_CAP_C0402-0.047UF,25V,10%,X7A',
 TOLERANCE='10%',
 MATERIAL='X7R',
 VOLTAGE='25V',
 VALUE='0.047UF',
 PRIM_FILE='./archive_libs/logical/q_cap/chips/chips.prt';

PART_NAME
 C120 'Q_CAP_C0402-0.047UF,25V,10%,X7A':;

SECTION_NUMBER 1
 '@S9S_MB_2U_LIB.S9S_MB_2U(SCH_1):PAGE199_I85@PURE_QUANTA.Q_CAP(CHIPS)':
 C_PATH='@s9s_mb_2u_lib.s9s_mb_2u(sch_1):page199_i85@pure_quanta.q_cap(chips)',
 P_PATH='@s9s_mb_2u_lib.s9s_mb_2u(sch_1):page210_i85@pure_quanta.q_cap(chips)',
 PATH='I85',
 DRAWING='@S9S_MB_2U_LIB.S9S_MB_2U(SCH_1):PAGE199',
 PHYS_PAGE='210',
 XY='(-8850,4925)',
 ROT='0',
 VER='1',
 PACK_TYPE='C0402',
 LOCATION='C120',
 CDS_LIB='pure_quanta',
 CDS_PART_NAME='Q_CAP_C0402-0.047UF,25V,10%,X7A',
 TOLERANCE='10%',
 MATERIAL='X7R',
 VOLTAGE='25V',
 VALUE='0.047UF',
 PRIM_FILE='./archive_libs/logical/q_cap/chips/chips.prt';

PART_NAME
 C139 'Q_CAP_DIFFBUS_C0201-DIFF BUS_0A':;

SECTION_NUMBER 1
 '@S9S_MB_2U_LIB.S9S_MB_2U(SCH_1):PAGE169_I35@PURE_QUANTA.Q_CAP_DIFFBUS(CHIPS)':
 C_PATH='@s9s_mb_2u_lib.s9s_mb_2u(sch_1):page169_i35@pure_quanta.q_cap_diffbus(c~
hips)',
 P_PATH='@s9s_mb_2u_lib.s9s_mb_2u(sch_1):page178_i35@pure_quanta.q_cap_diffbus(c~
hips)',
 PATH='I35',
 DRAWING='@S9S_MB_2U_LIB.S9S_MB_2U(SCH_1):PAGE169',
 PIN_NAMES_ROTATE='TRUE',
 PHYS_PAGE='178',
 XY='(-725,1575)',
 ROT='2',
 VER='2',
 PACK_TYPE='C0201',
 CDS_LIB='pure_quanta',
 CDS_PART_NAME='Q_CAP_DIFFBUS_C0201-DIFF BUS_0A',
 TOLERANCE='20%',
 MATERIAL='X6S',
 VOLTAGE='6.3V',
 VALUE='DIFF BUS_0.22UF',
 PRIM_FILE='./archive_libs/logical/q_cap_diffbus/chips/chips.prt';

PART_NAME
 C141 'Q_CAP_DIFFBUS_C0201-DIFF BUS_0A':;

SECTION_NUMBER 1
 '@S9S_MB_2U_LIB.S9S_MB_2U(SCH_1):PAGE169_I34@PURE_QUANTA.Q_CAP_DIFFBUS(CHIPS)':
 C_PATH='@s9s_mb_2u_lib.s9s_mb_2u(sch_1):page169_i34@pure_quanta.q_cap_diffbus(c~
hips)',
 P_PATH='@s9s_mb_2u_lib.s9s_mb_2u(sch_1):page178_i34@pure_quanta.q_cap_diffbus(c~
hips)',
 PATH='I34',
 DRAWING='@S9S_MB_2U_LIB.S9S_MB_2U(SCH_1):PAGE169',
 PIN_NAMES_ROTATE='TRUE',
 PHYS_PAGE='178',
 XY='(-725,1375)',
 ROT='2',
 VER='2',
 PACK_TYPE='C0201',
 CDS_LIB='pure_quanta',
 CDS_PART_NAME='Q_CAP_DIFFBUS_C0201-DIFF BUS_0A',
 TOLERANCE='20%',
 MATERIAL='X6S',
 VOLTAGE='6.3V',
 VALUE='DIFF BUS_0.22UF',
 PRIM_FILE='./archive_libs/logical/q_cap_diffbus/chips/chips.prt';

PART_NAME
 C142 'Q_CAP_DIFFBUS_C0201-DIFF BUS_0A':;

SECTION_NUMBER 1
 '@S9S_MB_2U_LIB.S9S_MB_2U(SCH_1):PAGE169_I33@PURE_QUANTA.Q_CAP_DIFFBUS(CHIPS)':
 C_PATH='@s9s_mb_2u_lib.s9s_mb_2u(sch_1):page169_i33@pure_quanta.q_cap_diffbus(c~
hips)',
 P_PATH='@s9s_mb_2u_lib.s9s_mb_2u(sch_1):page178_i33@pure_quanta.q_cap_diffbus(c~
hips)',
 PATH='I33',
 DRAWING='@S9S_MB_2U_LIB.S9S_MB_2U(SCH_1):PAGE169',
 PIN_NAMES_ROTATE='TRUE',
 PHYS_PAGE='178',
 XY='(-725,1325)',
 ROT='2',
 VER='2',
 PACK_TYPE='C0201',
 CDS_LIB='pure_quanta',
 CDS_PART_NAME='Q_CAP_DIFFBUS_C0201-DIFF BUS_0A',
 TOLERANCE='20%',
 MATERIAL='X6S',
 VOLTAGE='6.3V',
 VALUE='DIFF BUS_0.22UF',
 PRIM_FILE='./archive_libs/logical/q_cap_diffbus/chips/chips.prt';

PART_NAME
 C143 'Q_CAP_DIFFBUS_C0201-DIFF BUS_0A':;

SECTION_NUMBER 1
 '@S9S_MB_2U_LIB.S9S_MB_2U(SCH_1):PAGE169_I32@PURE_QUANTA.Q_CAP_DIFFBUS(CHIPS)':
 C_PATH='@s9s_mb_2u_lib.s9s_mb_2u(sch_1):page169_i32@pure_quanta.q_cap_diffbus(c~
hips)',
 P_PATH='@s9s_mb_2u_lib.s9s_mb_2u(sch_1):page178_i32@pure_quanta.q_cap_diffbus(c~
hips)',
 PATH='I32',
 DRAWING='@S9S_MB_2U_LIB.S9S_MB_2U(SCH_1):PAGE169',
 PIN_NAMES_ROTATE='TRUE',
 PHYS_PAGE='178',
 XY='(-725,1175)',
 ROT='2',
 VER='2',
 PACK_TYPE='C0201',
 CDS_LIB='pure_quanta',
 CDS_PART_NAME='Q_CAP_DIFFBUS_C0201-DIFF BUS_0A',
 TOLERANCE='20%',
 MATERIAL='X6S',
 VOLTAGE='6.3V',
 VALUE='DIFF BUS_0.22UF',
 PRIM_FILE='./archive_libs/logical/q_cap_diffbus/chips/chips.prt';

PART_NAME
 C144 'Q_CAP_DIFFBUS_C0201-DIFF BUS_0A':;

SECTION_NUMBER 1
 '@S9S_MB_2U_LIB.S9S_MB_2U(SCH_1):PAGE169_I31@PURE_QUANTA.Q_CAP_DIFFBUS(CHIPS)':
 C_PATH='@s9s_mb_2u_lib.s9s_mb_2u(sch_1):page169_i31@pure_quanta.q_cap_diffbus(c~
hips)',
 P_PATH='@s9s_mb_2u_lib.s9s_mb_2u(sch_1):page178_i31@pure_quanta.q_cap_diffbus(c~
hips)',
 PATH='I31',
 DRAWING='@S9S_MB_2U_LIB.S9S_MB_2U(SCH_1):PAGE169',
 PIN_NAMES_ROTATE='TRUE',
 PHYS_PAGE='178',
 XY='(-725,1125)',
 ROT='2',
 VER='2',
 PACK_TYPE='C0201',
 CDS_LIB='pure_quanta',
 CDS_PART_NAME='Q_CAP_DIFFBUS_C0201-DIFF BUS_0A',
 TOLERANCE='20%',
 MATERIAL='X6S',
 VOLTAGE='6.3V',
 VALUE='DIFF BUS_0.22UF',
 PRIM_FILE='./archive_libs/logical/q_cap_diffbus/chips/chips.prt';

PART_NAME
 C145 'Q_CAP_DIFFBUS_C0201-DIFF BUS_0A':;

SECTION_NUMBER 1
 '@S9S_MB_2U_LIB.S9S_MB_2U(SCH_1):PAGE169_I30@PURE_QUANTA.Q_CAP_DIFFBUS(CHIPS)':
 C_PATH='@s9s_mb_2u_lib.s9s_mb_2u(sch_1):page169_i30@pure_quanta.q_cap_diffbus(c~
hips)',
 P_PATH='@s9s_mb_2u_lib.s9s_mb_2u(sch_1):page178_i30@pure_quanta.q_cap_diffbus(c~
hips)',
 PATH='I30',
 DRAWING='@S9S_MB_2U_LIB.S9S_MB_2U(SCH_1):PAGE169',
 PIN_NAMES_ROTATE='TRUE',
 PHYS_PAGE='178',
 XY='(-725,975)',
 ROT='2',
 VER='2',
 PACK_TYPE='C0201',
 CDS_LIB='pure_quanta',
 CDS_PART_NAME='Q_CAP_DIFFBUS_C0201-DIFF BUS_0A',
 TOLERANCE='20%',
 MATERIAL='X6S',
 VOLTAGE='6.3V',
 VALUE='DIFF BUS_0.22UF',
 PRIM_FILE='./archive_libs/logical/q_cap_diffbus/chips/chips.prt';

PART_NAME
 C146 'Q_CAP_DIFFBUS_C0201-DIFF BUS_0A':;

SECTION_NUMBER 1
 '@S9S_MB_2U_LIB.S9S_MB_2U(SCH_1):PAGE169_I29@PURE_QUANTA.Q_CAP_DIFFBUS(CHIPS)':
 C_PATH='@s9s_mb_2u_lib.s9s_mb_2u(sch_1):page169_i29@pure_quanta.q_cap_diffbus(c~
hips)',
 P_PATH='@s9s_mb_2u_lib.s9s_mb_2u(sch_1):page178_i29@pure_quanta.q_cap_diffbus(c~
hips)',
 PATH='I29',
 DRAWING='@S9S_MB_2U_LIB.S9S_MB_2U(SCH_1):PAGE169',
 PIN_NAMES_ROTATE='TRUE',
 PHYS_PAGE='178',
 XY='(-725,925)',
 ROT='2',
 VER='2',
 PACK_TYPE='C0201',
 CDS_LIB='pure_quanta',
 CDS_PART_NAME='Q_CAP_DIFFBUS_C0201-DIFF BUS_0A',
 TOLERANCE='20%',
 MATERIAL='X6S',
 VOLTAGE='6.3V',
 VALUE='DIFF BUS_0.22UF',
 PRIM_FILE='./archive_libs/logical/q_cap_diffbus/chips/chips.prt';

PART_NAME
 C147 'Q_CAP_DIFFBUS_C0201-DIFF BUS_0A':;

SECTION_NUMBER 1
 '@S9S_MB_2U_LIB.S9S_MB_2U(SCH_1):PAGE169_I28@PURE_QUANTA.Q_CAP_DIFFBUS(CHIPS)':
 C_PATH='@s9s_mb_2u_lib.s9s_mb_2u(sch_1):page169_i28@pure_quanta.q_cap_diffbus(c~
hips)',
 P_PATH='@s9s_mb_2u_lib.s9s_mb_2u(sch_1):page178_i28@pure_quanta.q_cap_diffbus(c~
hips)',
 PATH='I28',
 DRAWING='@S9S_MB_2U_LIB.S9S_MB_2U(SCH_1):PAGE169',
 PIN_NAMES_ROTATE='TRUE',
 PHYS_PAGE='178',
 XY='(-725,775)',
 ROT='2',
 VER='2',
 PACK_TYPE='C0201',
 CDS_LIB='pure_quanta',
 CDS_PART_NAME='Q_CAP_DIFFBUS_C0201-DIFF BUS_0A',
 TOLERANCE='20%',
 MATERIAL='X6S',
 VOLTAGE='6.3V',
 VALUE='DIFF BUS_0.22UF',
 PRIM_FILE='./archive_libs/logical/q_cap_diffbus/chips/chips.prt';

PART_NAME
 C148 'Q_CAP_DIFFBUS_C0201-DIFF BUS_0A':;

SECTION_NUMBER 1
 '@S9S_MB_2U_LIB.S9S_MB_2U(SCH_1):PAGE169_I27@PURE_QUANTA.Q_CAP_DIFFBUS(CHIPS)':
 C_PATH='@s9s_mb_2u_lib.s9s_mb_2u(sch_1):page169_i27@pure_quanta.q_cap_diffbus(c~
hips)',
 P_PATH='@s9s_mb_2u_lib.s9s_mb_2u(sch_1):page178_i27@pure_quanta.q_cap_diffbus(c~
hips)',
 PATH='I27',
 DRAWING='@S9S_MB_2U_LIB.S9S_MB_2U(SCH_1):PAGE169',
 PIN_NAMES_ROTATE='TRUE',
 PHYS_PAGE='178',
 XY='(-725,725)',
 ROT='2',
 VER='2',
 PACK_TYPE='C0201',
 CDS_LIB='pure_quanta',
 CDS_PART_NAME='Q_CAP_DIFFBUS_C0201-DIFF BUS_0A',
 TOLERANCE='20%',
 MATERIAL='X6S',
 VOLTAGE='6.3V',
 VALUE='DIFF BUS_0.22UF',
 PRIM_FILE='./archive_libs/logical/q_cap_diffbus/chips/chips.prt';

PART_NAME
 C149 'Q_CAP_DIFFBUS_C0201-DIFF BUS_0A':;

SECTION_NUMBER 1
 '@S9S_MB_2U_LIB.S9S_MB_2U(SCH_1):PAGE169_I25@PURE_QUANTA.Q_CAP_DIFFBUS(CHIPS)':
 C_PATH='@s9s_mb_2u_lib.s9s_mb_2u(sch_1):page169_i25@pure_quanta.q_cap_diffbus(c~
hips)',
 P_PATH='@s9s_mb_2u_lib.s9s_mb_2u(sch_1):page178_i25@pure_quanta.q_cap_diffbus(c~
hips)',
 PATH='I25',
 DRAWING='@S9S_MB_2U_LIB.S9S_MB_2U(SCH_1):PAGE169',
 PIN_NAMES_ROTATE='TRUE',
 PHYS_PAGE='178',
 XY='(-725,575)',
 ROT='2',
 VER='2',
 PACK_TYPE='C0201',
 CDS_LIB='pure_quanta',
 CDS_PART_NAME='Q_CAP_DIFFBUS_C0201-DIFF BUS_0A',
 TOLERANCE='20%',
 MATERIAL='X6S',
 VOLTAGE='6.3V',
 VALUE='DIFF BUS_0.22UF',
 PRIM_FILE='./archive_libs/logical/q_cap_diffbus/chips/chips.prt';

PART_NAME
 C150 'Q_CAP_DIFFBUS_C0201-DIFF BUS_0A':;

SECTION_NUMBER 1
 '@S9S_MB_2U_LIB.S9S_MB_2U(SCH_1):PAGE169_I26@PURE_QUANTA.Q_CAP_DIFFBUS(CHIPS)':
 C_PATH='@s9s_mb_2u_lib.s9s_mb_2u(sch_1):page169_i26@pure_quanta.q_cap_diffbus(c~
hips)',
 P_PATH='@s9s_mb_2u_lib.s9s_mb_2u(sch_1):page178_i26@pure_quanta.q_cap_diffbus(c~
hips)',
 PATH='I26',
 DRAWING='@S9S_MB_2U_LIB.S9S_MB_2U(SCH_1):PAGE169',
 PIN_NAMES_ROTATE='TRUE',
 PHYS_PAGE='178',
 XY='(-725,525)',
 ROT='2',
 VER='2',
 PACK_TYPE='C0201',
 CDS_LIB='pure_quanta',
 CDS_PART_NAME='Q_CAP_DIFFBUS_C0201-DIFF BUS_0A',
 TOLERANCE='20%',
 MATERIAL='X6S',
 VOLTAGE='6.3V',
 VALUE='DIFF BUS_0.22UF',
 PRIM_FILE='./archive_libs/logical/q_cap_diffbus/chips/chips.prt';

PART_NAME
 C151 'Q_CAP_DIFFBUS_C0201-DIFF BUS_0A':;

SECTION_NUMBER 1
 '@S9S_MB_2U_LIB.S9S_MB_2U(SCH_1):PAGE169_I24@PURE_QUANTA.Q_CAP_DIFFBUS(CHIPS)':
 C_PATH='@s9s_mb_2u_lib.s9s_mb_2u(sch_1):page169_i24@pure_quanta.q_cap_diffbus(c~
hips)',
 P_PATH='@s9s_mb_2u_lib.s9s_mb_2u(sch_1):page178_i24@pure_quanta.q_cap_diffbus(c~
hips)',
 PATH='I24',
 DRAWING='@S9S_MB_2U_LIB.S9S_MB_2U(SCH_1):PAGE169',
 PIN_NAMES_ROTATE='TRUE',
 PHYS_PAGE='178',
 XY='(-725,375)',
 ROT='2',
 VER='2',
 PACK_TYPE='C0201',
 CDS_LIB='pure_quanta',
 CDS_PART_NAME='Q_CAP_DIFFBUS_C0201-DIFF BUS_0A',
 TOLERANCE='20%',
 MATERIAL='X6S',
 VOLTAGE='6.3V',
 VALUE='DIFF BUS_0.22UF',
 PRIM_FILE='./archive_libs/logical/q_cap_diffbus/chips/chips.prt';

PART_NAME
 C152 'Q_CAP_DIFFBUS_C0201-DIFF BUS_0A':;

SECTION_NUMBER 1
 '@S9S_MB_2U_LIB.S9S_MB_2U(SCH_1):PAGE169_I23@PURE_QUANTA.Q_CAP_DIFFBUS(CHIPS)':
 C_PATH='@s9s_mb_2u_lib.s9s_mb_2u(sch_1):page169_i23@pure_quanta.q_cap_diffbus(c~
hips)',
 P_PATH='@s9s_mb_2u_lib.s9s_mb_2u(sch_1):page178_i23@pure_quanta.q_cap_diffbus(c~
hips)',
 PATH='I23',
 DRAWING='@S9S_MB_2U_LIB.S9S_MB_2U(SCH_1):PAGE169',
 PIN_NAMES_ROTATE='TRUE',
 PHYS_PAGE='178',
 XY='(-725,325)',
 ROT='2',
 VER='2',
 PACK_TYPE='C0201',
 CDS_LIB='pure_quanta',
 CDS_PART_NAME='Q_CAP_DIFFBUS_C0201-DIFF BUS_0A',
 TOLERANCE='20%',
 MATERIAL='X6S',
 VOLTAGE='6.3V',
 VALUE='DIFF BUS_0.22UF',
 PRIM_FILE='./archive_libs/logical/q_cap_diffbus/chips/chips.prt';

PART_NAME
 C153 'Q_CAP_DIFFBUS_C0201-DIFF BUS_0A':;

SECTION_NUMBER 1
 '@S9S_MB_2U_LIB.S9S_MB_2U(SCH_1):PAGE169_I21@PURE_QUANTA.Q_CAP_DIFFBUS(CHIPS)':
 C_PATH='@s9s_mb_2u_lib.s9s_mb_2u(sch_1):page169_i21@pure_quanta.q_cap_diffbus(c~
hips)',
 P_PATH='@s9s_mb_2u_lib.s9s_mb_2u(sch_1):page178_i21@pure_quanta.q_cap_diffbus(c~
hips)',
 PATH='I21',
 DRAWING='@S9S_MB_2U_LIB.S9S_MB_2U(SCH_1):PAGE169',
 PIN_NAMES_ROTATE='TRUE',
 PHYS_PAGE='178',
 XY='(-725,175)',
 ROT='2',
 VER='2',
 PACK_TYPE='C0201',
 CDS_LIB='pure_quanta',
 CDS_PART_NAME='Q_CAP_DIFFBUS_C0201-DIFF BUS_0A',
 TOLERANCE='20%',
 MATERIAL='X6S',
 VOLTAGE='6.3V',
 VALUE='DIFF BUS_0.22UF',
 PRIM_FILE='./archive_libs/logical/q_cap_diffbus/chips/chips.prt';

PART_NAME
 C154 'Q_CAP_DIFFBUS_C0201-DIFF BUS_0A':;

SECTION_NUMBER 1
 '@S9S_MB_2U_LIB.S9S_MB_2U(SCH_1):PAGE169_I22@PURE_QUANTA.Q_CAP_DIFFBUS(CHIPS)':
 C_PATH='@s9s_mb_2u_lib.s9s_mb_2u(sch_1):page169_i22@pure_quanta.q_cap_diffbus(c~
hips)',
 P_PATH='@s9s_mb_2u_lib.s9s_mb_2u(sch_1):page178_i22@pure_quanta.q_cap_diffbus(c~
hips)',
 PATH='I22',
 DRAWING='@S9S_MB_2U_LIB.S9S_MB_2U(SCH_1):PAGE169',
 PIN_NAMES_ROTATE='TRUE',
 PHYS_PAGE='178',
 XY='(-725,125)',
 ROT='2',
 VER='2',
 PACK_TYPE='C0201',
 CDS_LIB='pure_quanta',
 CDS_PART_NAME='Q_CAP_DIFFBUS_C0201-DIFF BUS_0A',
 TOLERANCE='20%',
 MATERIAL='X6S',
 VOLTAGE='6.3V',
 VALUE='DIFF BUS_0.22UF',
 PRIM_FILE='./archive_libs/logical/q_cap_diffbus/chips/chips.prt';

PART_NAME
 C155 'Q_CAP_DIFFBUS_C0201-DIFF BUS_0A':;

SECTION_NUMBER 1
 '@S9S_MB_2U_LIB.S9S_MB_2U(SCH_1):PAGE169_I113@PURE_QUANTA.Q_CAP_DIFFBUS(CHIPS)':
 C_PATH='@s9s_mb_2u_lib.s9s_mb_2u(sch_1):page169_i113@pure_quanta.q_cap_diffbus(~
chips)',
 P_PATH='@s9s_mb_2u_lib.s9s_mb_2u(sch_1):page178_i113@pure_quanta.q_cap_diffbus(~
chips)',
 PATH='I113',
 DRAWING='@S9S_MB_2U_LIB.S9S_MB_2U(SCH_1):PAGE169',
 PIN_NAMES_ROTATE='TRUE',
 PHYS_PAGE='178',
 XY='(-725,-1425)',
 ROT='2',
 VER='2',
 PACK_TYPE='C0201',
 CDS_LIB='pure_quanta',
 CDS_PART_NAME='Q_CAP_DIFFBUS_C0201-DIFF BUS_0A',
 TOLERANCE='20%',
 MATERIAL='X6S',
 VOLTAGE='6.3V',
 VALUE='DIFF BUS_0.22UF',
 PRIM_FILE='./archive_libs/logical/q_cap_diffbus/chips/chips.prt';

PART_NAME
 C156 'Q_CAP_DIFFBUS_C0201-DIFF BUS_0A':;

SECTION_NUMBER 1
 '@S9S_MB_2U_LIB.S9S_MB_2U(SCH_1):PAGE169_I114@PURE_QUANTA.Q_CAP_DIFFBUS(CHIPS)':
 C_PATH='@s9s_mb_2u_lib.s9s_mb_2u(sch_1):page169_i114@pure_quanta.q_cap_diffbus(~
chips)',
 P_PATH='@s9s_mb_2u_lib.s9s_mb_2u(sch_1):page178_i114@pure_quanta.q_cap_diffbus(~
chips)',
 PATH='I114',
 DRAWING='@S9S_MB_2U_LIB.S9S_MB_2U(SCH_1):PAGE169',
 PIN_NAMES_ROTATE='TRUE',
 PHYS_PAGE='178',
 XY='(-725,-1475)',
 ROT='2',
 VER='2',
 PACK_TYPE='C0201',
 CDS_LIB='pure_quanta',
 CDS_PART_NAME='Q_CAP_DIFFBUS_C0201-DIFF BUS_0A',
 TOLERANCE='20%',
 MATERIAL='X6S',
 VOLTAGE='6.3V',
 VALUE='DIFF BUS_0.22UF',
 PRIM_FILE='./archive_libs/logical/q_cap_diffbus/chips/chips.prt';

PART_NAME
 C157 'Q_CAP_DIFFBUS_C0201-DIFF BUS_0A':;

SECTION_NUMBER 1
 '@S9S_MB_2U_LIB.S9S_MB_2U(SCH_1):PAGE169_I115@PURE_QUANTA.Q_CAP_DIFFBUS(CHIPS)':
 C_PATH='@s9s_mb_2u_lib.s9s_mb_2u(sch_1):page169_i115@pure_quanta.q_cap_diffbus(~
chips)',
 P_PATH='@s9s_mb_2u_lib.s9s_mb_2u(sch_1):page178_i115@pure_quanta.q_cap_diffbus(~
chips)',
 PATH='I115',
 DRAWING='@S9S_MB_2U_LIB.S9S_MB_2U(SCH_1):PAGE169',
 PIN_NAMES_ROTATE='TRUE',
 PHYS_PAGE='178',
 XY='(-725,-1625)',
 ROT='2',
 VER='2',
 PACK_TYPE='C0201',
 CDS_LIB='pure_quanta',
 CDS_PART_NAME='Q_CAP_DIFFBUS_C0201-DIFF BUS_0A',
 TOLERANCE='20%',
 MATERIAL='X6S',
 VOLTAGE='6.3V',
 VALUE='DIFF BUS_0.22UF',
 PRIM_FILE='./archive_libs/logical/q_cap_diffbus/chips/chips.prt';

PART_NAME
 C158 'Q_CAP_DIFFBUS_C0201-DIFF BUS_0A':;

SECTION_NUMBER 1
 '@S9S_MB_2U_LIB.S9S_MB_2U(SCH_1):PAGE169_I116@PURE_QUANTA.Q_CAP_DIFFBUS(CHIPS)':
 C_PATH='@s9s_mb_2u_lib.s9s_mb_2u(sch_1):page169_i116@pure_quanta.q_cap_diffbus(~
chips)',
 P_PATH='@s9s_mb_2u_lib.s9s_mb_2u(sch_1):page178_i116@pure_quanta.q_cap_diffbus(~
chips)',
 PATH='I116',
 DRAWING='@S9S_MB_2U_LIB.S9S_MB_2U(SCH_1):PAGE169',
 PIN_NAMES_ROTATE='TRUE',
 PHYS_PAGE='178',
 XY='(-725,-1675)',
 ROT='2',
 VER='2',
 PACK_TYPE='C0201',
 CDS_LIB='pure_quanta',
 CDS_PART_NAME='Q_CAP_DIFFBUS_C0201-DIFF BUS_0A',
 TOLERANCE='20%',
 MATERIAL='X6S',
 VOLTAGE='6.3V',
 VALUE='DIFF BUS_0.22UF',
 PRIM_FILE='./archive_libs/logical/q_cap_diffbus/chips/chips.prt';

PART_NAME
 C159 'Q_CAP_DIFFBUS_C0201-DIFF BUS_0A':;

SECTION_NUMBER 1
 '@S9S_MB_2U_LIB.S9S_MB_2U(SCH_1):PAGE169_I117@PURE_QUANTA.Q_CAP_DIFFBUS(CHIPS)':
 C_PATH='@s9s_mb_2u_lib.s9s_mb_2u(sch_1):page169_i117@pure_quanta.q_cap_diffbus(~
chips)',
 P_PATH='@s9s_mb_2u_lib.s9s_mb_2u(sch_1):page178_i117@pure_quanta.q_cap_diffbus(~
chips)',
 PATH='I117',
 DRAWING='@S9S_MB_2U_LIB.S9S_MB_2U(SCH_1):PAGE169',
 PIN_NAMES_ROTATE='TRUE',
 PHYS_PAGE='178',
 XY='(-725,-1825)',
 ROT='2',
 VER='2',
 PACK_TYPE='C0201',
 CDS_LIB='pure_quanta',
 CDS_PART_NAME='Q_CAP_DIFFBUS_C0201-DIFF BUS_0A',
 TOLERANCE='20%',
 MATERIAL='X6S',
 VOLTAGE='6.3V',
 VALUE='DIFF BUS_0.22UF',
 PRIM_FILE='./archive_libs/logical/q_cap_diffbus/chips/chips.prt';

PART_NAME
 C160 'Q_CAP_DIFFBUS_C0201-DIFF BUS_0A':;

SECTION_NUMBER 1
 '@S9S_MB_2U_LIB.S9S_MB_2U(SCH_1):PAGE169_I118@PURE_QUANTA.Q_CAP_DIFFBUS(CHIPS)':
 C_PATH='@s9s_mb_2u_lib.s9s_mb_2u(sch_1):page169_i118@pure_quanta.q_cap_diffbus(~
chips)',
 P_PATH='@s9s_mb_2u_lib.s9s_mb_2u(sch_1):page178_i118@pure_quanta.q_cap_diffbus(~
chips)',
 PATH='I118',
 DRAWING='@S9S_MB_2U_LIB.S9S_MB_2U(SCH_1):PAGE169',
 PIN_NAMES_ROTATE='TRUE',
 PHYS_PAGE='178',
 XY='(-725,-1875)',
 ROT='2',
 VER='2',
 PACK_TYPE='C0201',
 CDS_LIB='pure_quanta',
 CDS_PART_NAME='Q_CAP_DIFFBUS_C0201-DIFF BUS_0A',
 TOLERANCE='20%',
 MATERIAL='X6S',
 VOLTAGE='6.3V',
 VALUE='DIFF BUS_0.22UF',
 PRIM_FILE='./archive_libs/logical/q_cap_diffbus/chips/chips.prt';

PART_NAME
 C161 'Q_CAP_DIFFBUS_C0201-DIFF BUS_0A':;

SECTION_NUMBER 1
 '@S9S_MB_2U_LIB.S9S_MB_2U(SCH_1):PAGE169_I119@PURE_QUANTA.Q_CAP_DIFFBUS(CHIPS)':
 C_PATH='@s9s_mb_2u_lib.s9s_mb_2u(sch_1):page169_i119@pure_quanta.q_cap_diffbus(~
chips)',
 P_PATH='@s9s_mb_2u_lib.s9s_mb_2u(sch_1):page178_i119@pure_quanta.q_cap_diffbus(~
chips)',
 PATH='I119',
 DRAWING='@S9S_MB_2U_LIB.S9S_MB_2U(SCH_1):PAGE169',
 PIN_NAMES_ROTATE='TRUE',
 PHYS_PAGE='178',
 XY='(-725,-2025)',
 ROT='2',
 VER='2',
 PACK_TYPE='C0201',
 CDS_LIB='pure_quanta',
 CDS_PART_NAME='Q_CAP_DIFFBUS_C0201-DIFF BUS_0A',
 TOLERANCE='20%',
 MATERIAL='X6S',
 VOLTAGE='6.3V',
 VALUE='DIFF BUS_0.22UF',
 PRIM_FILE='./archive_libs/logical/q_cap_diffbus/chips/chips.prt';

PART_NAME
 C162 'Q_CAP_DIFFBUS_C0201-DIFF BUS_0A':;

SECTION_NUMBER 1
 '@S9S_MB_2U_LIB.S9S_MB_2U(SCH_1):PAGE169_I120@PURE_QUANTA.Q_CAP_DIFFBUS(CHIPS)':
 C_PATH='@s9s_mb_2u_lib.s9s_mb_2u(sch_1):page169_i120@pure_quanta.q_cap_diffbus(~
chips)',
 P_PATH='@s9s_mb_2u_lib.s9s_mb_2u(sch_1):page178_i120@pure_quanta.q_cap_diffbus(~
chips)',
 PATH='I120',
 DRAWING='@S9S_MB_2U_LIB.S9S_MB_2U(SCH_1):PAGE169',
 PIN_NAMES_ROTATE='TRUE',
 PHYS_PAGE='178',
 XY='(-725,-2075)',
 ROT='2',
 VER='2',
 PACK_TYPE='C0201',
 CDS_LIB='pure_quanta',
 CDS_PART_NAME='Q_CAP_DIFFBUS_C0201-DIFF BUS_0A',
 TOLERANCE='20%',
 MATERIAL='X6S',
 VOLTAGE='6.3V',
 VALUE='DIFF BUS_0.22UF',
 PRIM_FILE='./archive_libs/logical/q_cap_diffbus/chips/chips.prt';

PART_NAME
 C163 'Q_CAP_DIFFBUS_C0201-DIFF BUS_0A':;

SECTION_NUMBER 1
 '@S9S_MB_2U_LIB.S9S_MB_2U(SCH_1):PAGE169_I121@PURE_QUANTA.Q_CAP_DIFFBUS(CHIPS)':
 C_PATH='@s9s_mb_2u_lib.s9s_mb_2u(sch_1):page169_i121@pure_quanta.q_cap_diffbus(~
chips)',
 P_PATH='@s9s_mb_2u_lib.s9s_mb_2u(sch_1):page178_i121@pure_quanta.q_cap_diffbus(~
chips)',
 PATH='I121',
 DRAWING='@S9S_MB_2U_LIB.S9S_MB_2U(SCH_1):PAGE169',
 PIN_NAMES_ROTATE='TRUE',
 PHYS_PAGE='178',
 XY='(-725,-2225)',
 ROT='2',
 VER='2',
 PACK_TYPE='C0201',
 CDS_LIB='pure_quanta',
 CDS_PART_NAME='Q_CAP_DIFFBUS_C0201-DIFF BUS_0A',
 TOLERANCE='20%',
 MATERIAL='X6S',
 VOLTAGE='6.3V',
 VALUE='DIFF BUS_0.22UF',
 PRIM_FILE='./archive_libs/logical/q_cap_diffbus/chips/chips.prt';

PART_NAME
 C164 'Q_CAP_DIFFBUS_C0201-DIFF BUS_0A':;

SECTION_NUMBER 1
 '@S9S_MB_2U_LIB.S9S_MB_2U(SCH_1):PAGE169_I122@PURE_QUANTA.Q_CAP_DIFFBUS(CHIPS)':
 C_PATH='@s9s_mb_2u_lib.s9s_mb_2u(sch_1):page169_i122@pure_quanta.q_cap_diffbus(~
chips)',
 P_PATH='@s9s_mb_2u_lib.s9s_mb_2u(sch_1):page178_i122@pure_quanta.q_cap_diffbus(~
chips)',
 PATH='I122',
 DRAWING='@S9S_MB_2U_LIB.S9S_MB_2U(SCH_1):PAGE169',
 PIN_NAMES_ROTATE='TRUE',
 PHYS_PAGE='178',
 XY='(-725,-2275)',
 ROT='2',
 VER='2',
 PACK_TYPE='C0201',
 CDS_LIB='pure_quanta',
 CDS_PART_NAME='Q_CAP_DIFFBUS_C0201-DIFF BUS_0A',
 TOLERANCE='20%',
 MATERIAL='X6S',
 VOLTAGE='6.3V',
 VALUE='DIFF BUS_0.22UF',
 PRIM_FILE='./archive_libs/logical/q_cap_diffbus/chips/chips.prt';

PART_NAME
 C165 'Q_CAP_DIFFBUS_C0201-DIFF BUS_0A':;

SECTION_NUMBER 1
 '@S9S_MB_2U_LIB.S9S_MB_2U(SCH_1):PAGE169_I123@PURE_QUANTA.Q_CAP_DIFFBUS(CHIPS)':
 C_PATH='@s9s_mb_2u_lib.s9s_mb_2u(sch_1):page169_i123@pure_quanta.q_cap_diffbus(~
chips)',
 P_PATH='@s9s_mb_2u_lib.s9s_mb_2u(sch_1):page178_i123@pure_quanta.q_cap_diffbus(~
chips)',
 PATH='I123',
 DRAWING='@S9S_MB_2U_LIB.S9S_MB_2U(SCH_1):PAGE169',
 PIN_NAMES_ROTATE='TRUE',
 PHYS_PAGE='178',
 XY='(-725,-2425)',
 ROT='2',
 VER='2',
 PACK_TYPE='C0201',
 CDS_LIB='pure_quanta',
 CDS_PART_NAME='Q_CAP_DIFFBUS_C0201-DIFF BUS_0A',
 TOLERANCE='20%',
 MATERIAL='X6S',
 VOLTAGE='6.3V',
 VALUE='DIFF BUS_0.22UF',
 PRIM_FILE='./archive_libs/logical/q_cap_diffbus/chips/chips.prt';

PART_NAME
 C166 'Q_CAP_DIFFBUS_C0201-DIFF BUS_0A':;

SECTION_NUMBER 1
 '@S9S_MB_2U_LIB.S9S_MB_2U(SCH_1):PAGE169_I124@PURE_QUANTA.Q_CAP_DIFFBUS(CHIPS)':
 C_PATH='@s9s_mb_2u_lib.s9s_mb_2u(sch_1):page169_i124@pure_quanta.q_cap_diffbus(~
chips)',
 P_PATH='@s9s_mb_2u_lib.s9s_mb_2u(sch_1):page178_i124@pure_quanta.q_cap_diffbus(~
chips)',
 PATH='I124',
 DRAWING='@S9S_MB_2U_LIB.S9S_MB_2U(SCH_1):PAGE169',
 PIN_NAMES_ROTATE='TRUE',
 PHYS_PAGE='178',
 XY='(-725,-2475)',
 ROT='2',
 VER='2',
 PACK_TYPE='C0201',
 CDS_LIB='pure_quanta',
 CDS_PART_NAME='Q_CAP_DIFFBUS_C0201-DIFF BUS_0A',
 TOLERANCE='20%',
 MATERIAL='X6S',
 VOLTAGE='6.3V',
 VALUE='DIFF BUS_0.22UF',
 PRIM_FILE='./archive_libs/logical/q_cap_diffbus/chips/chips.prt';

PART_NAME
 C167 'Q_CAP_DIFFBUS_C0201-DIFF BUS_0A':;

SECTION_NUMBER 1
 '@S9S_MB_2U_LIB.S9S_MB_2U(SCH_1):PAGE169_I126@PURE_QUANTA.Q_CAP_DIFFBUS(CHIPS)':
 C_PATH='@s9s_mb_2u_lib.s9s_mb_2u(sch_1):page169_i126@pure_quanta.q_cap_diffbus(~
chips)',
 P_PATH='@s9s_mb_2u_lib.s9s_mb_2u(sch_1):page178_i126@pure_quanta.q_cap_diffbus(~
chips)',
 PATH='I126',
 DRAWING='@S9S_MB_2U_LIB.S9S_MB_2U(SCH_1):PAGE169',
 PIN_NAMES_ROTATE='TRUE',
 PHYS_PAGE='178',
 XY='(-725,-2625)',
 ROT='2',
 VER='2',
 PACK_TYPE='C0201',
 CDS_LIB='pure_quanta',
 CDS_PART_NAME='Q_CAP_DIFFBUS_C0201-DIFF BUS_0A',
 TOLERANCE='20%',
 MATERIAL='X6S',
 VOLTAGE='6.3V',
 VALUE='DIFF BUS_0.22UF',
 PRIM_FILE='./archive_libs/logical/q_cap_diffbus/chips/chips.prt';

PART_NAME
 C168 'Q_CAP_DIFFBUS_C0201-DIFF BUS_0A':;

SECTION_NUMBER 1
 '@S9S_MB_2U_LIB.S9S_MB_2U(SCH_1):PAGE169_I125@PURE_QUANTA.Q_CAP_DIFFBUS(CHIPS)':
 C_PATH='@s9s_mb_2u_lib.s9s_mb_2u(sch_1):page169_i125@pure_quanta.q_cap_diffbus(~
chips)',
 P_PATH='@s9s_mb_2u_lib.s9s_mb_2u(sch_1):page178_i125@pure_quanta.q_cap_diffbus(~
chips)',
 PATH='I125',
 DRAWING='@S9S_MB_2U_LIB.S9S_MB_2U(SCH_1):PAGE169',
 PIN_NAMES_ROTATE='TRUE',
 PHYS_PAGE='178',
 XY='(-725,-2675)',
 ROT='2',
 VER='2',
 PACK_TYPE='C0201',
 CDS_LIB='pure_quanta',
 CDS_PART_NAME='Q_CAP_DIFFBUS_C0201-DIFF BUS_0A',
 TOLERANCE='20%',
 MATERIAL='X6S',
 VOLTAGE='6.3V',
 VALUE='DIFF BUS_0.22UF',
 PRIM_FILE='./archive_libs/logical/q_cap_diffbus/chips/chips.prt';

PART_NAME
 C169 'Q_CAP_DIFFBUS_C0201-DIFF BUS_0A':;

SECTION_NUMBER 1
 '@S9S_MB_2U_LIB.S9S_MB_2U(SCH_1):PAGE169_I127@PURE_QUANTA.Q_CAP_DIFFBUS(CHIPS)':
 C_PATH='@s9s_mb_2u_lib.s9s_mb_2u(sch_1):page169_i127@pure_quanta.q_cap_diffbus(~
chips)',
 P_PATH='@s9s_mb_2u_lib.s9s_mb_2u(sch_1):page178_i127@pure_quanta.q_cap_diffbus(~
chips)',
 PATH='I127',
 DRAWING='@S9S_MB_2U_LIB.S9S_MB_2U(SCH_1):PAGE169',
 PIN_NAMES_ROTATE='TRUE',
 PHYS_PAGE='178',
 XY='(-725,-2825)',
 ROT='2',
 VER='2',
 PACK_TYPE='C0201',
 CDS_LIB='pure_quanta',
 CDS_PART_NAME='Q_CAP_DIFFBUS_C0201-DIFF BUS_0A',
 TOLERANCE='20%',
 MATERIAL='X6S',
 VOLTAGE='6.3V',
 VALUE='DIFF BUS_0.22UF',
 PRIM_FILE='./archive_libs/logical/q_cap_diffbus/chips/chips.prt';

PART_NAME
 C170 'Q_CAP_DIFFBUS_C0201-DIFF BUS_0A':;

SECTION_NUMBER 1
 '@S9S_MB_2U_LIB.S9S_MB_2U(SCH_1):PAGE169_I128@PURE_QUANTA.Q_CAP_DIFFBUS(CHIPS)':
 C_PATH='@s9s_mb_2u_lib.s9s_mb_2u(sch_1):page169_i128@pure_quanta.q_cap_diffbus(~
chips)',
 P_PATH='@s9s_mb_2u_lib.s9s_mb_2u(sch_1):page178_i128@pure_quanta.q_cap_diffbus(~
chips)',
 PATH='I128',
 DRAWING='@S9S_MB_2U_LIB.S9S_MB_2U(SCH_1):PAGE169',
 PIN_NAMES_ROTATE='TRUE',
 PHYS_PAGE='178',
 XY='(-725,-2875)',
 ROT='2',
 VER='2',
 PACK_TYPE='C0201',
 CDS_LIB='pure_quanta',
 CDS_PART_NAME='Q_CAP_DIFFBUS_C0201-DIFF BUS_0A',
 TOLERANCE='20%',
 MATERIAL='X6S',
 VOLTAGE='6.3V',
 VALUE='DIFF BUS_0.22UF',
 PRIM_FILE='./archive_libs/logical/q_cap_diffbus/chips/chips.prt';

PART_NAME
 C171 'Q_CAP_C0402-0.047UF,25V,10%,X7A':;

SECTION_NUMBER 1
 '@S9S_MB_2U_LIB.S9S_MB_2U(SCH_1):PAGE199_I77@PURE_QUANTA.Q_CAP(CHIPS)':
 C_PATH='@s9s_mb_2u_lib.s9s_mb_2u(sch_1):page199_i77@pure_quanta.q_cap(chips)',
 P_PATH='@s9s_mb_2u_lib.s9s_mb_2u(sch_1):page210_i77@pure_quanta.q_cap(chips)',
 PATH='I77',
 DRAWING='@S9S_MB_2U_LIB.S9S_MB_2U(SCH_1):PAGE199',
 PHYS_PAGE='210',
 XY='(-10900,7450)',
 ROT='0',
 VER='1',
 PACK_TYPE='C0402',
 LOCATION='C171',
 CDS_LIB='pure_quanta',
 CDS_PART_NAME='Q_CAP_C0402-0.047UF,25V,10%,X7A',
 TOLERANCE='10%',
 MATERIAL='X7R',
 VOLTAGE='25V',
 VALUE='0.047UF',
 PRIM_FILE='./archive_libs/logical/q_cap/chips/chips.prt';

PART_NAME
 C172 'Q_CAP_C0603-10UF,6.3V,20%,X6S,A':;

SECTION_NUMBER 1
 '@S9S_MB_2U_LIB.S9S_MB_2U(SCH_1):PAGE199_I6@PURE_QUANTA.Q_CAP(CHIPS)':
 C_PATH='@s9s_mb_2u_lib.s9s_mb_2u(sch_1):page199_i6@pure_quanta.q_cap(chips)',
 P_PATH='@s9s_mb_2u_lib.s9s_mb_2u(sch_1):page210_i6@pure_quanta.q_cap(chips)',
 PATH='I6',
 DRAWING='@S9S_MB_2U_LIB.S9S_MB_2U(SCH_1):PAGE199',
 PHYS_PAGE='210',
 XY='(-9250,7450)',
 ROT='0',
 VER='1',
 PACK_TYPE='C0603',
 CDS_LIB='pure_quanta',
 CDS_PART_NAME='Q_CAP_C0603-10UF,6.3V,20%,X6S,A',
 TOLERANCE='20%',
 MATERIAL='X6S',
 VOLTAGE='6.3V',
 VALUE='10UF',
 PRIM_FILE='./archive_libs/logical/q_cap/chips/chips.prt';

PART_NAME
 C173 'Q_CAP_C0402-0.047UF,25V,10%,X7A':;

SECTION_NUMBER 1
 '@S9S_MB_2U_LIB.S9S_MB_2U(SCH_1):PAGE199_I78@PURE_QUANTA.Q_CAP(CHIPS)':
 C_PATH='@s9s_mb_2u_lib.s9s_mb_2u(sch_1):page199_i78@pure_quanta.q_cap(chips)',
 P_PATH='@s9s_mb_2u_lib.s9s_mb_2u(sch_1):page210_i78@pure_quanta.q_cap(chips)',
 PATH='I78',
 DRAWING='@S9S_MB_2U_LIB.S9S_MB_2U(SCH_1):PAGE199',
 PHYS_PAGE='210',
 XY='(-8850,7450)',
 ROT='0',
 VER='1',
 PACK_TYPE='C0402',
 LOCATION='C173',
 CDS_LIB='pure_quanta',
 CDS_PART_NAME='Q_CAP_C0402-0.047UF,25V,10%,X7A',
 TOLERANCE='10%',
 MATERIAL='X7R',
 VOLTAGE='25V',
 VALUE='0.047UF',
 PRIM_FILE='./archive_libs/logical/q_cap/chips/chips.prt';

PART_NAME
 C174 'Q_CAP_0402-0.1UF,25V,10%,X7R,CA':;

SECTION_NUMBER 1
 '@S9S_MB_2U_LIB.S9S_MB_2U(SCH_1):PAGE219_I47@PURE_QUANTA.Q_CAP(CHIPS)':
 C_PATH='@s9s_mb_2u_lib.s9s_mb_2u(sch_1):page219_i47@pure_quanta.q_cap(chips)',
 P_PATH='@s9s_mb_2u_lib.s9s_mb_2u(sch_1):page231_i47@pure_quanta.q_cap(chips)',
 PATH='I47',
 DRAWING='@S9S_MB_2U_LIB.S9S_MB_2U(SCH_1):PAGE219',
 PHYS_PAGE='231',
 XY='(1200,3500)',
 ROT='0',
 VER='1',
 PACK_TYPE='0402',
 CDS_LIB='pure_quanta',
 CDS_PART_NAME='Q_CAP_0402-0.1UF,25V,10%,X7R,CA',
 TOLERANCE='10%',
 MATERIAL='X7R',
 VOLTAGE='25V',
 VALUE='0.1UF',
 PRIM_FILE='./archive_libs/logical/q_cap/chips/chips.prt';

PART_NAME
 C188 'Q_CAP_0402-0.1UF,25V,10%,X7R,CA':;

SECTION_NUMBER 1
 '@S9S_MB_2U_LIB.S9S_MB_2U(SCH_1):PAGE152_I44@PURE_QUANTA.Q_CAP(CHIPS)':
 C_PATH='@s9s_mb_2u_lib.s9s_mb_2u(sch_1):page152_i44@pure_quanta.q_cap(chips)',
 P_PATH='@s9s_mb_2u_lib.s9s_mb_2u(sch_1):page155_i44@pure_quanta.q_cap(chips)',
 PATH='I44',
 DRAWING='@S9S_MB_2U_LIB.S9S_MB_2U(SCH_1):PAGE152',
 PHYS_PAGE='155',
 XY='(-6750,6050)',
 ROT='0',
 VER='1',
 PACK_TYPE='0402',
 CDS_LIB='pure_quanta',
 CDS_PART_NAME='Q_CAP_0402-0.1UF,25V,10%,X7R,CA',
 TOLERANCE='10%',
 MATERIAL='X7R',
 VOLTAGE='25V',
 VALUE='0.1UF',
 PRIM_FILE='./archive_libs/logical/q_cap/chips/chips.prt';

PART_NAME
 C204 'Q_CAP_0402-0.1UF,25V,10%,X7R,CA':;

SECTION_NUMBER 1
 '@S9S_MB_2U_LIB.S9S_MB_2U(SCH_1):PAGE195_I171@PURE_QUANTA.Q_CAP(CHIPS)':
 C_PATH='@s9s_mb_2u_lib.s9s_mb_2u(sch_1):page195_i171@pure_quanta.q_cap(chips)',
 P_PATH='@s9s_mb_2u_lib.s9s_mb_2u(sch_1):page206_i171@pure_quanta.q_cap(chips)',
 PATH='I171',
 DRAWING='@S9S_MB_2U_LIB.S9S_MB_2U(SCH_1):PAGE195',
 BOM_COST='VR_SYSTEM ',
 PHYS_PAGE='206',
 XY='(-8875,5000)',
 ROT='0',
 VER='1',
 PACK_TYPE='0402',
 CDS_LIB='pure_quanta',
 CDS_PART_NAME='Q_CAP_0402-0.1UF,25V,10%,X7R,CA',
 TOLERANCE='10%',
 MATERIAL='X7R',
 VOLTAGE='25V',
 VALUE='0.1UF',
 PRIM_FILE='./archive_libs/logical/q_cap/chips/chips.prt';

PART_NAME
 C205 'Q_CAP_0402-0.1UF,25V,10%,X7R,CA':;

SECTION_NUMBER 1
 '@S9S_MB_2U_LIB.S9S_MB_2U(SCH_1):PAGE195_I172@PURE_QUANTA.Q_CAP(CHIPS)':
 C_PATH='@s9s_mb_2u_lib.s9s_mb_2u(sch_1):page195_i172@pure_quanta.q_cap(chips)',
 P_PATH='@s9s_mb_2u_lib.s9s_mb_2u(sch_1):page206_i172@pure_quanta.q_cap(chips)',
 PATH='I172',
 DRAWING='@S9S_MB_2U_LIB.S9S_MB_2U(SCH_1):PAGE195',
 BOM_COST='VR_SYSTEM ',
 PHYS_PAGE='206',
 XY='(-8475,5000)',
 ROT='0',
 VER='1',
 PACK_TYPE='0402',
 CDS_LIB='pure_quanta',
 CDS_PART_NAME='Q_CAP_0402-0.1UF,25V,10%,X7R,CA',
 TOLERANCE='10%',
 MATERIAL='X7R',
 VOLTAGE='25V',
 VALUE='0.1UF',
 PRIM_FILE='./archive_libs/logical/q_cap/chips/chips.prt';

PART_NAME
 C206 'Q_CAP_0402-0.1UF,25V,10%,X7R,CA':;

SECTION_NUMBER 1
 '@S9S_MB_2U_LIB.S9S_MB_2U(SCH_1):PAGE195_I173@PURE_QUANTA.Q_CAP(CHIPS)':
 C_PATH='@s9s_mb_2u_lib.s9s_mb_2u(sch_1):page195_i173@pure_quanta.q_cap(chips)',
 P_PATH='@s9s_mb_2u_lib.s9s_mb_2u(sch_1):page206_i173@pure_quanta.q_cap(chips)',
 PATH='I173',
 DRAWING='@S9S_MB_2U_LIB.S9S_MB_2U(SCH_1):PAGE195',
 BOM_COST='VR_SYSTEM ',
 PHYS_PAGE='206',
 XY='(-8100,5000)',
 ROT='0',
 VER='1',
 PACK_TYPE='0402',
 CDS_LIB='pure_quanta',
 CDS_PART_NAME='Q_CAP_0402-0.1UF,25V,10%,X7R,CA',
 TOLERANCE='10%',
 MATERIAL='X7R',
 VOLTAGE='25V',
 VALUE='0.1UF',
 PRIM_FILE='./archive_libs/logical/q_cap/chips/chips.prt';

PART_NAME
 C207 'Q_CAP_0402-0.1UF,25V,10%,X7R,CA':;

SECTION_NUMBER 1
 '@S9S_MB_2U_LIB.S9S_MB_2U(SCH_1):PAGE195_I174@PURE_QUANTA.Q_CAP(CHIPS)':
 C_PATH='@s9s_mb_2u_lib.s9s_mb_2u(sch_1):page195_i174@pure_quanta.q_cap(chips)',
 P_PATH='@s9s_mb_2u_lib.s9s_mb_2u(sch_1):page206_i174@pure_quanta.q_cap(chips)',
 PATH='I174',
 DRAWING='@S9S_MB_2U_LIB.S9S_MB_2U(SCH_1):PAGE195',
 BOM_COST='VR_SYSTEM ',
 PHYS_PAGE='206',
 XY='(-7725,5000)',
 ROT='0',
 VER='1',
 PACK_TYPE='0402',
 CDS_LIB='pure_quanta',
 CDS_PART_NAME='Q_CAP_0402-0.1UF,25V,10%,X7R,CA',
 TOLERANCE='10%',
 MATERIAL='X7R',
 VOLTAGE='25V',
 VALUE='0.1UF',
 PRIM_FILE='./archive_libs/logical/q_cap/chips/chips.prt';

PART_NAME
 C208 'Q_CAP_C0603-10UF,6.3V,20%,X6S,A':;

SECTION_NUMBER 1
 '@S9S_MB_2U_LIB.S9S_MB_2U(SCH_1):PAGE195_I167@PURE_QUANTA.Q_CAP(CHIPS)':
 C_PATH='@s9s_mb_2u_lib.s9s_mb_2u(sch_1):page195_i167@pure_quanta.q_cap(chips)',
 P_PATH='@s9s_mb_2u_lib.s9s_mb_2u(sch_1):page206_i167@pure_quanta.q_cap(chips)',
 PATH='I167',
 DRAWING='@S9S_MB_2U_LIB.S9S_MB_2U(SCH_1):PAGE195',
 PHYS_PAGE='206',
 XY='(-7450,3975)',
 ROT='0',
 VER='1',
 PACK_TYPE='C0603',
 CDS_LIB='pure_quanta',
 CDS_PART_NAME='Q_CAP_C0603-10UF,6.3V,20%,X6S,A',
 TOLERANCE='20%',
 MATERIAL='X6S',
 VOLTAGE='6.3V',
 VALUE='10UF',
 PRIM_FILE='./archive_libs/logical/q_cap/chips/chips.prt';

PART_NAME
 C209 'Q_CAP_C0603-10UF,6.3V,20%,X6S,A':;

SECTION_NUMBER 1
 '@S9S_MB_2U_LIB.S9S_MB_2U(SCH_1):PAGE195_I164@PURE_QUANTA.Q_CAP(CHIPS)':
 C_PATH='@s9s_mb_2u_lib.s9s_mb_2u(sch_1):page195_i164@pure_quanta.q_cap(chips)',
 P_PATH='@s9s_mb_2u_lib.s9s_mb_2u(sch_1):page206_i164@pure_quanta.q_cap(chips)',
 PATH='I164',
 DRAWING='@S9S_MB_2U_LIB.S9S_MB_2U(SCH_1):PAGE195',
 PHYS_PAGE='206',
 XY='(-7450,3100)',
 ROT='0',
 VER='1',
 PACK_TYPE='C0603',
 CDS_LIB='pure_quanta',
 CDS_PART_NAME='Q_CAP_C0603-10UF,6.3V,20%,X6S,A',
 TOLERANCE='20%',
 MATERIAL='X6S',
 VOLTAGE='6.3V',
 VALUE='10UF',
 PRIM_FILE='./archive_libs/logical/q_cap/chips/chips.prt';

PART_NAME
 C210 'Q_CAP_0402-0.1UF,25V,10%,X7R,CA':;

SECTION_NUMBER 1
 '@S9S_MB_2U_LIB.S9S_MB_2U(SCH_1):PAGE195_I168@PURE_QUANTA.Q_CAP(CHIPS)':
 C_PATH='@s9s_mb_2u_lib.s9s_mb_2u(sch_1):page195_i168@pure_quanta.q_cap(chips)',
 P_PATH='@s9s_mb_2u_lib.s9s_mb_2u(sch_1):page206_i168@pure_quanta.q_cap(chips)',
 PATH='I168',
 DRAWING='@S9S_MB_2U_LIB.S9S_MB_2U(SCH_1):PAGE195',
 BOM_COST='VR_SYSTEM ',
 PHYS_PAGE='206',
 XY='(-7075,3975)',
 ROT='0',
 VER='1',
 PACK_TYPE='0402',
 CDS_LIB='pure_quanta',
 CDS_PART_NAME='Q_CAP_0402-0.1UF,25V,10%,X7R,CA',
 TOLERANCE='10%',
 MATERIAL='X7R',
 VOLTAGE='25V',
 VALUE='0.1UF',
 PRIM_FILE='./archive_libs/logical/q_cap/chips/chips.prt';

PART_NAME
 C211 'Q_CAP_0402-0.1UF,25V,10%,X7R,CA':;

SECTION_NUMBER 1
 '@S9S_MB_2U_LIB.S9S_MB_2U(SCH_1):PAGE195_I165@PURE_QUANTA.Q_CAP(CHIPS)':
 C_PATH='@s9s_mb_2u_lib.s9s_mb_2u(sch_1):page195_i165@pure_quanta.q_cap(chips)',
 P_PATH='@s9s_mb_2u_lib.s9s_mb_2u(sch_1):page206_i165@pure_quanta.q_cap(chips)',
 PATH='I165',
 DRAWING='@S9S_MB_2U_LIB.S9S_MB_2U(SCH_1):PAGE195',
 BOM_COST='VR_SYSTEM ',
 PHYS_PAGE='206',
 XY='(-7075,3100)',
 ROT='0',
 VER='1',
 PACK_TYPE='0402',
 CDS_LIB='pure_quanta',
 CDS_PART_NAME='Q_CAP_0402-0.1UF,25V,10%,X7R,CA',
 TOLERANCE='10%',
 MATERIAL='X7R',
 VOLTAGE='25V',
 VALUE='0.1UF',
 PRIM_FILE='./archive_libs/logical/q_cap/chips/chips.prt';

PART_NAME
 C212 'Q_CAP_C0805-47UF,4V,20%,X6S,CHA':;

SECTION_NUMBER 1
 '@S9S_MB_2U_LIB.S9S_MB_2U(SCH_1):PAGE74_I18@PURE_QUANTA.Q_CAP(CHIPS)':
 C_PATH='@s9s_mb_2u_lib.s9s_mb_2u(sch_1):page74_i18@pure_quanta.q_cap(chips)',
 P_PATH='@s9s_mb_2u_lib.s9s_mb_2u(sch_1):page74_i18@pure_quanta.q_cap(chips)',
 PATH='I18',
 DRAWING='@S9S_MB_2U_LIB.S9S_MB_2U(SCH_1):PAGE74',
 PHYS_PAGE='74',
 XY='(-3800,-50)',
 ROT='0',
 VER='1',
 PACK_TYPE='C0805',
 CDS_LIB='pure_quanta',
 CDS_PART_NAME='Q_CAP_C0805-47UF,4V,20%,X6S,CHA',
 TOLERANCE='20%',
 MATERIAL='X6S',
 VOLTAGE='4V',
 VALUE='47UF',
 PRIM_FILE='./archive_libs/logical/q_cap/chips/chips.prt';

PART_NAME
 C213 'Q_CAP_C0805-47UF,4V,20%,X6S,CHA':;

SECTION_NUMBER 1
 '@S9S_MB_2U_LIB.S9S_MB_2U(SCH_1):PAGE74_I20@PURE_QUANTA.Q_CAP(CHIPS)':
 C_PATH='@s9s_mb_2u_lib.s9s_mb_2u(sch_1):page74_i20@pure_quanta.q_cap(chips)',
 P_PATH='@s9s_mb_2u_lib.s9s_mb_2u(sch_1):page74_i20@pure_quanta.q_cap(chips)',
 PATH='I20',
 DRAWING='@S9S_MB_2U_LIB.S9S_MB_2U(SCH_1):PAGE74',
 PHYS_PAGE='74',
 XY='(-3350,-50)',
 ROT='0',
 VER='1',
 PACK_TYPE='C0805',
 CDS_LIB='pure_quanta',
 CDS_PART_NAME='Q_CAP_C0805-47UF,4V,20%,X6S,CHA',
 TOLERANCE='20%',
 MATERIAL='X6S',
 VOLTAGE='4V',
 VALUE='47UF',
 PRIM_FILE='./archive_libs/logical/q_cap/chips/chips.prt';

PART_NAME
 C214 'Q_CAP_C0805-47UF,4V,20%,X6S,CHA':;

SECTION_NUMBER 1
 '@S9S_MB_2U_LIB.S9S_MB_2U(SCH_1):PAGE74_I35@PURE_QUANTA.Q_CAP(CHIPS)':
 C_PATH='@s9s_mb_2u_lib.s9s_mb_2u(sch_1):page74_i35@pure_quanta.q_cap(chips)',
 P_PATH='@s9s_mb_2u_lib.s9s_mb_2u(sch_1):page74_i35@pure_quanta.q_cap(chips)',
 PATH='I35',
 DRAWING='@S9S_MB_2U_LIB.S9S_MB_2U(SCH_1):PAGE74',
 PHYS_PAGE='74',
 XY='(-2900,-50)',
 ROT='0',
 VER='1',
 PACK_TYPE='C0805',
 CDS_LIB='pure_quanta',
 CDS_PART_NAME='Q_CAP_C0805-47UF,4V,20%,X6S,CHA',
 TOLERANCE='20%',
 MATERIAL='X6S',
 VOLTAGE='4V',
 VALUE='47UF',
 PRIM_FILE='./archive_libs/logical/q_cap/chips/chips.prt';

PART_NAME
 C215 'Q_CAP_C0805-47UF,4V,20%,X6S,CHA':;

SECTION_NUMBER 1
 '@S9S_MB_2U_LIB.S9S_MB_2U(SCH_1):PAGE74_I36@PURE_QUANTA.Q_CAP(CHIPS)':
 C_PATH='@s9s_mb_2u_lib.s9s_mb_2u(sch_1):page74_i36@pure_quanta.q_cap(chips)',
 P_PATH='@s9s_mb_2u_lib.s9s_mb_2u(sch_1):page74_i36@pure_quanta.q_cap(chips)',
 PATH='I36',
 DRAWING='@S9S_MB_2U_LIB.S9S_MB_2U(SCH_1):PAGE74',
 PHYS_PAGE='74',
 XY='(-2450,-50)',
 ROT='0',
 VER='1',
 PACK_TYPE='C0805',
 CDS_LIB='pure_quanta',
 CDS_PART_NAME='Q_CAP_C0805-47UF,4V,20%,X6S,CHA',
 TOLERANCE='20%',
 MATERIAL='X6S',
 VOLTAGE='4V',
 VALUE='47UF',
 PRIM_FILE='./archive_libs/logical/q_cap/chips/chips.prt';

PART_NAME
 C216 'Q_CAP_C0805-47UF,4V,20%,X6S,CHA':;

SECTION_NUMBER 1
 '@S9S_MB_2U_LIB.S9S_MB_2U(SCH_1):PAGE74_I40@PURE_QUANTA.Q_CAP(CHIPS)':
 C_PATH='@s9s_mb_2u_lib.s9s_mb_2u(sch_1):page74_i40@pure_quanta.q_cap(chips)',
 P_PATH='@s9s_mb_2u_lib.s9s_mb_2u(sch_1):page74_i40@pure_quanta.q_cap(chips)',
 PATH='I40',
 DRAWING='@S9S_MB_2U_LIB.S9S_MB_2U(SCH_1):PAGE74',
 PHYS_PAGE='74',
 XY='(-2000,-50)',
 ROT='0',
 VER='1',
 PACK_TYPE='C0805',
 CDS_LIB='pure_quanta',
 CDS_PART_NAME='Q_CAP_C0805-47UF,4V,20%,X6S,CHA',
 TOLERANCE='20%',
 MATERIAL='X6S',
 VOLTAGE='4V',
 VALUE='47UF',
 PRIM_FILE='./archive_libs/logical/q_cap/chips/chips.prt';

PART_NAME
 C217 'Q_CAP_C0805-47UF,4V,20%,X6S,CHA':;

SECTION_NUMBER 1
 '@S9S_MB_2U_LIB.S9S_MB_2U(SCH_1):PAGE74_I43@PURE_QUANTA.Q_CAP(CHIPS)':
 C_PATH='@s9s_mb_2u_lib.s9s_mb_2u(sch_1):page74_i43@pure_quanta.q_cap(chips)',
 P_PATH='@s9s_mb_2u_lib.s9s_mb_2u(sch_1):page74_i43@pure_quanta.q_cap(chips)',
 PATH='I43',
 DRAWING='@S9S_MB_2U_LIB.S9S_MB_2U(SCH_1):PAGE74',
 PHYS_PAGE='74',
 XY='(-1550,-50)',
 ROT='0',
 VER='1',
 PACK_TYPE='C0805',
 CDS_LIB='pure_quanta',
 CDS_PART_NAME='Q_CAP_C0805-47UF,4V,20%,X6S,CHA',
 TOLERANCE='20%',
 MATERIAL='X6S',
 VOLTAGE='4V',
 VALUE='47UF',
 PRIM_FILE='./archive_libs/logical/q_cap/chips/chips.prt';

PART_NAME
 C218 'Q_CAP_C0805-47UF,4V,20%,X6S,CHA':;

SECTION_NUMBER 1
 '@S9S_MB_2U_LIB.S9S_MB_2U(SCH_1):PAGE74_I44@PURE_QUANTA.Q_CAP(CHIPS)':
 C_PATH='@s9s_mb_2u_lib.s9s_mb_2u(sch_1):page74_i44@pure_quanta.q_cap(chips)',
 P_PATH='@s9s_mb_2u_lib.s9s_mb_2u(sch_1):page74_i44@pure_quanta.q_cap(chips)',
 PATH='I44',
 DRAWING='@S9S_MB_2U_LIB.S9S_MB_2U(SCH_1):PAGE74',
 PHYS_PAGE='74',
 XY='(-1100,-50)',
 ROT='0',
 VER='1',
 PACK_TYPE='C0805',
 CDS_LIB='pure_quanta',
 CDS_PART_NAME='Q_CAP_C0805-47UF,4V,20%,X6S,CHA',
 TOLERANCE='20%',
 MATERIAL='X6S',
 VOLTAGE='4V',
 VALUE='47UF',
 PRIM_FILE='./archive_libs/logical/q_cap/chips/chips.prt';

PART_NAME
 C219 'Q_CAP_C0805-47UF,4V,20%,X6S,CHA':;

SECTION_NUMBER 1
 '@S9S_MB_2U_LIB.S9S_MB_2U(SCH_1):PAGE74_I71@PURE_QUANTA.Q_CAP(CHIPS)':
 C_PATH='@s9s_mb_2u_lib.s9s_mb_2u(sch_1):page74_i71@pure_quanta.q_cap(chips)',
 P_PATH='@s9s_mb_2u_lib.s9s_mb_2u(sch_1):page74_i71@pure_quanta.q_cap(chips)',
 PATH='I71',
 DRAWING='@S9S_MB_2U_LIB.S9S_MB_2U(SCH_1):PAGE74',
 PHYS_PAGE='74',
 XY='(-650,-50)',
 ROT='0',
 VER='1',
 PACK_TYPE='C0805',
 CDS_LIB='pure_quanta',
 CDS_PART_NAME='Q_CAP_C0805-47UF,4V,20%,X6S,CHA',
 TOLERANCE='20%',
 MATERIAL='X6S',
 VOLTAGE='4V',
 VALUE='47UF',
 PRIM_FILE='./archive_libs/logical/q_cap/chips/chips.prt';

PART_NAME
 C220 'Q_CAP_C0805-47UF,4V,20%,X6S,CHA':;

SECTION_NUMBER 1
 '@S9S_MB_2U_LIB.S9S_MB_2U(SCH_1):PAGE74_I74@PURE_QUANTA.Q_CAP(CHIPS)':
 C_PATH='@s9s_mb_2u_lib.s9s_mb_2u(sch_1):page74_i74@pure_quanta.q_cap(chips)',
 P_PATH='@s9s_mb_2u_lib.s9s_mb_2u(sch_1):page74_i74@pure_quanta.q_cap(chips)',
 PATH='I74',
 DRAWING='@S9S_MB_2U_LIB.S9S_MB_2U(SCH_1):PAGE74',
 PHYS_PAGE='74',
 XY='(-200,-50)',
 ROT='0',
 VER='1',
 PACK_TYPE='C0805',
 CDS_LIB='pure_quanta',
 CDS_PART_NAME='Q_CAP_C0805-47UF,4V,20%,X6S,CHA',
 TOLERANCE='20%',
 MATERIAL='X6S',
 VOLTAGE='4V',
 VALUE='47UF',
 PRIM_FILE='./archive_libs/logical/q_cap/chips/chips.prt';

PART_NAME
 C221 'Q_CAP_C0402-10UF,6.3V,20%,X6S,B':;

SECTION_NUMBER 1
 '@S9S_MB_2U_LIB.S9S_MB_2U(SCH_1):PAGE77_I28@PURE_QUANTA.Q_CAP(CHIPS)':
 C_PATH='@s9s_mb_2u_lib.s9s_mb_2u(sch_1):page77_i28@pure_quanta.q_cap(chips)',
 P_PATH='@s9s_mb_2u_lib.s9s_mb_2u(sch_1):page77_i28@pure_quanta.q_cap(chips)',
 PATH='I28',
 DRAWING='@S9S_MB_2U_LIB.S9S_MB_2U(SCH_1):PAGE77',
 PHYS_PAGE='77',
 XY='(-7275,6925)',
 ROT='0',
 VER='1',
 PACK_TYPE='C0402',
 CDS_LIB='pure_quanta',
 CDS_PART_NAME='Q_CAP_C0402-10UF,6.3V,20%,X6S,B',
 TOLERANCE='20%',
 MATERIAL='X6S',
 VOLTAGE='6.3V',
 VALUE='10UF',
 PRIM_FILE='./archive_libs/logical/q_cap/chips/chips.prt';

PART_NAME
 C222 'Q_CAP_C0402-10UF,6.3V,20%,X6S,B':;

SECTION_NUMBER 1
 '@S9S_MB_2U_LIB.S9S_MB_2U(SCH_1):PAGE77_I25@PURE_QUANTA.Q_CAP(CHIPS)':
 C_PATH='@s9s_mb_2u_lib.s9s_mb_2u(sch_1):page77_i25@pure_quanta.q_cap(chips)',
 P_PATH='@s9s_mb_2u_lib.s9s_mb_2u(sch_1):page77_i25@pure_quanta.q_cap(chips)',
 PATH='I25',
 DRAWING='@S9S_MB_2U_LIB.S9S_MB_2U(SCH_1):PAGE77',
 PHYS_PAGE='77',
 XY='(-7275,6150)',
 ROT='0',
 VER='1',
 PACK_TYPE='C0402',
 CDS_LIB='pure_quanta',
 CDS_PART_NAME='Q_CAP_C0402-10UF,6.3V,20%,X6S,B',
 TOLERANCE='20%',
 MATERIAL='X6S',
 VOLTAGE='6.3V',
 VALUE='10UF',
 PRIM_FILE='./archive_libs/logical/q_cap/chips/chips.prt';

PART_NAME
 C223 'Q_CAP_C0402-10UF,6.3V,20%,X6S,B':;

SECTION_NUMBER 1
 '@S9S_MB_2U_LIB.S9S_MB_2U(SCH_1):PAGE77_I22@PURE_QUANTA.Q_CAP(CHIPS)':
 C_PATH='@s9s_mb_2u_lib.s9s_mb_2u(sch_1):page77_i22@pure_quanta.q_cap(chips)',
 P_PATH='@s9s_mb_2u_lib.s9s_mb_2u(sch_1):page77_i22@pure_quanta.q_cap(chips)',
 PATH='I22',
 DRAWING='@S9S_MB_2U_LIB.S9S_MB_2U(SCH_1):PAGE77',
 PHYS_PAGE='77',
 XY='(-7250,5400)',
 ROT='0',
 VER='1',
 PACK_TYPE='C0402',
 CDS_LIB='pure_quanta',
 CDS_PART_NAME='Q_CAP_C0402-10UF,6.3V,20%,X6S,B',
 TOLERANCE='20%',
 MATERIAL='X6S',
 VOLTAGE='6.3V',
 VALUE='10UF',
 PRIM_FILE='./archive_libs/logical/q_cap/chips/chips.prt';

PART_NAME
 C224 'Q_CAP_C0402-10UF,6.3V,20%,X6S,B':;

SECTION_NUMBER 1
 '@S9S_MB_2U_LIB.S9S_MB_2U(SCH_1):PAGE77_I13@PURE_QUANTA.Q_CAP(CHIPS)':
 C_PATH='@s9s_mb_2u_lib.s9s_mb_2u(sch_1):page77_i13@pure_quanta.q_cap(chips)',
 P_PATH='@s9s_mb_2u_lib.s9s_mb_2u(sch_1):page77_i13@pure_quanta.q_cap(chips)',
 PATH='I13',
 DRAWING='@S9S_MB_2U_LIB.S9S_MB_2U(SCH_1):PAGE77',
 PHYS_PAGE='77',
 XY='(-7250,4625)',
 ROT='0',
 VER='1',
 PACK_TYPE='C0402',
 CDS_LIB='pure_quanta',
 CDS_PART_NAME='Q_CAP_C0402-10UF,6.3V,20%,X6S,B',
 TOLERANCE='20%',
 MATERIAL='X6S',
 VOLTAGE='6.3V',
 VALUE='10UF',
 PRIM_FILE='./archive_libs/logical/q_cap/chips/chips.prt';

PART_NAME
 C225 'Q_CAP_C0805-47UF,4V,20%,X6S,CHA':;

SECTION_NUMBER 1
 '@S9S_MB_2U_LIB.S9S_MB_2U(SCH_1):PAGE77_I10@PURE_QUANTA.Q_CAP(CHIPS)':
 C_PATH='@s9s_mb_2u_lib.s9s_mb_2u(sch_1):page77_i10@pure_quanta.q_cap(chips)',
 P_PATH='@s9s_mb_2u_lib.s9s_mb_2u(sch_1):page77_i10@pure_quanta.q_cap(chips)',
 PATH='I10',
 DRAWING='@S9S_MB_2U_LIB.S9S_MB_2U(SCH_1):PAGE77',
 PHYS_PAGE='77',
 XY='(-7250,3850)',
 ROT='0',
 VER='1',
 PACK_TYPE='C0805',
 CDS_LIB='pure_quanta',
 CDS_PART_NAME='Q_CAP_C0805-47UF,4V,20%,X6S,CHA',
 TOLERANCE='20%',
 MATERIAL='X6S',
 VOLTAGE='4V',
 VALUE='47UF',
 PRIM_FILE='./archive_libs/logical/q_cap/chips/chips.prt';

PART_NAME
 C226 'Q_CAP_C0402-10UF,6.3V,20%,X6S,B':;

SECTION_NUMBER 1
 '@S9S_MB_2U_LIB.S9S_MB_2U(SCH_1):PAGE77_I29@PURE_QUANTA.Q_CAP(CHIPS)':
 C_PATH='@s9s_mb_2u_lib.s9s_mb_2u(sch_1):page77_i29@pure_quanta.q_cap(chips)',
 P_PATH='@s9s_mb_2u_lib.s9s_mb_2u(sch_1):page77_i29@pure_quanta.q_cap(chips)',
 PATH='I29',
 DRAWING='@S9S_MB_2U_LIB.S9S_MB_2U(SCH_1):PAGE77',
 PHYS_PAGE='77',
 XY='(-6825,6925)',
 ROT='0',
 VER='1',
 PACK_TYPE='C0402',
 CDS_LIB='pure_quanta',
 CDS_PART_NAME='Q_CAP_C0402-10UF,6.3V,20%,X6S,B',
 TOLERANCE='20%',
 MATERIAL='X6S',
 VOLTAGE='6.3V',
 VALUE='10UF',
 PRIM_FILE='./archive_libs/logical/q_cap/chips/chips.prt';

PART_NAME
 C227 'Q_CAP_C0402-10UF,6.3V,20%,X6S,B':;

SECTION_NUMBER 1
 '@S9S_MB_2U_LIB.S9S_MB_2U(SCH_1):PAGE77_I26@PURE_QUANTA.Q_CAP(CHIPS)':
 C_PATH='@s9s_mb_2u_lib.s9s_mb_2u(sch_1):page77_i26@pure_quanta.q_cap(chips)',
 P_PATH='@s9s_mb_2u_lib.s9s_mb_2u(sch_1):page77_i26@pure_quanta.q_cap(chips)',
 PATH='I26',
 DRAWING='@S9S_MB_2U_LIB.S9S_MB_2U(SCH_1):PAGE77',
 PHYS_PAGE='77',
 XY='(-6825,6150)',
 ROT='0',
 VER='1',
 PACK_TYPE='C0402',
 CDS_LIB='pure_quanta',
 CDS_PART_NAME='Q_CAP_C0402-10UF,6.3V,20%,X6S,B',
 TOLERANCE='20%',
 MATERIAL='X6S',
 VOLTAGE='6.3V',
 VALUE='10UF',
 PRIM_FILE='./archive_libs/logical/q_cap/chips/chips.prt';

PART_NAME
 C228 'Q_CAP_C0402-10UF,6.3V,20%,X6S,B':;

SECTION_NUMBER 1
 '@S9S_MB_2U_LIB.S9S_MB_2U(SCH_1):PAGE77_I23@PURE_QUANTA.Q_CAP(CHIPS)':
 C_PATH='@s9s_mb_2u_lib.s9s_mb_2u(sch_1):page77_i23@pure_quanta.q_cap(chips)',
 P_PATH='@s9s_mb_2u_lib.s9s_mb_2u(sch_1):page77_i23@pure_quanta.q_cap(chips)',
 PATH='I23',
 DRAWING='@S9S_MB_2U_LIB.S9S_MB_2U(SCH_1):PAGE77',
 PHYS_PAGE='77',
 XY='(-6800,5400)',
 ROT='0',
 VER='1',
 PACK_TYPE='C0402',
 CDS_LIB='pure_quanta',
 CDS_PART_NAME='Q_CAP_C0402-10UF,6.3V,20%,X6S,B',
 TOLERANCE='20%',
 MATERIAL='X6S',
 VOLTAGE='6.3V',
 VALUE='10UF',
 PRIM_FILE='./archive_libs/logical/q_cap/chips/chips.prt';

PART_NAME
 C229 'Q_CAP_C0402-10UF,6.3V,20%,X6S,B':;

SECTION_NUMBER 1
 '@S9S_MB_2U_LIB.S9S_MB_2U(SCH_1):PAGE77_I14@PURE_QUANTA.Q_CAP(CHIPS)':
 C_PATH='@s9s_mb_2u_lib.s9s_mb_2u(sch_1):page77_i14@pure_quanta.q_cap(chips)',
 P_PATH='@s9s_mb_2u_lib.s9s_mb_2u(sch_1):page77_i14@pure_quanta.q_cap(chips)',
 PATH='I14',
 DRAWING='@S9S_MB_2U_LIB.S9S_MB_2U(SCH_1):PAGE77',
 PHYS_PAGE='77',
 XY='(-6800,4625)',
 ROT='0',
 VER='1',
 PACK_TYPE='C0402',
 CDS_LIB='pure_quanta',
 CDS_PART_NAME='Q_CAP_C0402-10UF,6.3V,20%,X6S,B',
 TOLERANCE='20%',
 MATERIAL='X6S',
 VOLTAGE='6.3V',
 VALUE='10UF',
 PRIM_FILE='./archive_libs/logical/q_cap/chips/chips.prt';

PART_NAME
 C230 'Q_CAP_C0805-47UF,4V,20%,X6S,CHA':;

SECTION_NUMBER 1
 '@S9S_MB_2U_LIB.S9S_MB_2U(SCH_1):PAGE77_I11@PURE_QUANTA.Q_CAP(CHIPS)':
 C_PATH='@s9s_mb_2u_lib.s9s_mb_2u(sch_1):page77_i11@pure_quanta.q_cap(chips)',
 P_PATH='@s9s_mb_2u_lib.s9s_mb_2u(sch_1):page77_i11@pure_quanta.q_cap(chips)',
 PATH='I11',
 DRAWING='@S9S_MB_2U_LIB.S9S_MB_2U(SCH_1):PAGE77',
 PHYS_PAGE='77',
 XY='(-6800,3850)',
 ROT='0',
 VER='1',
 PACK_TYPE='C0805',
 CDS_LIB='pure_quanta',
 CDS_PART_NAME='Q_CAP_C0805-47UF,4V,20%,X6S,CHA',
 TOLERANCE='20%',
 MATERIAL='X6S',
 VOLTAGE='4V',
 VALUE='47UF',
 PRIM_FILE='./archive_libs/logical/q_cap/chips/chips.prt';

PART_NAME
 C231 'Q_CAP_C0402-10UF,6.3V,20%,X6S,B':;

SECTION_NUMBER 1
 '@S9S_MB_2U_LIB.S9S_MB_2U(SCH_1):PAGE77_I33@PURE_QUANTA.Q_CAP(CHIPS)':
 C_PATH='@s9s_mb_2u_lib.s9s_mb_2u(sch_1):page77_i33@pure_quanta.q_cap(chips)',
 P_PATH='@s9s_mb_2u_lib.s9s_mb_2u(sch_1):page77_i33@pure_quanta.q_cap(chips)',
 PATH='I33',
 DRAWING='@S9S_MB_2U_LIB.S9S_MB_2U(SCH_1):PAGE77',
 PHYS_PAGE='77',
 XY='(-6375,6925)',
 ROT='0',
 VER='1',
 PACK_TYPE='C0402',
 CDS_LIB='pure_quanta',
 CDS_PART_NAME='Q_CAP_C0402-10UF,6.3V,20%,X6S,B',
 TOLERANCE='20%',
 MATERIAL='X6S',
 VOLTAGE='6.3V',
 VALUE='10UF',
 PRIM_FILE='./archive_libs/logical/q_cap/chips/chips.prt';

PART_NAME
 C232 'Q_CAP_C0402-10UF,6.3V,20%,X6S,B':;

SECTION_NUMBER 1
 '@S9S_MB_2U_LIB.S9S_MB_2U(SCH_1):PAGE77_I32@PURE_QUANTA.Q_CAP(CHIPS)':
 C_PATH='@s9s_mb_2u_lib.s9s_mb_2u(sch_1):page77_i32@pure_quanta.q_cap(chips)',
 P_PATH='@s9s_mb_2u_lib.s9s_mb_2u(sch_1):page77_i32@pure_quanta.q_cap(chips)',
 PATH='I32',
 DRAWING='@S9S_MB_2U_LIB.S9S_MB_2U(SCH_1):PAGE77',
 PHYS_PAGE='77',
 XY='(-6375,6150)',
 ROT='0',
 VER='1',
 PACK_TYPE='C0402',
 CDS_LIB='pure_quanta',
 CDS_PART_NAME='Q_CAP_C0402-10UF,6.3V,20%,X6S,B',
 TOLERANCE='20%',
 MATERIAL='X6S',
 VOLTAGE='6.3V',
 VALUE='10UF',
 PRIM_FILE='./archive_libs/logical/q_cap/chips/chips.prt';

PART_NAME
 C233 'Q_CAP_C0402-10UF,6.3V,20%,X6S,B':;

SECTION_NUMBER 1
 '@S9S_MB_2U_LIB.S9S_MB_2U(SCH_1):PAGE77_I30@PURE_QUANTA.Q_CAP(CHIPS)':
 C_PATH='@s9s_mb_2u_lib.s9s_mb_2u(sch_1):page77_i30@pure_quanta.q_cap(chips)',
 P_PATH='@s9s_mb_2u_lib.s9s_mb_2u(sch_1):page77_i30@pure_quanta.q_cap(chips)',
 PATH='I30',
 DRAWING='@S9S_MB_2U_LIB.S9S_MB_2U(SCH_1):PAGE77',
 PHYS_PAGE='77',
 XY='(-6350,5400)',
 ROT='0',
 VER='1',
 PACK_TYPE='C0402',
 CDS_LIB='pure_quanta',
 CDS_PART_NAME='Q_CAP_C0402-10UF,6.3V,20%,X6S,B',
 TOLERANCE='20%',
 MATERIAL='X6S',
 VOLTAGE='6.3V',
 VALUE='10UF',
 PRIM_FILE='./archive_libs/logical/q_cap/chips/chips.prt';

PART_NAME
 C234 'Q_CAP_C0402-10UF,6.3V,20%,X6S,B':;

SECTION_NUMBER 1
 '@S9S_MB_2U_LIB.S9S_MB_2U(SCH_1):PAGE77_I19@PURE_QUANTA.Q_CAP(CHIPS)':
 C_PATH='@s9s_mb_2u_lib.s9s_mb_2u(sch_1):page77_i19@pure_quanta.q_cap(chips)',
 P_PATH='@s9s_mb_2u_lib.s9s_mb_2u(sch_1):page77_i19@pure_quanta.q_cap(chips)',
 PATH='I19',
 DRAWING='@S9S_MB_2U_LIB.S9S_MB_2U(SCH_1):PAGE77',
 PHYS_PAGE='77',
 XY='(-6350,4625)',
 ROT='0',
 VER='1',
 PACK_TYPE='C0402',
 CDS_LIB='pure_quanta',
 CDS_PART_NAME='Q_CAP_C0402-10UF,6.3V,20%,X6S,B',
 TOLERANCE='20%',
 MATERIAL='X6S',
 VOLTAGE='6.3V',
 VALUE='10UF',
 PRIM_FILE='./archive_libs/logical/q_cap/chips/chips.prt';

PART_NAME
 C235 'Q_CAP_C0805-47UF,4V,20%,X6S,CHA':;

SECTION_NUMBER 1
 '@S9S_MB_2U_LIB.S9S_MB_2U(SCH_1):PAGE77_I16@PURE_QUANTA.Q_CAP(CHIPS)':
 C_PATH='@s9s_mb_2u_lib.s9s_mb_2u(sch_1):page77_i16@pure_quanta.q_cap(chips)',
 P_PATH='@s9s_mb_2u_lib.s9s_mb_2u(sch_1):page77_i16@pure_quanta.q_cap(chips)',
 PATH='I16',
 DRAWING='@S9S_MB_2U_LIB.S9S_MB_2U(SCH_1):PAGE77',
 PHYS_PAGE='77',
 XY='(-6350,3850)',
 ROT='0',
 VER='1',
 PACK_TYPE='C0805',
 CDS_LIB='pure_quanta',
 CDS_PART_NAME='Q_CAP_C0805-47UF,4V,20%,X6S,CHA',
 TOLERANCE='20%',
 MATERIAL='X6S',
 VOLTAGE='4V',
 VALUE='47UF',
 PRIM_FILE='./archive_libs/logical/q_cap/chips/chips.prt';

PART_NAME
 C236 'Q_CAP_C0402-10UF,6.3V,20%,X6S,B':;

SECTION_NUMBER 1
 '@S9S_MB_2U_LIB.S9S_MB_2U(SCH_1):PAGE77_I35@PURE_QUANTA.Q_CAP(CHIPS)':
 C_PATH='@s9s_mb_2u_lib.s9s_mb_2u(sch_1):page77_i35@pure_quanta.q_cap(chips)',
 P_PATH='@s9s_mb_2u_lib.s9s_mb_2u(sch_1):page77_i35@pure_quanta.q_cap(chips)',
 PATH='I35',
 DRAWING='@S9S_MB_2U_LIB.S9S_MB_2U(SCH_1):PAGE77',
 PHYS_PAGE='77',
 XY='(-5925,6925)',
 ROT='0',
 VER='1',
 PACK_TYPE='C0402',
 CDS_LIB='pure_quanta',
 CDS_PART_NAME='Q_CAP_C0402-10UF,6.3V,20%,X6S,B',
 TOLERANCE='20%',
 MATERIAL='X6S',
 VOLTAGE='6.3V',
 VALUE='10UF',
 PRIM_FILE='./archive_libs/logical/q_cap/chips/chips.prt';

PART_NAME
 C237 'Q_CAP_C0402-10UF,6.3V,20%,X6S,B':;

SECTION_NUMBER 1
 '@S9S_MB_2U_LIB.S9S_MB_2U(SCH_1):PAGE77_I34@PURE_QUANTA.Q_CAP(CHIPS)':
 C_PATH='@s9s_mb_2u_lib.s9s_mb_2u(sch_1):page77_i34@pure_quanta.q_cap(chips)',
 P_PATH='@s9s_mb_2u_lib.s9s_mb_2u(sch_1):page77_i34@pure_quanta.q_cap(chips)',
 PATH='I34',
 DRAWING='@S9S_MB_2U_LIB.S9S_MB_2U(SCH_1):PAGE77',
 PHYS_PAGE='77',
 XY='(-5925,6150)',
 ROT='0',
 VER='1',
 PACK_TYPE='C0402',
 CDS_LIB='pure_quanta',
 CDS_PART_NAME='Q_CAP_C0402-10UF,6.3V,20%,X6S,B',
 TOLERANCE='20%',
 MATERIAL='X6S',
 VOLTAGE='6.3V',
 VALUE='10UF',
 PRIM_FILE='./archive_libs/logical/q_cap/chips/chips.prt';

PART_NAME
 C238 'Q_CAP_C0402-10UF,6.3V,20%,X6S,B':;

SECTION_NUMBER 1
 '@S9S_MB_2U_LIB.S9S_MB_2U(SCH_1):PAGE77_I31@PURE_QUANTA.Q_CAP(CHIPS)':
 C_PATH='@s9s_mb_2u_lib.s9s_mb_2u(sch_1):page77_i31@pure_quanta.q_cap(chips)',
 P_PATH='@s9s_mb_2u_lib.s9s_mb_2u(sch_1):page77_i31@pure_quanta.q_cap(chips)',
 PATH='I31',
 DRAWING='@S9S_MB_2U_LIB.S9S_MB_2U(SCH_1):PAGE77',
 PHYS_PAGE='77',
 XY='(-5900,5400)',
 ROT='0',
 VER='1',
 PACK_TYPE='C0402',
 CDS_LIB='pure_quanta',
 CDS_PART_NAME='Q_CAP_C0402-10UF,6.3V,20%,X6S,B',
 TOLERANCE='20%',
 MATERIAL='X6S',
 VOLTAGE='6.3V',
 VALUE='10UF',
 PRIM_FILE='./archive_libs/logical/q_cap/chips/chips.prt';

PART_NAME
 C239 'Q_CAP_C0402-10UF,6.3V,20%,X6S,B':;

SECTION_NUMBER 1
 '@S9S_MB_2U_LIB.S9S_MB_2U(SCH_1):PAGE77_I20@PURE_QUANTA.Q_CAP(CHIPS)':
 C_PATH='@s9s_mb_2u_lib.s9s_mb_2u(sch_1):page77_i20@pure_quanta.q_cap(chips)',
 P_PATH='@s9s_mb_2u_lib.s9s_mb_2u(sch_1):page77_i20@pure_quanta.q_cap(chips)',
 PATH='I20',
 DRAWING='@S9S_MB_2U_LIB.S9S_MB_2U(SCH_1):PAGE77',
 PHYS_PAGE='77',
 XY='(-5900,4625)',
 ROT='0',
 VER='1',
 PACK_TYPE='C0402',
 CDS_LIB='pure_quanta',
 CDS_PART_NAME='Q_CAP_C0402-10UF,6.3V,20%,X6S,B',
 TOLERANCE='20%',
 MATERIAL='X6S',
 VOLTAGE='6.3V',
 VALUE='10UF',
 PRIM_FILE='./archive_libs/logical/q_cap/chips/chips.prt';

PART_NAME
 C240 'Q_CAP_C0805-47UF,4V,20%,X6S,CHA':;

SECTION_NUMBER 1
 '@S9S_MB_2U_LIB.S9S_MB_2U(SCH_1):PAGE77_I18@PURE_QUANTA.Q_CAP(CHIPS)':
 C_PATH='@s9s_mb_2u_lib.s9s_mb_2u(sch_1):page77_i18@pure_quanta.q_cap(chips)',
 P_PATH='@s9s_mb_2u_lib.s9s_mb_2u(sch_1):page77_i18@pure_quanta.q_cap(chips)',
 PATH='I18',
 DRAWING='@S9S_MB_2U_LIB.S9S_MB_2U(SCH_1):PAGE77',
 PHYS_PAGE='77',
 XY='(-5900,3850)',
 ROT='0',
 VER='1',
 PACK_TYPE='C0805',
 CDS_LIB='pure_quanta',
 CDS_PART_NAME='Q_CAP_C0805-47UF,4V,20%,X6S,CHA',
 TOLERANCE='20%',
 MATERIAL='X6S',
 VOLTAGE='4V',
 VALUE='47UF',
 PRIM_FILE='./archive_libs/logical/q_cap/chips/chips.prt';

PART_NAME
 C241 'Q_CAP_C0402-10UF,6.3V,20%,X6S,B':;

SECTION_NUMBER 1
 '@S9S_MB_2U_LIB.S9S_MB_2U(SCH_1):PAGE77_I77@PURE_QUANTA.Q_CAP(CHIPS)':
 C_PATH='@s9s_mb_2u_lib.s9s_mb_2u(sch_1):page77_i77@pure_quanta.q_cap(chips)',
 P_PATH='@s9s_mb_2u_lib.s9s_mb_2u(sch_1):page77_i77@pure_quanta.q_cap(chips)',
 PATH='I77',
 DRAWING='@S9S_MB_2U_LIB.S9S_MB_2U(SCH_1):PAGE77',
 PHYS_PAGE='77',
 XY='(-5475,6925)',
 ROT='0',
 VER='1',
 PACK_TYPE='C0402',
 CDS_LIB='pure_quanta',
 CDS_PART_NAME='Q_CAP_C0402-10UF,6.3V,20%,X6S,B',
 TOLERANCE='20%',
 MATERIAL='X6S',
 VOLTAGE='6.3V',
 VALUE='10UF',
 PRIM_FILE='./archive_libs/logical/q_cap/chips/chips.prt';

PART_NAME
 C242 'Q_CAP_C0402-10UF,6.3V,20%,X6S,B':;

SECTION_NUMBER 1
 '@S9S_MB_2U_LIB.S9S_MB_2U(SCH_1):PAGE77_I76@PURE_QUANTA.Q_CAP(CHIPS)':
 C_PATH='@s9s_mb_2u_lib.s9s_mb_2u(sch_1):page77_i76@pure_quanta.q_cap(chips)',
 P_PATH='@s9s_mb_2u_lib.s9s_mb_2u(sch_1):page77_i76@pure_quanta.q_cap(chips)',
 PATH='I76',
 DRAWING='@S9S_MB_2U_LIB.S9S_MB_2U(SCH_1):PAGE77',
 PHYS_PAGE='77',
 XY='(-5475,6150)',
 ROT='0',
 VER='1',
 PACK_TYPE='C0402',
 CDS_LIB='pure_quanta',
 CDS_PART_NAME='Q_CAP_C0402-10UF,6.3V,20%,X6S,B',
 TOLERANCE='20%',
 MATERIAL='X6S',
 VOLTAGE='6.3V',
 VALUE='10UF',
 PRIM_FILE='./archive_libs/logical/q_cap/chips/chips.prt';

PART_NAME
 C243 'Q_CAP_C0402-10UF,6.3V,20%,X6S,B':;

SECTION_NUMBER 1
 '@S9S_MB_2U_LIB.S9S_MB_2U(SCH_1):PAGE77_I74@PURE_QUANTA.Q_CAP(CHIPS)':
 C_PATH='@s9s_mb_2u_lib.s9s_mb_2u(sch_1):page77_i74@pure_quanta.q_cap(chips)',
 P_PATH='@s9s_mb_2u_lib.s9s_mb_2u(sch_1):page77_i74@pure_quanta.q_cap(chips)',
 PATH='I74',
 DRAWING='@S9S_MB_2U_LIB.S9S_MB_2U(SCH_1):PAGE77',
 PHYS_PAGE='77',
 XY='(-5450,5400)',
 ROT='0',
 VER='1',
 PACK_TYPE='C0402',
 CDS_LIB='pure_quanta',
 CDS_PART_NAME='Q_CAP_C0402-10UF,6.3V,20%,X6S,B',
 TOLERANCE='20%',
 MATERIAL='X6S',
 VOLTAGE='6.3V',
 VALUE='10UF',
 PRIM_FILE='./archive_libs/logical/q_cap/chips/chips.prt';

PART_NAME
 C244 'Q_CAP_C0402-10UF,6.3V,20%,X6S,B':;

SECTION_NUMBER 1
 '@S9S_MB_2U_LIB.S9S_MB_2U(SCH_1):PAGE77_I45@PURE_QUANTA.Q_CAP(CHIPS)':
 C_PATH='@s9s_mb_2u_lib.s9s_mb_2u(sch_1):page77_i45@pure_quanta.q_cap(chips)',
 P_PATH='@s9s_mb_2u_lib.s9s_mb_2u(sch_1):page77_i45@pure_quanta.q_cap(chips)',
 PATH='I45',
 DRAWING='@S9S_MB_2U_LIB.S9S_MB_2U(SCH_1):PAGE77',
 PHYS_PAGE='77',
 XY='(-5450,4625)',
 ROT='0',
 VER='1',
 PACK_TYPE='C0402',
 CDS_LIB='pure_quanta',
 CDS_PART_NAME='Q_CAP_C0402-10UF,6.3V,20%,X6S,B',
 TOLERANCE='20%',
 MATERIAL='X6S',
 VOLTAGE='6.3V',
 VALUE='10UF',
 PRIM_FILE='./archive_libs/logical/q_cap/chips/chips.prt';

PART_NAME
 C245 'Q_CAP_C0805-47UF,4V,20%,X6S,CHA':;

SECTION_NUMBER 1
 '@S9S_MB_2U_LIB.S9S_MB_2U(SCH_1):PAGE77_I41@PURE_QUANTA.Q_CAP(CHIPS)':
 C_PATH='@s9s_mb_2u_lib.s9s_mb_2u(sch_1):page77_i41@pure_quanta.q_cap(chips)',
 P_PATH='@s9s_mb_2u_lib.s9s_mb_2u(sch_1):page77_i41@pure_quanta.q_cap(chips)',
 PATH='I41',
 DRAWING='@S9S_MB_2U_LIB.S9S_MB_2U(SCH_1):PAGE77',
 PHYS_PAGE='77',
 XY='(-5450,3850)',
 ROT='0',
 VER='1',
 PACK_TYPE='C0805',
 CDS_LIB='pure_quanta',
 CDS_PART_NAME='Q_CAP_C0805-47UF,4V,20%,X6S,CHA',
 TOLERANCE='20%',
 MATERIAL='X6S',
 VOLTAGE='4V',
 VALUE='47UF',
 PRIM_FILE='./archive_libs/logical/q_cap/chips/chips.prt';

PART_NAME
 C246 'Q_CAP_C0402-10UF,6.3V,20%,X6S,B':;

SECTION_NUMBER 1
 '@S9S_MB_2U_LIB.S9S_MB_2U(SCH_1):PAGE77_I79@PURE_QUANTA.Q_CAP(CHIPS)':
 C_PATH='@s9s_mb_2u_lib.s9s_mb_2u(sch_1):page77_i79@pure_quanta.q_cap(chips)',
 P_PATH='@s9s_mb_2u_lib.s9s_mb_2u(sch_1):page77_i79@pure_quanta.q_cap(chips)',
 PATH='I79',
 DRAWING='@S9S_MB_2U_LIB.S9S_MB_2U(SCH_1):PAGE77',
 PHYS_PAGE='77',
 XY='(-5025,6925)',
 ROT='0',
 VER='1',
 PACK_TYPE='C0402',
 CDS_LIB='pure_quanta',
 CDS_PART_NAME='Q_CAP_C0402-10UF,6.3V,20%,X6S,B',
 TOLERANCE='20%',
 MATERIAL='X6S',
 VOLTAGE='6.3V',
 VALUE='10UF',
 PRIM_FILE='./archive_libs/logical/q_cap/chips/chips.prt';

PART_NAME
 C247 'Q_CAP_C0402-10UF,6.3V,20%,X6S,B':;

SECTION_NUMBER 1
 '@S9S_MB_2U_LIB.S9S_MB_2U(SCH_1):PAGE77_I78@PURE_QUANTA.Q_CAP(CHIPS)':
 C_PATH='@s9s_mb_2u_lib.s9s_mb_2u(sch_1):page77_i78@pure_quanta.q_cap(chips)',
 P_PATH='@s9s_mb_2u_lib.s9s_mb_2u(sch_1):page77_i78@pure_quanta.q_cap(chips)',
 PATH='I78',
 DRAWING='@S9S_MB_2U_LIB.S9S_MB_2U(SCH_1):PAGE77',
 PHYS_PAGE='77',
 XY='(-5025,6150)',
 ROT='0',
 VER='1',
 PACK_TYPE='C0402',
 CDS_LIB='pure_quanta',
 CDS_PART_NAME='Q_CAP_C0402-10UF,6.3V,20%,X6S,B',
 TOLERANCE='20%',
 MATERIAL='X6S',
 VOLTAGE='6.3V',
 VALUE='10UF',
 PRIM_FILE='./archive_libs/logical/q_cap/chips/chips.prt';

PART_NAME
 C248 'Q_CAP_C0402-10UF,6.3V,20%,X6S,B':;

SECTION_NUMBER 1
 '@S9S_MB_2U_LIB.S9S_MB_2U(SCH_1):PAGE77_I75@PURE_QUANTA.Q_CAP(CHIPS)':
 C_PATH='@s9s_mb_2u_lib.s9s_mb_2u(sch_1):page77_i75@pure_quanta.q_cap(chips)',
 P_PATH='@s9s_mb_2u_lib.s9s_mb_2u(sch_1):page77_i75@pure_quanta.q_cap(chips)',
 PATH='I75',
 DRAWING='@S9S_MB_2U_LIB.S9S_MB_2U(SCH_1):PAGE77',
 PHYS_PAGE='77',
 XY='(-5000,5400)',
 ROT='0',
 VER='1',
 PACK_TYPE='C0402',
 CDS_LIB='pure_quanta',
 CDS_PART_NAME='Q_CAP_C0402-10UF,6.3V,20%,X6S,B',
 TOLERANCE='20%',
 MATERIAL='X6S',
 VOLTAGE='6.3V',
 VALUE='10UF',
 PRIM_FILE='./archive_libs/logical/q_cap/chips/chips.prt';

PART_NAME
 C249 'Q_CAP_C0402-10UF,6.3V,20%,X6S,B':;

SECTION_NUMBER 1
 '@S9S_MB_2U_LIB.S9S_MB_2U(SCH_1):PAGE77_I46@PURE_QUANTA.Q_CAP(CHIPS)':
 C_PATH='@s9s_mb_2u_lib.s9s_mb_2u(sch_1):page77_i46@pure_quanta.q_cap(chips)',
 P_PATH='@s9s_mb_2u_lib.s9s_mb_2u(sch_1):page77_i46@pure_quanta.q_cap(chips)',
 PATH='I46',
 DRAWING='@S9S_MB_2U_LIB.S9S_MB_2U(SCH_1):PAGE77',
 PHYS_PAGE='77',
 XY='(-5000,4625)',
 ROT='0',
 VER='1',
 PACK_TYPE='C0402',
 CDS_LIB='pure_quanta',
 CDS_PART_NAME='Q_CAP_C0402-10UF,6.3V,20%,X6S,B',
 TOLERANCE='20%',
 MATERIAL='X6S',
 VOLTAGE='6.3V',
 VALUE='10UF',
 PRIM_FILE='./archive_libs/logical/q_cap/chips/chips.prt';

PART_NAME
 C250 'Q_CAP_C0805-47UF,4V,20%,X6S,CHA':;

SECTION_NUMBER 1
 '@S9S_MB_2U_LIB.S9S_MB_2U(SCH_1):PAGE77_I44@PURE_QUANTA.Q_CAP(CHIPS)':
 C_PATH='@s9s_mb_2u_lib.s9s_mb_2u(sch_1):page77_i44@pure_quanta.q_cap(chips)',
 P_PATH='@s9s_mb_2u_lib.s9s_mb_2u(sch_1):page77_i44@pure_quanta.q_cap(chips)',
 PATH='I44',
 DRAWING='@S9S_MB_2U_LIB.S9S_MB_2U(SCH_1):PAGE77',
 PHYS_PAGE='77',
 XY='(-5000,3850)',
 ROT='0',
 VER='1',
 PACK_TYPE='C0805',
 CDS_LIB='pure_quanta',
 CDS_PART_NAME='Q_CAP_C0805-47UF,4V,20%,X6S,CHA',
 TOLERANCE='20%',
 MATERIAL='X6S',
 VOLTAGE='4V',
 VALUE='47UF',
 PRIM_FILE='./archive_libs/logical/q_cap/chips/chips.prt';

PART_NAME
 C251 'Q_CAP_C0402-10UF,6.3V,20%,X6S,B':;

SECTION_NUMBER 1
 '@S9S_MB_2U_LIB.S9S_MB_2U(SCH_1):PAGE77_I83@PURE_QUANTA.Q_CAP(CHIPS)':
 C_PATH='@s9s_mb_2u_lib.s9s_mb_2u(sch_1):page77_i83@pure_quanta.q_cap(chips)',
 P_PATH='@s9s_mb_2u_lib.s9s_mb_2u(sch_1):page77_i83@pure_quanta.q_cap(chips)',
 PATH='I83',
 DRAWING='@S9S_MB_2U_LIB.S9S_MB_2U(SCH_1):PAGE77',
 PHYS_PAGE='77',
 XY='(-4575,6925)',
 ROT='0',
 VER='1',
 PACK_TYPE='C0402',
 CDS_LIB='pure_quanta',
 CDS_PART_NAME='Q_CAP_C0402-10UF,6.3V,20%,X6S,B',
 TOLERANCE='20%',
 MATERIAL='X6S',
 VOLTAGE='6.3V',
 VALUE='10UF',
 PRIM_FILE='./archive_libs/logical/q_cap/chips/chips.prt';

PART_NAME
 C252 'Q_CAP_C0402-10UF,6.3V,20%,X6S,B':;

SECTION_NUMBER 1
 '@S9S_MB_2U_LIB.S9S_MB_2U(SCH_1):PAGE77_I82@PURE_QUANTA.Q_CAP(CHIPS)':
 C_PATH='@s9s_mb_2u_lib.s9s_mb_2u(sch_1):page77_i82@pure_quanta.q_cap(chips)',
 P_PATH='@s9s_mb_2u_lib.s9s_mb_2u(sch_1):page77_i82@pure_quanta.q_cap(chips)',
 PATH='I82',
 DRAWING='@S9S_MB_2U_LIB.S9S_MB_2U(SCH_1):PAGE77',
 PHYS_PAGE='77',
 XY='(-4575,6150)',
 ROT='0',
 VER='1',
 PACK_TYPE='C0402',
 CDS_LIB='pure_quanta',
 CDS_PART_NAME='Q_CAP_C0402-10UF,6.3V,20%,X6S,B',
 TOLERANCE='20%',
 MATERIAL='X6S',
 VOLTAGE='6.3V',
 VALUE='10UF',
 PRIM_FILE='./archive_libs/logical/q_cap/chips/chips.prt';

PART_NAME
 C253 'Q_CAP_C0402-10UF,6.3V,20%,X6S,B':;

SECTION_NUMBER 1
 '@S9S_MB_2U_LIB.S9S_MB_2U(SCH_1):PAGE77_I80@PURE_QUANTA.Q_CAP(CHIPS)':
 C_PATH='@s9s_mb_2u_lib.s9s_mb_2u(sch_1):page77_i80@pure_quanta.q_cap(chips)',
 P_PATH='@s9s_mb_2u_lib.s9s_mb_2u(sch_1):page77_i80@pure_quanta.q_cap(chips)',
 PATH='I80',
 DRAWING='@S9S_MB_2U_LIB.S9S_MB_2U(SCH_1):PAGE77',
 PHYS_PAGE='77',
 XY='(-4550,5400)',
 ROT='0',
 VER='1',
 PACK_TYPE='C0402',
 CDS_LIB='pure_quanta',
 CDS_PART_NAME='Q_CAP_C0402-10UF,6.3V,20%,X6S,B',
 TOLERANCE='20%',
 MATERIAL='X6S',
 VOLTAGE='6.3V',
 VALUE='10UF',
 PRIM_FILE='./archive_libs/logical/q_cap/chips/chips.prt';

PART_NAME
 C254 'Q_CAP_C0402-10UF,6.3V,20%,X6S,B':;

SECTION_NUMBER 1
 '@S9S_MB_2U_LIB.S9S_MB_2U(SCH_1):PAGE77_I51@PURE_QUANTA.Q_CAP(CHIPS)':
 C_PATH='@s9s_mb_2u_lib.s9s_mb_2u(sch_1):page77_i51@pure_quanta.q_cap(chips)',
 P_PATH='@s9s_mb_2u_lib.s9s_mb_2u(sch_1):page77_i51@pure_quanta.q_cap(chips)',
 PATH='I51',
 DRAWING='@S9S_MB_2U_LIB.S9S_MB_2U(SCH_1):PAGE77',
 PHYS_PAGE='77',
 XY='(-4550,4625)',
 ROT='0',
 VER='1',
 PACK_TYPE='C0402',
 CDS_LIB='pure_quanta',
 CDS_PART_NAME='Q_CAP_C0402-10UF,6.3V,20%,X6S,B',
 TOLERANCE='20%',
 MATERIAL='X6S',
 VOLTAGE='6.3V',
 VALUE='10UF',
 PRIM_FILE='./archive_libs/logical/q_cap/chips/chips.prt';

PART_NAME
 C255 'Q_CAP_C0805-47UF,4V,20%,X6S,CHA':;

SECTION_NUMBER 1
 '@S9S_MB_2U_LIB.S9S_MB_2U(SCH_1):PAGE77_I48@PURE_QUANTA.Q_CAP(CHIPS)':
 C_PATH='@s9s_mb_2u_lib.s9s_mb_2u(sch_1):page77_i48@pure_quanta.q_cap(chips)',
 P_PATH='@s9s_mb_2u_lib.s9s_mb_2u(sch_1):page77_i48@pure_quanta.q_cap(chips)',
 PATH='I48',
 DRAWING='@S9S_MB_2U_LIB.S9S_MB_2U(SCH_1):PAGE77',
 PHYS_PAGE='77',
 XY='(-4550,3850)',
 ROT='0',
 VER='1',
 PACK_TYPE='C0805',
 CDS_LIB='pure_quanta',
 CDS_PART_NAME='Q_CAP_C0805-47UF,4V,20%,X6S,CHA',
 TOLERANCE='20%',
 MATERIAL='X6S',
 VOLTAGE='4V',
 VALUE='47UF',
 PRIM_FILE='./archive_libs/logical/q_cap/chips/chips.prt';

PART_NAME
 C256 'Q_CAP_C0402-10UF,6.3V,20%,X6S,B':;

SECTION_NUMBER 1
 '@S9S_MB_2U_LIB.S9S_MB_2U(SCH_1):PAGE77_I85@PURE_QUANTA.Q_CAP(CHIPS)':
 C_PATH='@s9s_mb_2u_lib.s9s_mb_2u(sch_1):page77_i85@pure_quanta.q_cap(chips)',
 P_PATH='@s9s_mb_2u_lib.s9s_mb_2u(sch_1):page77_i85@pure_quanta.q_cap(chips)',
 PATH='I85',
 DRAWING='@S9S_MB_2U_LIB.S9S_MB_2U(SCH_1):PAGE77',
 PHYS_PAGE='77',
 XY='(-4125,6925)',
 ROT='0',
 VER='1',
 PACK_TYPE='C0402',
 CDS_LIB='pure_quanta',
 CDS_PART_NAME='Q_CAP_C0402-10UF,6.3V,20%,X6S,B',
 TOLERANCE='20%',
 MATERIAL='X6S',
 VOLTAGE='6.3V',
 VALUE='10UF',
 PRIM_FILE='./archive_libs/logical/q_cap/chips/chips.prt';

PART_NAME
 C257 'Q_CAP_C0402-10UF,6.3V,20%,X6S,B':;

SECTION_NUMBER 1
 '@S9S_MB_2U_LIB.S9S_MB_2U(SCH_1):PAGE77_I84@PURE_QUANTA.Q_CAP(CHIPS)':
 C_PATH='@s9s_mb_2u_lib.s9s_mb_2u(sch_1):page77_i84@pure_quanta.q_cap(chips)',
 P_PATH='@s9s_mb_2u_lib.s9s_mb_2u(sch_1):page77_i84@pure_quanta.q_cap(chips)',
 PATH='I84',
 DRAWING='@S9S_MB_2U_LIB.S9S_MB_2U(SCH_1):PAGE77',
 PHYS_PAGE='77',
 XY='(-4125,6150)',
 ROT='0',
 VER='1',
 PACK_TYPE='C0402',
 CDS_LIB='pure_quanta',
 CDS_PART_NAME='Q_CAP_C0402-10UF,6.3V,20%,X6S,B',
 TOLERANCE='20%',
 MATERIAL='X6S',
 VOLTAGE='6.3V',
 VALUE='10UF',
 PRIM_FILE='./archive_libs/logical/q_cap/chips/chips.prt';

PART_NAME
 C258 'Q_CAP_C0402-10UF,6.3V,20%,X6S,B':;

SECTION_NUMBER 1
 '@S9S_MB_2U_LIB.S9S_MB_2U(SCH_1):PAGE77_I81@PURE_QUANTA.Q_CAP(CHIPS)':
 C_PATH='@s9s_mb_2u_lib.s9s_mb_2u(sch_1):page77_i81@pure_quanta.q_cap(chips)',
 P_PATH='@s9s_mb_2u_lib.s9s_mb_2u(sch_1):page77_i81@pure_quanta.q_cap(chips)',
 PATH='I81',
 DRAWING='@S9S_MB_2U_LIB.S9S_MB_2U(SCH_1):PAGE77',
 PHYS_PAGE='77',
 XY='(-4100,5400)',
 ROT='0',
 VER='1',
 PACK_TYPE='C0402',
 CDS_LIB='pure_quanta',
 CDS_PART_NAME='Q_CAP_C0402-10UF,6.3V,20%,X6S,B',
 TOLERANCE='20%',
 MATERIAL='X6S',
 VOLTAGE='6.3V',
 VALUE='10UF',
 PRIM_FILE='./archive_libs/logical/q_cap/chips/chips.prt';

PART_NAME
 C259 'Q_CAP_C0402-10UF,6.3V,20%,X6S,B':;

SECTION_NUMBER 1
 '@S9S_MB_2U_LIB.S9S_MB_2U(SCH_1):PAGE77_I52@PURE_QUANTA.Q_CAP(CHIPS)':
 C_PATH='@s9s_mb_2u_lib.s9s_mb_2u(sch_1):page77_i52@pure_quanta.q_cap(chips)',
 P_PATH='@s9s_mb_2u_lib.s9s_mb_2u(sch_1):page77_i52@pure_quanta.q_cap(chips)',
 PATH='I52',
 DRAWING='@S9S_MB_2U_LIB.S9S_MB_2U(SCH_1):PAGE77',
 PHYS_PAGE='77',
 XY='(-4100,4625)',
 ROT='0',
 VER='1',
 PACK_TYPE='C0402',
 CDS_LIB='pure_quanta',
 CDS_PART_NAME='Q_CAP_C0402-10UF,6.3V,20%,X6S,B',
 TOLERANCE='20%',
 MATERIAL='X6S',
 VOLTAGE='6.3V',
 VALUE='10UF',
 PRIM_FILE='./archive_libs/logical/q_cap/chips/chips.prt';

PART_NAME
 C260 'Q_CAP_C0805-47UF,4V,20%,X6S,CHA':;

SECTION_NUMBER 1
 '@S9S_MB_2U_LIB.S9S_MB_2U(SCH_1):PAGE77_I50@PURE_QUANTA.Q_CAP(CHIPS)':
 C_PATH='@s9s_mb_2u_lib.s9s_mb_2u(sch_1):page77_i50@pure_quanta.q_cap(chips)',
 P_PATH='@s9s_mb_2u_lib.s9s_mb_2u(sch_1):page77_i50@pure_quanta.q_cap(chips)',
 PATH='I50',
 DRAWING='@S9S_MB_2U_LIB.S9S_MB_2U(SCH_1):PAGE77',
 PHYS_PAGE='77',
 XY='(-4100,3850)',
 ROT='0',
 VER='1',
 PACK_TYPE='C0805',
 CDS_LIB='pure_quanta',
 CDS_PART_NAME='Q_CAP_C0805-47UF,4V,20%,X6S,CHA',
 TOLERANCE='20%',
 MATERIAL='X6S',
 VOLTAGE='4V',
 VALUE='47UF',
 PRIM_FILE='./archive_libs/logical/q_cap/chips/chips.prt';

PART_NAME
 C261 'Q_CAP_C0402-10UF,6.3V,20%,X6S,B':;

SECTION_NUMBER 1
 '@S9S_MB_2U_LIB.S9S_MB_2U(SCH_1):PAGE77_I95@PURE_QUANTA.Q_CAP(CHIPS)':
 C_PATH='@s9s_mb_2u_lib.s9s_mb_2u(sch_1):page77_i95@pure_quanta.q_cap(chips)',
 P_PATH='@s9s_mb_2u_lib.s9s_mb_2u(sch_1):page77_i95@pure_quanta.q_cap(chips)',
 PATH='I95',
 DRAWING='@S9S_MB_2U_LIB.S9S_MB_2U(SCH_1):PAGE77',
 PHYS_PAGE='77',
 XY='(-3675,6925)',
 ROT='0',
 VER='1',
 PACK_TYPE='C0402',
 CDS_LIB='pure_quanta',
 CDS_PART_NAME='Q_CAP_C0402-10UF,6.3V,20%,X6S,B',
 TOLERANCE='20%',
 MATERIAL='X6S',
 VOLTAGE='6.3V',
 VALUE='10UF',
 PRIM_FILE='./archive_libs/logical/q_cap/chips/chips.prt';

PART_NAME
 C262 'Q_CAP_C0402-10UF,6.3V,20%,X6S,B':;

SECTION_NUMBER 1
 '@S9S_MB_2U_LIB.S9S_MB_2U(SCH_1):PAGE77_I93@PURE_QUANTA.Q_CAP(CHIPS)':
 C_PATH='@s9s_mb_2u_lib.s9s_mb_2u(sch_1):page77_i93@pure_quanta.q_cap(chips)',
 P_PATH='@s9s_mb_2u_lib.s9s_mb_2u(sch_1):page77_i93@pure_quanta.q_cap(chips)',
 PATH='I93',
 DRAWING='@S9S_MB_2U_LIB.S9S_MB_2U(SCH_1):PAGE77',
 PHYS_PAGE='77',
 XY='(-3675,6150)',
 ROT='0',
 VER='1',
 PACK_TYPE='C0402',
 CDS_LIB='pure_quanta',
 CDS_PART_NAME='Q_CAP_C0402-10UF,6.3V,20%,X6S,B',
 TOLERANCE='20%',
 MATERIAL='X6S',
 VOLTAGE='6.3V',
 VALUE='10UF',
 PRIM_FILE='./archive_libs/logical/q_cap/chips/chips.prt';

PART_NAME
 C263 'Q_CAP_C0402-10UF,6.3V,20%,X6S,B':;

SECTION_NUMBER 1
 '@S9S_MB_2U_LIB.S9S_MB_2U(SCH_1):PAGE77_I86@PURE_QUANTA.Q_CAP(CHIPS)':
 C_PATH='@s9s_mb_2u_lib.s9s_mb_2u(sch_1):page77_i86@pure_quanta.q_cap(chips)',
 P_PATH='@s9s_mb_2u_lib.s9s_mb_2u(sch_1):page77_i86@pure_quanta.q_cap(chips)',
 PATH='I86',
 DRAWING='@S9S_MB_2U_LIB.S9S_MB_2U(SCH_1):PAGE77',
 PHYS_PAGE='77',
 XY='(-3650,5400)',
 ROT='0',
 VER='1',
 PACK_TYPE='C0402',
 CDS_LIB='pure_quanta',
 CDS_PART_NAME='Q_CAP_C0402-10UF,6.3V,20%,X6S,B',
 TOLERANCE='20%',
 MATERIAL='X6S',
 VOLTAGE='6.3V',
 VALUE='10UF',
 PRIM_FILE='./archive_libs/logical/q_cap/chips/chips.prt';

PART_NAME
 C264 'Q_CAP_C0402-10UF,6.3V,20%,X6S,B':;

SECTION_NUMBER 1
 '@S9S_MB_2U_LIB.S9S_MB_2U(SCH_1):PAGE77_I63@PURE_QUANTA.Q_CAP(CHIPS)':
 C_PATH='@s9s_mb_2u_lib.s9s_mb_2u(sch_1):page77_i63@pure_quanta.q_cap(chips)',
 P_PATH='@s9s_mb_2u_lib.s9s_mb_2u(sch_1):page77_i63@pure_quanta.q_cap(chips)',
 PATH='I63',
 DRAWING='@S9S_MB_2U_LIB.S9S_MB_2U(SCH_1):PAGE77',
 PHYS_PAGE='77',
 XY='(-3650,4625)',
 ROT='0',
 VER='1',
 PACK_TYPE='C0402',
 CDS_LIB='pure_quanta',
 CDS_PART_NAME='Q_CAP_C0402-10UF,6.3V,20%,X6S,B',
 TOLERANCE='20%',
 MATERIAL='X6S',
 VOLTAGE='6.3V',
 VALUE='10UF',
 PRIM_FILE='./archive_libs/logical/q_cap/chips/chips.prt';

PART_NAME
 C265 'Q_CAP_C0805-47UF,4V,20%,X6S,CHA':;

SECTION_NUMBER 1
 '@S9S_MB_2U_LIB.S9S_MB_2U(SCH_1):PAGE77_I59@PURE_QUANTA.Q_CAP(CHIPS)':
 C_PATH='@s9s_mb_2u_lib.s9s_mb_2u(sch_1):page77_i59@pure_quanta.q_cap(chips)',
 P_PATH='@s9s_mb_2u_lib.s9s_mb_2u(sch_1):page77_i59@pure_quanta.q_cap(chips)',
 PATH='I59',
 DRAWING='@S9S_MB_2U_LIB.S9S_MB_2U(SCH_1):PAGE77',
 PHYS_PAGE='77',
 XY='(-3650,3850)',
 ROT='0',
 VER='1',
 PACK_TYPE='C0805',
 CDS_LIB='pure_quanta',
 CDS_PART_NAME='Q_CAP_C0805-47UF,4V,20%,X6S,CHA',
 TOLERANCE='20%',
 MATERIAL='X6S',
 VOLTAGE='4V',
 VALUE='47UF',
 PRIM_FILE='./archive_libs/logical/q_cap/chips/chips.prt';

PART_NAME
 C266 'Q_CAP_C0402-10UF,6.3V,20%,X6S,B':;

SECTION_NUMBER 1
 '@S9S_MB_2U_LIB.S9S_MB_2U(SCH_1):PAGE77_I97@PURE_QUANTA.Q_CAP(CHIPS)':
 C_PATH='@s9s_mb_2u_lib.s9s_mb_2u(sch_1):page77_i97@pure_quanta.q_cap(chips)',
 P_PATH='@s9s_mb_2u_lib.s9s_mb_2u(sch_1):page77_i97@pure_quanta.q_cap(chips)',
 PATH='I97',
 DRAWING='@S9S_MB_2U_LIB.S9S_MB_2U(SCH_1):PAGE77',
 PHYS_PAGE='77',
 XY='(-3225,6925)',
 ROT='0',
 VER='1',
 PACK_TYPE='C0402',
 CDS_LIB='pure_quanta',
 CDS_PART_NAME='Q_CAP_C0402-10UF,6.3V,20%,X6S,B',
 TOLERANCE='20%',
 MATERIAL='X6S',
 VOLTAGE='6.3V',
 VALUE='10UF',
 PRIM_FILE='./archive_libs/logical/q_cap/chips/chips.prt';

PART_NAME
 C267 'Q_CAP_C0402-10UF,6.3V,20%,X6S,B':;

SECTION_NUMBER 1
 '@S9S_MB_2U_LIB.S9S_MB_2U(SCH_1):PAGE77_I94@PURE_QUANTA.Q_CAP(CHIPS)':
 C_PATH='@s9s_mb_2u_lib.s9s_mb_2u(sch_1):page77_i94@pure_quanta.q_cap(chips)',
 P_PATH='@s9s_mb_2u_lib.s9s_mb_2u(sch_1):page77_i94@pure_quanta.q_cap(chips)',
 PATH='I94',
 DRAWING='@S9S_MB_2U_LIB.S9S_MB_2U(SCH_1):PAGE77',
 PHYS_PAGE='77',
 XY='(-3225,6150)',
 ROT='0',
 VER='1',
 PACK_TYPE='C0402',
 CDS_LIB='pure_quanta',
 CDS_PART_NAME='Q_CAP_C0402-10UF,6.3V,20%,X6S,B',
 TOLERANCE='20%',
 MATERIAL='X6S',
 VOLTAGE='6.3V',
 VALUE='10UF',
 PRIM_FILE='./archive_libs/logical/q_cap/chips/chips.prt';

PART_NAME
 C268 'Q_CAP_C0402-10UF,6.3V,20%,X6S,B':;

SECTION_NUMBER 1
 '@S9S_MB_2U_LIB.S9S_MB_2U(SCH_1):PAGE77_I88@PURE_QUANTA.Q_CAP(CHIPS)':
 C_PATH='@s9s_mb_2u_lib.s9s_mb_2u(sch_1):page77_i88@pure_quanta.q_cap(chips)',
 P_PATH='@s9s_mb_2u_lib.s9s_mb_2u(sch_1):page77_i88@pure_quanta.q_cap(chips)',
 PATH='I88',
 DRAWING='@S9S_MB_2U_LIB.S9S_MB_2U(SCH_1):PAGE77',
 PHYS_PAGE='77',
 XY='(-3200,5400)',
 ROT='0',
 VER='1',
 PACK_TYPE='C0402',
 CDS_LIB='pure_quanta',
 CDS_PART_NAME='Q_CAP_C0402-10UF,6.3V,20%,X6S,B',
 TOLERANCE='20%',
 MATERIAL='X6S',
 VOLTAGE='6.3V',
 VALUE='10UF',
 PRIM_FILE='./archive_libs/logical/q_cap/chips/chips.prt';

PART_NAME
 C269 'Q_CAP_C0402-10UF,6.3V,20%,X6S,B':;

SECTION_NUMBER 1
 '@S9S_MB_2U_LIB.S9S_MB_2U(SCH_1):PAGE77_I64@PURE_QUANTA.Q_CAP(CHIPS)':
 C_PATH='@s9s_mb_2u_lib.s9s_mb_2u(sch_1):page77_i64@pure_quanta.q_cap(chips)',
 P_PATH='@s9s_mb_2u_lib.s9s_mb_2u(sch_1):page77_i64@pure_quanta.q_cap(chips)',
 PATH='I64',
 DRAWING='@S9S_MB_2U_LIB.S9S_MB_2U(SCH_1):PAGE77',
 PHYS_PAGE='77',
 XY='(-3200,4625)',
 ROT='0',
 VER='1',
 PACK_TYPE='C0402',
 CDS_LIB='pure_quanta',
 CDS_PART_NAME='Q_CAP_C0402-10UF,6.3V,20%,X6S,B',
 TOLERANCE='20%',
 MATERIAL='X6S',
 VOLTAGE='6.3V',
 VALUE='10UF',
 PRIM_FILE='./archive_libs/logical/q_cap/chips/chips.prt';

PART_NAME
 C270 'Q_CAP_C0805-47UF,4V,20%,X6S,CHA':;

SECTION_NUMBER 1
 '@S9S_MB_2U_LIB.S9S_MB_2U(SCH_1):PAGE77_I62@PURE_QUANTA.Q_CAP(CHIPS)':
 C_PATH='@s9s_mb_2u_lib.s9s_mb_2u(sch_1):page77_i62@pure_quanta.q_cap(chips)',
 P_PATH='@s9s_mb_2u_lib.s9s_mb_2u(sch_1):page77_i62@pure_quanta.q_cap(chips)',
 PATH='I62',
 DRAWING='@S9S_MB_2U_LIB.S9S_MB_2U(SCH_1):PAGE77',
 PHYS_PAGE='77',
 XY='(-3200,3850)',
 ROT='0',
 VER='1',
 PACK_TYPE='C0805',
 CDS_LIB='pure_quanta',
 CDS_PART_NAME='Q_CAP_C0805-47UF,4V,20%,X6S,CHA',
 TOLERANCE='20%',
 MATERIAL='X6S',
 VOLTAGE='4V',
 VALUE='47UF',
 PRIM_FILE='./archive_libs/logical/q_cap/chips/chips.prt';

PART_NAME
 C271 'Q_CAP_C0402-22UF,4V,20%,X6S,CHA':;

SECTION_NUMBER 1
 '@S9S_MB_2U_LIB.S9S_MB_2U(SCH_1):PAGE77_I100@PURE_QUANTA.Q_CAP(CHIPS)':
 C_PATH='@s9s_mb_2u_lib.s9s_mb_2u(sch_1):page77_i100@pure_quanta.q_cap(chips)',
 P_PATH='@s9s_mb_2u_lib.s9s_mb_2u(sch_1):page77_i100@pure_quanta.q_cap(chips)',
 PATH='I100',
 DRAWING='@S9S_MB_2U_LIB.S9S_MB_2U(SCH_1):PAGE77',
 PHYS_PAGE='77',
 XY='(-2750,6925)',
 ROT='0',
 VER='1',
 PACK_TYPE='C0402',
 CDS_LIB='pure_quanta',
 CDS_PART_NAME='Q_CAP_C0402-22UF,4V,20%,X6S,CHA',
 TOLERANCE='20%',
 MATERIAL='X6S',
 VOLTAGE='4V',
 VALUE='22UF',
 PRIM_FILE='./archive_libs/logical/q_cap/chips/chips.prt';

PART_NAME
 C272 'Q_CAP_C0402-22UF,4V,20%,X6S,CHA':;

SECTION_NUMBER 1
 '@S9S_MB_2U_LIB.S9S_MB_2U(SCH_1):PAGE77_I98@PURE_QUANTA.Q_CAP(CHIPS)':
 C_PATH='@s9s_mb_2u_lib.s9s_mb_2u(sch_1):page77_i98@pure_quanta.q_cap(chips)',
 P_PATH='@s9s_mb_2u_lib.s9s_mb_2u(sch_1):page77_i98@pure_quanta.q_cap(chips)',
 PATH='I98',
 DRAWING='@S9S_MB_2U_LIB.S9S_MB_2U(SCH_1):PAGE77',
 PHYS_PAGE='77',
 XY='(-2750,6150)',
 ROT='0',
 VER='1',
 PACK_TYPE='C0402',
 CDS_LIB='pure_quanta',
 CDS_PART_NAME='Q_CAP_C0402-22UF,4V,20%,X6S,CHA',
 TOLERANCE='20%',
 MATERIAL='X6S',
 VOLTAGE='4V',
 VALUE='22UF',
 PRIM_FILE='./archive_libs/logical/q_cap/chips/chips.prt';

PART_NAME
 C273 'Q_CAP_C0402-22UF,4V,20%,X6S,CHA':;

SECTION_NUMBER 1
 '@S9S_MB_2U_LIB.S9S_MB_2U(SCH_1):PAGE77_I91@PURE_QUANTA.Q_CAP(CHIPS)':
 C_PATH='@s9s_mb_2u_lib.s9s_mb_2u(sch_1):page77_i91@pure_quanta.q_cap(chips)',
 P_PATH='@s9s_mb_2u_lib.s9s_mb_2u(sch_1):page77_i91@pure_quanta.q_cap(chips)',
 PATH='I91',
 DRAWING='@S9S_MB_2U_LIB.S9S_MB_2U(SCH_1):PAGE77',
 PHYS_PAGE='77',
 XY='(-2725,5400)',
 ROT='0',
 VER='1',
 PACK_TYPE='C0402',
 CDS_LIB='pure_quanta',
 CDS_PART_NAME='Q_CAP_C0402-22UF,4V,20%,X6S,CHA',
 TOLERANCE='20%',
 MATERIAL='X6S',
 VOLTAGE='4V',
 VALUE='22UF',
 PRIM_FILE='./archive_libs/logical/q_cap/chips/chips.prt';

PART_NAME
 C274 'Q_CAP_C0402-22UF,4V,20%,X6S,CHA':;

SECTION_NUMBER 1
 '@S9S_MB_2U_LIB.S9S_MB_2U(SCH_1):PAGE77_I66@PURE_QUANTA.Q_CAP(CHIPS)':
 C_PATH='@s9s_mb_2u_lib.s9s_mb_2u(sch_1):page77_i66@pure_quanta.q_cap(chips)',
 P_PATH='@s9s_mb_2u_lib.s9s_mb_2u(sch_1):page77_i66@pure_quanta.q_cap(chips)',
 PATH='I66',
 DRAWING='@S9S_MB_2U_LIB.S9S_MB_2U(SCH_1):PAGE77',
 PHYS_PAGE='77',
 XY='(-2725,4625)',
 ROT='0',
 VER='1',
 PACK_TYPE='C0402',
 CDS_LIB='pure_quanta',
 CDS_PART_NAME='Q_CAP_C0402-22UF,4V,20%,X6S,CHA',
 TOLERANCE='20%',
 MATERIAL='X6S',
 VOLTAGE='4V',
 VALUE='22UF',
 PRIM_FILE='./archive_libs/logical/q_cap/chips/chips.prt';

PART_NAME
 C275 'Q_CAP_C0402-22UF,4V,20%,X6S,CHA':;

SECTION_NUMBER 1
 '@S9S_MB_2U_LIB.S9S_MB_2U(SCH_1):PAGE77_I104@PURE_QUANTA.Q_CAP(CHIPS)':
 C_PATH='@s9s_mb_2u_lib.s9s_mb_2u(sch_1):page77_i104@pure_quanta.q_cap(chips)',
 P_PATH='@s9s_mb_2u_lib.s9s_mb_2u(sch_1):page77_i104@pure_quanta.q_cap(chips)',
 PATH='I104',
 DRAWING='@S9S_MB_2U_LIB.S9S_MB_2U(SCH_1):PAGE77',
 PHYS_PAGE='77',
 XY='(-2300,6925)',
 ROT='0',
 VER='1',
 PACK_TYPE='C0402',
 CDS_LIB='pure_quanta',
 CDS_PART_NAME='Q_CAP_C0402-22UF,4V,20%,X6S,CHA',
 TOLERANCE='20%',
 MATERIAL='X6S',
 VOLTAGE='4V',
 VALUE='22UF',
 PRIM_FILE='./archive_libs/logical/q_cap/chips/chips.prt';

PART_NAME
 C276 'Q_CAP_C0402-22UF,4V,20%,X6S,CHA':;

SECTION_NUMBER 1
 '@S9S_MB_2U_LIB.S9S_MB_2U(SCH_1):PAGE77_I103@PURE_QUANTA.Q_CAP(CHIPS)':
 C_PATH='@s9s_mb_2u_lib.s9s_mb_2u(sch_1):page77_i103@pure_quanta.q_cap(chips)',
 P_PATH='@s9s_mb_2u_lib.s9s_mb_2u(sch_1):page77_i103@pure_quanta.q_cap(chips)',
 PATH='I103',
 DRAWING='@S9S_MB_2U_LIB.S9S_MB_2U(SCH_1):PAGE77',
 PHYS_PAGE='77',
 XY='(-2300,6150)',
 ROT='0',
 VER='1',
 PACK_TYPE='C0402',
 CDS_LIB='pure_quanta',
 CDS_PART_NAME='Q_CAP_C0402-22UF,4V,20%,X6S,CHA',
 TOLERANCE='20%',
 MATERIAL='X6S',
 VOLTAGE='4V',
 VALUE='22UF',
 PRIM_FILE='./archive_libs/logical/q_cap/chips/chips.prt';

PART_NAME
 C277 'Q_CAP_C0402-22UF,4V,20%,X6S,CHA':;

SECTION_NUMBER 1
 '@S9S_MB_2U_LIB.S9S_MB_2U(SCH_1):PAGE77_I101@PURE_QUANTA.Q_CAP(CHIPS)':
 C_PATH='@s9s_mb_2u_lib.s9s_mb_2u(sch_1):page77_i101@pure_quanta.q_cap(chips)',
 P_PATH='@s9s_mb_2u_lib.s9s_mb_2u(sch_1):page77_i101@pure_quanta.q_cap(chips)',
 PATH='I101',
 DRAWING='@S9S_MB_2U_LIB.S9S_MB_2U(SCH_1):PAGE77',
 PHYS_PAGE='77',
 XY='(-2275,5400)',
 ROT='0',
 VER='1',
 PACK_TYPE='C0402',
 CDS_LIB='pure_quanta',
 CDS_PART_NAME='Q_CAP_C0402-22UF,4V,20%,X6S,CHA',
 TOLERANCE='20%',
 MATERIAL='X6S',
 VOLTAGE='4V',
 VALUE='22UF',
 PRIM_FILE='./archive_libs/logical/q_cap/chips/chips.prt';

PART_NAME
 C278 'Q_CAP_C0402-22UF,4V,20%,X6S,CHA':;

SECTION_NUMBER 1
 '@S9S_MB_2U_LIB.S9S_MB_2U(SCH_1):PAGE77_I71@PURE_QUANTA.Q_CAP(CHIPS)':
 C_PATH='@s9s_mb_2u_lib.s9s_mb_2u(sch_1):page77_i71@pure_quanta.q_cap(chips)',
 P_PATH='@s9s_mb_2u_lib.s9s_mb_2u(sch_1):page77_i71@pure_quanta.q_cap(chips)',
 PATH='I71',
 DRAWING='@S9S_MB_2U_LIB.S9S_MB_2U(SCH_1):PAGE77',
 PHYS_PAGE='77',
 XY='(-2275,4625)',
 ROT='0',
 VER='1',
 PACK_TYPE='C0402',
 CDS_LIB='pure_quanta',
 CDS_PART_NAME='Q_CAP_C0402-22UF,4V,20%,X6S,CHA',
 TOLERANCE='20%',
 MATERIAL='X6S',
 VOLTAGE='4V',
 VALUE='22UF',
 PRIM_FILE='./archive_libs/logical/q_cap/chips/chips.prt';

PART_NAME
 C279 'Q_CAP_C0402-22UF,4V,20%,X6S,CHA':;

SECTION_NUMBER 1
 '@S9S_MB_2U_LIB.S9S_MB_2U(SCH_1):PAGE77_I106@PURE_QUANTA.Q_CAP(CHIPS)':
 C_PATH='@s9s_mb_2u_lib.s9s_mb_2u(sch_1):page77_i106@pure_quanta.q_cap(chips)',
 P_PATH='@s9s_mb_2u_lib.s9s_mb_2u(sch_1):page77_i106@pure_quanta.q_cap(chips)',
 PATH='I106',
 DRAWING='@S9S_MB_2U_LIB.S9S_MB_2U(SCH_1):PAGE77',
 PHYS_PAGE='77',
 XY='(-1850,6925)',
 ROT='0',
 VER='1',
 PACK_TYPE='C0402',
 CDS_LIB='pure_quanta',
 CDS_PART_NAME='Q_CAP_C0402-22UF,4V,20%,X6S,CHA',
 TOLERANCE='20%',
 MATERIAL='X6S',
 VOLTAGE='4V',
 VALUE='22UF',
 PRIM_FILE='./archive_libs/logical/q_cap/chips/chips.prt';

PART_NAME
 C280 'Q_CAP_C0402-22UF,4V,20%,X6S,CHA':;

SECTION_NUMBER 1
 '@S9S_MB_2U_LIB.S9S_MB_2U(SCH_1):PAGE77_I105@PURE_QUANTA.Q_CAP(CHIPS)':
 C_PATH='@s9s_mb_2u_lib.s9s_mb_2u(sch_1):page77_i105@pure_quanta.q_cap(chips)',
 P_PATH='@s9s_mb_2u_lib.s9s_mb_2u(sch_1):page77_i105@pure_quanta.q_cap(chips)',
 PATH='I105',
 DRAWING='@S9S_MB_2U_LIB.S9S_MB_2U(SCH_1):PAGE77',
 PHYS_PAGE='77',
 XY='(-1850,6150)',
 ROT='0',
 VER='1',
 PACK_TYPE='C0402',
 CDS_LIB='pure_quanta',
 CDS_PART_NAME='Q_CAP_C0402-22UF,4V,20%,X6S,CHA',
 TOLERANCE='20%',
 MATERIAL='X6S',
 VOLTAGE='4V',
 VALUE='22UF',
 PRIM_FILE='./archive_libs/logical/q_cap/chips/chips.prt';

PART_NAME
 C281 'Q_CAP_C0402-22UF,4V,20%,X6S,CHA':;

SECTION_NUMBER 1
 '@S9S_MB_2U_LIB.S9S_MB_2U(SCH_1):PAGE77_I102@PURE_QUANTA.Q_CAP(CHIPS)':
 C_PATH='@s9s_mb_2u_lib.s9s_mb_2u(sch_1):page77_i102@pure_quanta.q_cap(chips)',
 P_PATH='@s9s_mb_2u_lib.s9s_mb_2u(sch_1):page77_i102@pure_quanta.q_cap(chips)',
 PATH='I102',
 DRAWING='@S9S_MB_2U_LIB.S9S_MB_2U(SCH_1):PAGE77',
 PHYS_PAGE='77',
 XY='(-1825,5400)',
 ROT='0',
 VER='1',
 PACK_TYPE='C0402',
 CDS_LIB='pure_quanta',
 CDS_PART_NAME='Q_CAP_C0402-22UF,4V,20%,X6S,CHA',
 TOLERANCE='20%',
 MATERIAL='X6S',
 VOLTAGE='4V',
 VALUE='22UF',
 PRIM_FILE='./archive_libs/logical/q_cap/chips/chips.prt';

PART_NAME
 C282 'Q_CAP_C0402-22UF,4V,20%,X6S,CHA':;

SECTION_NUMBER 1
 '@S9S_MB_2U_LIB.S9S_MB_2U(SCH_1):PAGE77_I73@PURE_QUANTA.Q_CAP(CHIPS)':
 C_PATH='@s9s_mb_2u_lib.s9s_mb_2u(sch_1):page77_i73@pure_quanta.q_cap(chips)',
 P_PATH='@s9s_mb_2u_lib.s9s_mb_2u(sch_1):page77_i73@pure_quanta.q_cap(chips)',
 PATH='I73',
 DRAWING='@S9S_MB_2U_LIB.S9S_MB_2U(SCH_1):PAGE77',
 PHYS_PAGE='77',
 XY='(-1825,4625)',
 ROT='0',
 VER='1',
 PACK_TYPE='C0402',
 CDS_LIB='pure_quanta',
 CDS_PART_NAME='Q_CAP_C0402-22UF,4V,20%,X6S,CHA',
 TOLERANCE='20%',
 MATERIAL='X6S',
 VOLTAGE='4V',
 VALUE='22UF',
 PRIM_FILE='./archive_libs/logical/q_cap/chips/chips.prt';

PART_NAME
 C283 'Q_CAP_C0402-22UF,4V,20%,X6S,CHA':;

SECTION_NUMBER 1
 '@S9S_MB_2U_LIB.S9S_MB_2U(SCH_1):PAGE77_I122@PURE_QUANTA.Q_CAP(CHIPS)':
 C_PATH='@s9s_mb_2u_lib.s9s_mb_2u(sch_1):page77_i122@pure_quanta.q_cap(chips)',
 P_PATH='@s9s_mb_2u_lib.s9s_mb_2u(sch_1):page77_i122@pure_quanta.q_cap(chips)',
 PATH='I122',
 DRAWING='@S9S_MB_2U_LIB.S9S_MB_2U(SCH_1):PAGE77',
 PHYS_PAGE='77',
 XY='(-1400,6925)',
 ROT='0',
 VER='1',
 PACK_TYPE='C0402',
 CDS_LIB='pure_quanta',
 CDS_PART_NAME='Q_CAP_C0402-22UF,4V,20%,X6S,CHA',
 TOLERANCE='20%',
 MATERIAL='X6S',
 VOLTAGE='4V',
 VALUE='22UF',
 PRIM_FILE='./archive_libs/logical/q_cap/chips/chips.prt';

PART_NAME
 C284 'Q_CAP_C0402-22UF,4V,20%,X6S,CHA':;

SECTION_NUMBER 1
 '@S9S_MB_2U_LIB.S9S_MB_2U(SCH_1):PAGE77_I121@PURE_QUANTA.Q_CAP(CHIPS)':
 C_PATH='@s9s_mb_2u_lib.s9s_mb_2u(sch_1):page77_i121@pure_quanta.q_cap(chips)',
 P_PATH='@s9s_mb_2u_lib.s9s_mb_2u(sch_1):page77_i121@pure_quanta.q_cap(chips)',
 PATH='I121',
 DRAWING='@S9S_MB_2U_LIB.S9S_MB_2U(SCH_1):PAGE77',
 PHYS_PAGE='77',
 XY='(-1400,6150)',
 ROT='0',
 VER='1',
 PACK_TYPE='C0402',
 CDS_LIB='pure_quanta',
 CDS_PART_NAME='Q_CAP_C0402-22UF,4V,20%,X6S,CHA',
 TOLERANCE='20%',
 MATERIAL='X6S',
 VOLTAGE='4V',
 VALUE='22UF',
 PRIM_FILE='./archive_libs/logical/q_cap/chips/chips.prt';

PART_NAME
 C285 'Q_CAP_C0402-22UF,4V,20%,X6S,CHA':;

SECTION_NUMBER 1
 '@S9S_MB_2U_LIB.S9S_MB_2U(SCH_1):PAGE77_I119@PURE_QUANTA.Q_CAP(CHIPS)':
 C_PATH='@s9s_mb_2u_lib.s9s_mb_2u(sch_1):page77_i119@pure_quanta.q_cap(chips)',
 P_PATH='@s9s_mb_2u_lib.s9s_mb_2u(sch_1):page77_i119@pure_quanta.q_cap(chips)',
 PATH='I119',
 DRAWING='@S9S_MB_2U_LIB.S9S_MB_2U(SCH_1):PAGE77',
 PHYS_PAGE='77',
 XY='(-1375,5400)',
 ROT='0',
 VER='1',
 PACK_TYPE='C0402',
 CDS_LIB='pure_quanta',
 CDS_PART_NAME='Q_CAP_C0402-22UF,4V,20%,X6S,CHA',
 TOLERANCE='20%',
 MATERIAL='X6S',
 VOLTAGE='4V',
 VALUE='22UF',
 PRIM_FILE='./archive_libs/logical/q_cap/chips/chips.prt';

PART_NAME
 C286 'Q_CAP_C0402-22UF,4V,20%,X6S,CHA':;

SECTION_NUMBER 1
 '@S9S_MB_2U_LIB.S9S_MB_2U(SCH_1):PAGE77_I111@PURE_QUANTA.Q_CAP(CHIPS)':
 C_PATH='@s9s_mb_2u_lib.s9s_mb_2u(sch_1):page77_i111@pure_quanta.q_cap(chips)',
 P_PATH='@s9s_mb_2u_lib.s9s_mb_2u(sch_1):page77_i111@pure_quanta.q_cap(chips)',
 PATH='I111',
 DRAWING='@S9S_MB_2U_LIB.S9S_MB_2U(SCH_1):PAGE77',
 PHYS_PAGE='77',
 XY='(-1375,4625)',
 ROT='0',
 VER='1',
 PACK_TYPE='C0402',
 CDS_LIB='pure_quanta',
 CDS_PART_NAME='Q_CAP_C0402-22UF,4V,20%,X6S,CHA',
 TOLERANCE='20%',
 MATERIAL='X6S',
 VOLTAGE='4V',
 VALUE='22UF',
 PRIM_FILE='./archive_libs/logical/q_cap/chips/chips.prt';

PART_NAME
 C287 'Q_CAP_C0402-22UF,4V,20%,X6S,CHA':;

SECTION_NUMBER 1
 '@S9S_MB_2U_LIB.S9S_MB_2U(SCH_1):PAGE77_I124@PURE_QUANTA.Q_CAP(CHIPS)':
 C_PATH='@s9s_mb_2u_lib.s9s_mb_2u(sch_1):page77_i124@pure_quanta.q_cap(chips)',
 P_PATH='@s9s_mb_2u_lib.s9s_mb_2u(sch_1):page77_i124@pure_quanta.q_cap(chips)',
 PATH='I124',
 DRAWING='@S9S_MB_2U_LIB.S9S_MB_2U(SCH_1):PAGE77',
 PHYS_PAGE='77',
 XY='(-950,6925)',
 ROT='0',
 VER='1',
 PACK_TYPE='C0402',
 CDS_LIB='pure_quanta',
 CDS_PART_NAME='Q_CAP_C0402-22UF,4V,20%,X6S,CHA',
 TOLERANCE='20%',
 MATERIAL='X6S',
 VOLTAGE='4V',
 VALUE='22UF',
 PRIM_FILE='./archive_libs/logical/q_cap/chips/chips.prt';

PART_NAME
 C288 'Q_CAP_C0402-22UF,4V,20%,X6S,CHA':;

SECTION_NUMBER 1
 '@S9S_MB_2U_LIB.S9S_MB_2U(SCH_1):PAGE77_I123@PURE_QUANTA.Q_CAP(CHIPS)':
 C_PATH='@s9s_mb_2u_lib.s9s_mb_2u(sch_1):page77_i123@pure_quanta.q_cap(chips)',
 P_PATH='@s9s_mb_2u_lib.s9s_mb_2u(sch_1):page77_i123@pure_quanta.q_cap(chips)',
 PATH='I123',
 DRAWING='@S9S_MB_2U_LIB.S9S_MB_2U(SCH_1):PAGE77',
 PHYS_PAGE='77',
 XY='(-950,6150)',
 ROT='0',
 VER='1',
 PACK_TYPE='C0402',
 CDS_LIB='pure_quanta',
 CDS_PART_NAME='Q_CAP_C0402-22UF,4V,20%,X6S,CHA',
 TOLERANCE='20%',
 MATERIAL='X6S',
 VOLTAGE='4V',
 VALUE='22UF',
 PRIM_FILE='./archive_libs/logical/q_cap/chips/chips.prt';

PART_NAME
 C289 'Q_CAP_C0402-22UF,4V,20%,X6S,CHA':;

SECTION_NUMBER 1
 '@S9S_MB_2U_LIB.S9S_MB_2U(SCH_1):PAGE77_I120@PURE_QUANTA.Q_CAP(CHIPS)':
 C_PATH='@s9s_mb_2u_lib.s9s_mb_2u(sch_1):page77_i120@pure_quanta.q_cap(chips)',
 P_PATH='@s9s_mb_2u_lib.s9s_mb_2u(sch_1):page77_i120@pure_quanta.q_cap(chips)',
 PATH='I120',
 DRAWING='@S9S_MB_2U_LIB.S9S_MB_2U(SCH_1):PAGE77',
 PHYS_PAGE='77',
 XY='(-925,5400)',
 ROT='0',
 VER='1',
 PACK_TYPE='C0402',
 CDS_LIB='pure_quanta',
 CDS_PART_NAME='Q_CAP_C0402-22UF,4V,20%,X6S,CHA',
 TOLERANCE='20%',
 MATERIAL='X6S',
 VOLTAGE='4V',
 VALUE='22UF',
 PRIM_FILE='./archive_libs/logical/q_cap/chips/chips.prt';

PART_NAME
 C290 'Q_CAP_C0402-22UF,4V,20%,X6S,CHA':;

SECTION_NUMBER 1
 '@S9S_MB_2U_LIB.S9S_MB_2U(SCH_1):PAGE77_I112@PURE_QUANTA.Q_CAP(CHIPS)':
 C_PATH='@s9s_mb_2u_lib.s9s_mb_2u(sch_1):page77_i112@pure_quanta.q_cap(chips)',
 P_PATH='@s9s_mb_2u_lib.s9s_mb_2u(sch_1):page77_i112@pure_quanta.q_cap(chips)',
 PATH='I112',
 DRAWING='@S9S_MB_2U_LIB.S9S_MB_2U(SCH_1):PAGE77',
 PHYS_PAGE='77',
 XY='(-925,4625)',
 ROT='0',
 VER='1',
 PACK_TYPE='C0402',
 CDS_LIB='pure_quanta',
 CDS_PART_NAME='Q_CAP_C0402-22UF,4V,20%,X6S,CHA',
 TOLERANCE='20%',
 MATERIAL='X6S',
 VOLTAGE='4V',
 VALUE='22UF',
 PRIM_FILE='./archive_libs/logical/q_cap/chips/chips.prt';

PART_NAME
 C291 'Q_CAP_C0402-22UF,4V,20%,X6S,CHA':;

SECTION_NUMBER 1
 '@S9S_MB_2U_LIB.S9S_MB_2U(SCH_1):PAGE77_I128@PURE_QUANTA.Q_CAP(CHIPS)':
 C_PATH='@s9s_mb_2u_lib.s9s_mb_2u(sch_1):page77_i128@pure_quanta.q_cap(chips)',
 P_PATH='@s9s_mb_2u_lib.s9s_mb_2u(sch_1):page77_i128@pure_quanta.q_cap(chips)',
 PATH='I128',
 DRAWING='@S9S_MB_2U_LIB.S9S_MB_2U(SCH_1):PAGE77',
 PHYS_PAGE='77',
 XY='(-500,6925)',
 ROT='0',
 VER='1',
 PACK_TYPE='C0402',
 CDS_LIB='pure_quanta',
 CDS_PART_NAME='Q_CAP_C0402-22UF,4V,20%,X6S,CHA',
 TOLERANCE='20%',
 MATERIAL='X6S',
 VOLTAGE='4V',
 VALUE='22UF',
 PRIM_FILE='./archive_libs/logical/q_cap/chips/chips.prt';

PART_NAME
 C292 'Q_CAP_C0402-22UF,4V,20%,X6S,CHA':;

SECTION_NUMBER 1
 '@S9S_MB_2U_LIB.S9S_MB_2U(SCH_1):PAGE77_I127@PURE_QUANTA.Q_CAP(CHIPS)':
 C_PATH='@s9s_mb_2u_lib.s9s_mb_2u(sch_1):page77_i127@pure_quanta.q_cap(chips)',
 P_PATH='@s9s_mb_2u_lib.s9s_mb_2u(sch_1):page77_i127@pure_quanta.q_cap(chips)',
 PATH='I127',
 DRAWING='@S9S_MB_2U_LIB.S9S_MB_2U(SCH_1):PAGE77',
 PHYS_PAGE='77',
 XY='(-500,6150)',
 ROT='0',
 VER='1',
 PACK_TYPE='C0402',
 CDS_LIB='pure_quanta',
 CDS_PART_NAME='Q_CAP_C0402-22UF,4V,20%,X6S,CHA',
 TOLERANCE='20%',
 MATERIAL='X6S',
 VOLTAGE='4V',
 VALUE='22UF',
 PRIM_FILE='./archive_libs/logical/q_cap/chips/chips.prt';

PART_NAME
 C293 'Q_CAP_C0402-22UF,4V,20%,X6S,CHA':;

SECTION_NUMBER 1
 '@S9S_MB_2U_LIB.S9S_MB_2U(SCH_1):PAGE77_I125@PURE_QUANTA.Q_CAP(CHIPS)':
 C_PATH='@s9s_mb_2u_lib.s9s_mb_2u(sch_1):page77_i125@pure_quanta.q_cap(chips)',
 P_PATH='@s9s_mb_2u_lib.s9s_mb_2u(sch_1):page77_i125@pure_quanta.q_cap(chips)',
 PATH='I125',
 DRAWING='@S9S_MB_2U_LIB.S9S_MB_2U(SCH_1):PAGE77',
 PHYS_PAGE='77',
 XY='(-475,5400)',
 ROT='0',
 VER='1',
 PACK_TYPE='C0402',
 CDS_LIB='pure_quanta',
 CDS_PART_NAME='Q_CAP_C0402-22UF,4V,20%,X6S,CHA',
 TOLERANCE='20%',
 MATERIAL='X6S',
 VOLTAGE='4V',
 VALUE='22UF',
 PRIM_FILE='./archive_libs/logical/q_cap/chips/chips.prt';

PART_NAME
 C294 'Q_CAP_C0402-22UF,4V,20%,X6S,CHA':;

SECTION_NUMBER 1
 '@S9S_MB_2U_LIB.S9S_MB_2U(SCH_1):PAGE77_I114@PURE_QUANTA.Q_CAP(CHIPS)':
 C_PATH='@s9s_mb_2u_lib.s9s_mb_2u(sch_1):page77_i114@pure_quanta.q_cap(chips)',
 P_PATH='@s9s_mb_2u_lib.s9s_mb_2u(sch_1):page77_i114@pure_quanta.q_cap(chips)',
 PATH='I114',
 DRAWING='@S9S_MB_2U_LIB.S9S_MB_2U(SCH_1):PAGE77',
 PHYS_PAGE='77',
 XY='(-475,4625)',
 ROT='0',
 VER='1',
 PACK_TYPE='C0402',
 CDS_LIB='pure_quanta',
 CDS_PART_NAME='Q_CAP_C0402-22UF,4V,20%,X6S,CHA',
 TOLERANCE='20%',
 MATERIAL='X6S',
 VOLTAGE='4V',
 VALUE='22UF',
 PRIM_FILE='./archive_libs/logical/q_cap/chips/chips.prt';

PART_NAME
 C295 'Q_CAP_C0402-22UF,4V,20%,X6S,CHA':;

SECTION_NUMBER 1
 '@S9S_MB_2U_LIB.S9S_MB_2U(SCH_1):PAGE77_I130@PURE_QUANTA.Q_CAP(CHIPS)':
 C_PATH='@s9s_mb_2u_lib.s9s_mb_2u(sch_1):page77_i130@pure_quanta.q_cap(chips)',
 P_PATH='@s9s_mb_2u_lib.s9s_mb_2u(sch_1):page77_i130@pure_quanta.q_cap(chips)',
 PATH='I130',
 DRAWING='@S9S_MB_2U_LIB.S9S_MB_2U(SCH_1):PAGE77',
 PHYS_PAGE='77',
 XY='(-50,6925)',
 ROT='0',
 VER='1',
 PACK_TYPE='C0402',
 CDS_LIB='pure_quanta',
 CDS_PART_NAME='Q_CAP_C0402-22UF,4V,20%,X6S,CHA',
 TOLERANCE='20%',
 MATERIAL='X6S',
 VOLTAGE='4V',
 VALUE='22UF',
 PRIM_FILE='./archive_libs/logical/q_cap/chips/chips.prt';

PART_NAME
 C296 'Q_CAP_C0402-22UF,4V,20%,X6S,CHA':;

SECTION_NUMBER 1
 '@S9S_MB_2U_LIB.S9S_MB_2U(SCH_1):PAGE77_I129@PURE_QUANTA.Q_CAP(CHIPS)':
 C_PATH='@s9s_mb_2u_lib.s9s_mb_2u(sch_1):page77_i129@pure_quanta.q_cap(chips)',
 P_PATH='@s9s_mb_2u_lib.s9s_mb_2u(sch_1):page77_i129@pure_quanta.q_cap(chips)',
 PATH='I129',
 DRAWING='@S9S_MB_2U_LIB.S9S_MB_2U(SCH_1):PAGE77',
 PHYS_PAGE='77',
 XY='(-50,6150)',
 ROT='0',
 VER='1',
 PACK_TYPE='C0402',
 CDS_LIB='pure_quanta',
 CDS_PART_NAME='Q_CAP_C0402-22UF,4V,20%,X6S,CHA',
 TOLERANCE='20%',
 MATERIAL='X6S',
 VOLTAGE='4V',
 VALUE='22UF',
 PRIM_FILE='./archive_libs/logical/q_cap/chips/chips.prt';

PART_NAME
 C297 'Q_CAP_C0402-22UF,4V,20%,X6S,CHA':;

SECTION_NUMBER 1
 '@S9S_MB_2U_LIB.S9S_MB_2U(SCH_1):PAGE77_I126@PURE_QUANTA.Q_CAP(CHIPS)':
 C_PATH='@s9s_mb_2u_lib.s9s_mb_2u(sch_1):page77_i126@pure_quanta.q_cap(chips)',
 P_PATH='@s9s_mb_2u_lib.s9s_mb_2u(sch_1):page77_i126@pure_quanta.q_cap(chips)',
 PATH='I126',
 DRAWING='@S9S_MB_2U_LIB.S9S_MB_2U(SCH_1):PAGE77',
 PHYS_PAGE='77',
 XY='(-25,5400)',
 ROT='0',
 VER='1',
 PACK_TYPE='C0402',
 CDS_LIB='pure_quanta',
 CDS_PART_NAME='Q_CAP_C0402-22UF,4V,20%,X6S,CHA',
 TOLERANCE='20%',
 MATERIAL='X6S',
 VOLTAGE='4V',
 VALUE='22UF',
 PRIM_FILE='./archive_libs/logical/q_cap/chips/chips.prt';

PART_NAME
 C298 'Q_CAP_C0402-22UF,4V,20%,X6S,CHA':;

SECTION_NUMBER 1
 '@S9S_MB_2U_LIB.S9S_MB_2U(SCH_1):PAGE77_I115@PURE_QUANTA.Q_CAP(CHIPS)':
 C_PATH='@s9s_mb_2u_lib.s9s_mb_2u(sch_1):page77_i115@pure_quanta.q_cap(chips)',
 P_PATH='@s9s_mb_2u_lib.s9s_mb_2u(sch_1):page77_i115@pure_quanta.q_cap(chips)',
 PATH='I115',
 DRAWING='@S9S_MB_2U_LIB.S9S_MB_2U(SCH_1):PAGE77',
 PHYS_PAGE='77',
 XY='(-25,4625)',
 ROT='0',
 VER='1',
 PACK_TYPE='C0402',
 CDS_LIB='pure_quanta',
 CDS_PART_NAME='Q_CAP_C0402-22UF,4V,20%,X6S,CHA',
 TOLERANCE='20%',
 MATERIAL='X6S',
 VOLTAGE='4V',
 VALUE='22UF',
 PRIM_FILE='./archive_libs/logical/q_cap/chips/chips.prt';

PART_NAME
 C299 'Q_CAP_C0402-22UF,4V,20%,X6S,CHA':;

SECTION_NUMBER 1
 '@S9S_MB_2U_LIB.S9S_MB_2U(SCH_1):PAGE77_I131@PURE_QUANTA.Q_CAP(CHIPS)':
 C_PATH='@s9s_mb_2u_lib.s9s_mb_2u(sch_1):page77_i131@pure_quanta.q_cap(chips)',
 P_PATH='@s9s_mb_2u_lib.s9s_mb_2u(sch_1):page77_i131@pure_quanta.q_cap(chips)',
 PATH='I131',
 DRAWING='@S9S_MB_2U_LIB.S9S_MB_2U(SCH_1):PAGE77',
 PHYS_PAGE='77',
 XY='(400,6925)',
 ROT='0',
 VER='1',
 PACK_TYPE='C0402',
 CDS_LIB='pure_quanta',
 CDS_PART_NAME='Q_CAP_C0402-22UF,4V,20%,X6S,CHA',
 TOLERANCE='20%',
 MATERIAL='X6S',
 VOLTAGE='4V',
 VALUE='22UF',
 PRIM_FILE='./archive_libs/logical/q_cap/chips/chips.prt';

PART_NAME
 C300 'Q_CAP_C0402-22UF,4V,20%,X6S,CHA':;

SECTION_NUMBER 1
 '@S9S_MB_2U_LIB.S9S_MB_2U(SCH_1):PAGE77_I132@PURE_QUANTA.Q_CAP(CHIPS)':
 C_PATH='@s9s_mb_2u_lib.s9s_mb_2u(sch_1):page77_i132@pure_quanta.q_cap(chips)',
 P_PATH='@s9s_mb_2u_lib.s9s_mb_2u(sch_1):page77_i132@pure_quanta.q_cap(chips)',
 PATH='I132',
 DRAWING='@S9S_MB_2U_LIB.S9S_MB_2U(SCH_1):PAGE77',
 PHYS_PAGE='77',
 XY='(400,6150)',
 ROT='0',
 VER='1',
 PACK_TYPE='C0402',
 CDS_LIB='pure_quanta',
 CDS_PART_NAME='Q_CAP_C0402-22UF,4V,20%,X6S,CHA',
 TOLERANCE='20%',
 MATERIAL='X6S',
 VOLTAGE='4V',
 VALUE='22UF',
 PRIM_FILE='./archive_libs/logical/q_cap/chips/chips.prt';

PART_NAME
 C301 'Q_CAP_C0402-22UF,4V,20%,X6S,CHA':;

SECTION_NUMBER 1
 '@S9S_MB_2U_LIB.S9S_MB_2U(SCH_1):PAGE77_I133@PURE_QUANTA.Q_CAP(CHIPS)':
 C_PATH='@s9s_mb_2u_lib.s9s_mb_2u(sch_1):page77_i133@pure_quanta.q_cap(chips)',
 P_PATH='@s9s_mb_2u_lib.s9s_mb_2u(sch_1):page77_i133@pure_quanta.q_cap(chips)',
 PATH='I133',
 DRAWING='@S9S_MB_2U_LIB.S9S_MB_2U(SCH_1):PAGE77',
 PHYS_PAGE='77',
 XY='(425,5400)',
 ROT='0',
 VER='1',
 PACK_TYPE='C0402',
 CDS_LIB='pure_quanta',
 CDS_PART_NAME='Q_CAP_C0402-22UF,4V,20%,X6S,CHA',
 TOLERANCE='20%',
 MATERIAL='X6S',
 VOLTAGE='4V',
 VALUE='22UF',
 PRIM_FILE='./archive_libs/logical/q_cap/chips/chips.prt';

PART_NAME
 C302 'Q_CAP_C0402-22UF,4V,20%,X6S,CHA':;

SECTION_NUMBER 1
 '@S9S_MB_2U_LIB.S9S_MB_2U(SCH_1):PAGE77_I117@PURE_QUANTA.Q_CAP(CHIPS)':
 C_PATH='@s9s_mb_2u_lib.s9s_mb_2u(sch_1):page77_i117@pure_quanta.q_cap(chips)',
 P_PATH='@s9s_mb_2u_lib.s9s_mb_2u(sch_1):page77_i117@pure_quanta.q_cap(chips)',
 PATH='I117',
 DRAWING='@S9S_MB_2U_LIB.S9S_MB_2U(SCH_1):PAGE77',
 PHYS_PAGE='77',
 XY='(425,4625)',
 ROT='0',
 VER='1',
 PACK_TYPE='C0402',
 CDS_LIB='pure_quanta',
 CDS_PART_NAME='Q_CAP_C0402-22UF,4V,20%,X6S,CHA',
 TOLERANCE='20%',
 MATERIAL='X6S',
 VOLTAGE='4V',
 VALUE='22UF',
 PRIM_FILE='./archive_libs/logical/q_cap/chips/chips.prt';

PART_NAME
 C303 'Q_CAP_C0402-22UF,4V,20%,X6S,CHA':;

SECTION_NUMBER 1
 '@S9S_MB_2U_LIB.S9S_MB_2U(SCH_1):PAGE77_I139@PURE_QUANTA.Q_CAP(CHIPS)':
 C_PATH='@s9s_mb_2u_lib.s9s_mb_2u(sch_1):page77_i139@pure_quanta.q_cap(chips)',
 P_PATH='@s9s_mb_2u_lib.s9s_mb_2u(sch_1):page77_i139@pure_quanta.q_cap(chips)',
 PATH='I139',
 DRAWING='@S9S_MB_2U_LIB.S9S_MB_2U(SCH_1):PAGE77',
 PHYS_PAGE='77',
 XY='(850,6925)',
 ROT='0',
 VER='1',
 PACK_TYPE='C0402',
 CDS_LIB='pure_quanta',
 CDS_PART_NAME='Q_CAP_C0402-22UF,4V,20%,X6S,CHA',
 TOLERANCE='20%',
 MATERIAL='X6S',
 VOLTAGE='4V',
 VALUE='22UF',
 PRIM_FILE='./archive_libs/logical/q_cap/chips/chips.prt';

PART_NAME
 C304 'Q_CAP_C0402-22UF,4V,20%,X6S,CHA':;

SECTION_NUMBER 1
 '@S9S_MB_2U_LIB.S9S_MB_2U(SCH_1):PAGE77_I138@PURE_QUANTA.Q_CAP(CHIPS)':
 C_PATH='@s9s_mb_2u_lib.s9s_mb_2u(sch_1):page77_i138@pure_quanta.q_cap(chips)',
 P_PATH='@s9s_mb_2u_lib.s9s_mb_2u(sch_1):page77_i138@pure_quanta.q_cap(chips)',
 PATH='I138',
 DRAWING='@S9S_MB_2U_LIB.S9S_MB_2U(SCH_1):PAGE77',
 PHYS_PAGE='77',
 XY='(850,6150)',
 ROT='0',
 VER='1',
 PACK_TYPE='C0402',
 CDS_LIB='pure_quanta',
 CDS_PART_NAME='Q_CAP_C0402-22UF,4V,20%,X6S,CHA',
 TOLERANCE='20%',
 MATERIAL='X6S',
 VOLTAGE='4V',
 VALUE='22UF',
 PRIM_FILE='./archive_libs/logical/q_cap/chips/chips.prt';

PART_NAME
 C305 'Q_CAP_C0402-22UF,4V,20%,X6S,CHA':;

SECTION_NUMBER 1
 '@S9S_MB_2U_LIB.S9S_MB_2U(SCH_1):PAGE77_I134@PURE_QUANTA.Q_CAP(CHIPS)':
 C_PATH='@s9s_mb_2u_lib.s9s_mb_2u(sch_1):page77_i134@pure_quanta.q_cap(chips)',
 P_PATH='@s9s_mb_2u_lib.s9s_mb_2u(sch_1):page77_i134@pure_quanta.q_cap(chips)',
 PATH='I134',
 DRAWING='@S9S_MB_2U_LIB.S9S_MB_2U(SCH_1):PAGE77',
 PHYS_PAGE='77',
 XY='(875,5400)',
 ROT='0',
 VER='1',
 PACK_TYPE='C0402',
 CDS_LIB='pure_quanta',
 CDS_PART_NAME='Q_CAP_C0402-22UF,4V,20%,X6S,CHA',
 TOLERANCE='20%',
 MATERIAL='X6S',
 VOLTAGE='4V',
 VALUE='22UF',
 PRIM_FILE='./archive_libs/logical/q_cap/chips/chips.prt';

PART_NAME
 C306 'Q_CAP_C0402-22UF,4V,20%,X6S,CHA':;

SECTION_NUMBER 1
 '@S9S_MB_2U_LIB.S9S_MB_2U(SCH_1):PAGE77_I118@PURE_QUANTA.Q_CAP(CHIPS)':
 C_PATH='@s9s_mb_2u_lib.s9s_mb_2u(sch_1):page77_i118@pure_quanta.q_cap(chips)',
 P_PATH='@s9s_mb_2u_lib.s9s_mb_2u(sch_1):page77_i118@pure_quanta.q_cap(chips)',
 PATH='I118',
 DRAWING='@S9S_MB_2U_LIB.S9S_MB_2U(SCH_1):PAGE77',
 PHYS_PAGE='77',
 XY='(875,4625)',
 ROT='0',
 VER='1',
 PACK_TYPE='C0402',
 CDS_LIB='pure_quanta',
 CDS_PART_NAME='Q_CAP_C0402-22UF,4V,20%,X6S,CHA',
 TOLERANCE='20%',
 MATERIAL='X6S',
 VOLTAGE='4V',
 VALUE='22UF',
 PRIM_FILE='./archive_libs/logical/q_cap/chips/chips.prt';

PART_NAME
 C307 'Q_CAP_C0402-22UF,4V,20%,X6S,CHA':;

SECTION_NUMBER 1
 '@S9S_MB_2U_LIB.S9S_MB_2U(SCH_1):PAGE77_I142@PURE_QUANTA.Q_CAP(CHIPS)':
 C_PATH='@s9s_mb_2u_lib.s9s_mb_2u(sch_1):page77_i142@pure_quanta.q_cap(chips)',
 P_PATH='@s9s_mb_2u_lib.s9s_mb_2u(sch_1):page77_i142@pure_quanta.q_cap(chips)',
 PATH='I142',
 DRAWING='@S9S_MB_2U_LIB.S9S_MB_2U(SCH_1):PAGE77',
 PHYS_PAGE='77',
 XY='(1300,6925)',
 ROT='0',
 VER='1',
 PACK_TYPE='C0402',
 CDS_LIB='pure_quanta',
 CDS_PART_NAME='Q_CAP_C0402-22UF,4V,20%,X6S,CHA',
 TOLERANCE='20%',
 MATERIAL='X6S',
 VOLTAGE='4V',
 VALUE='22UF',
 PRIM_FILE='./archive_libs/logical/q_cap/chips/chips.prt';

PART_NAME
 C308 'Q_CAP_C0402-22UF,4V,20%,X6S,CHA':;

SECTION_NUMBER 1
 '@S9S_MB_2U_LIB.S9S_MB_2U(SCH_1):PAGE77_I140@PURE_QUANTA.Q_CAP(CHIPS)':
 C_PATH='@s9s_mb_2u_lib.s9s_mb_2u(sch_1):page77_i140@pure_quanta.q_cap(chips)',
 P_PATH='@s9s_mb_2u_lib.s9s_mb_2u(sch_1):page77_i140@pure_quanta.q_cap(chips)',
 PATH='I140',
 DRAWING='@S9S_MB_2U_LIB.S9S_MB_2U(SCH_1):PAGE77',
 PHYS_PAGE='77',
 XY='(1300,6150)',
 ROT='0',
 VER='1',
 PACK_TYPE='C0402',
 CDS_LIB='pure_quanta',
 CDS_PART_NAME='Q_CAP_C0402-22UF,4V,20%,X6S,CHA',
 TOLERANCE='20%',
 MATERIAL='X6S',
 VOLTAGE='4V',
 VALUE='22UF',
 PRIM_FILE='./archive_libs/logical/q_cap/chips/chips.prt';

PART_NAME
 C309 'Q_CAP_C0402-22UF,4V,20%,X6S,CHA':;

SECTION_NUMBER 1
 '@S9S_MB_2U_LIB.S9S_MB_2U(SCH_1):PAGE77_I136@PURE_QUANTA.Q_CAP(CHIPS)':
 C_PATH='@s9s_mb_2u_lib.s9s_mb_2u(sch_1):page77_i136@pure_quanta.q_cap(chips)',
 P_PATH='@s9s_mb_2u_lib.s9s_mb_2u(sch_1):page77_i136@pure_quanta.q_cap(chips)',
 PATH='I136',
 DRAWING='@S9S_MB_2U_LIB.S9S_MB_2U(SCH_1):PAGE77',
 PHYS_PAGE='77',
 XY='(1325,5400)',
 ROT='0',
 VER='1',
 PACK_TYPE='C0402',
 CDS_LIB='pure_quanta',
 CDS_PART_NAME='Q_CAP_C0402-22UF,4V,20%,X6S,CHA',
 TOLERANCE='20%',
 MATERIAL='X6S',
 VOLTAGE='4V',
 VALUE='22UF',
 PRIM_FILE='./archive_libs/logical/q_cap/chips/chips.prt';

PART_NAME
 C310 'Q_CAP_C0402-22UF,4V,20%,X6S,CHA':;

SECTION_NUMBER 1
 '@S9S_MB_2U_LIB.S9S_MB_2U(SCH_1):PAGE77_I70@PURE_QUANTA.Q_CAP(CHIPS)':
 C_PATH='@s9s_mb_2u_lib.s9s_mb_2u(sch_1):page77_i70@pure_quanta.q_cap(chips)',
 P_PATH='@s9s_mb_2u_lib.s9s_mb_2u(sch_1):page77_i70@pure_quanta.q_cap(chips)',
 PATH='I70',
 DRAWING='@S9S_MB_2U_LIB.S9S_MB_2U(SCH_1):PAGE77',
 PHYS_PAGE='77',
 XY='(-1975,3775)',
 ROT='0',
 VER='1',
 PACK_TYPE='C0402',
 CDS_LIB='pure_quanta',
 CDS_PART_NAME='Q_CAP_C0402-22UF,4V,20%,X6S,CHA',
 TOLERANCE='20%',
 MATERIAL='X6S',
 VOLTAGE='4V',
 VALUE='22UF',
 PRIM_FILE='./archive_libs/logical/q_cap/chips/chips.prt';

PART_NAME
 C311 'Q_CAP_C0805-47UF,4V,20%,X6S,CHA':;

SECTION_NUMBER 1
 '@S9S_MB_2U_LIB.S9S_MB_2U(SCH_1):PAGE78_I16@PURE_QUANTA.Q_CAP(CHIPS)':
 C_PATH='@s9s_mb_2u_lib.s9s_mb_2u(sch_1):page78_i16@pure_quanta.q_cap(chips)',
 P_PATH='@s9s_mb_2u_lib.s9s_mb_2u(sch_1):page78_i16@pure_quanta.q_cap(chips)',
 PATH='I16',
 DRAWING='@S9S_MB_2U_LIB.S9S_MB_2U(SCH_1):PAGE78',
 PHYS_PAGE='78',
 XY='(-4450,2400)',
 ROT='0',
 VER='1',
 PACK_TYPE='C0805',
 CDS_LIB='pure_quanta',
 CDS_PART_NAME='Q_CAP_C0805-47UF,4V,20%,X6S,CHA',
 TOLERANCE='20%',
 MATERIAL='X6S',
 VOLTAGE='4V',
 VALUE='47UF',
 PRIM_FILE='./archive_libs/logical/q_cap/chips/chips.prt';

PART_NAME
 C312 'Q_CAP_C0805-47UF,4V,20%,X6S,CHA':;

SECTION_NUMBER 1
 '@S9S_MB_2U_LIB.S9S_MB_2U(SCH_1):PAGE78_I14@PURE_QUANTA.Q_CAP(CHIPS)':
 C_PATH='@s9s_mb_2u_lib.s9s_mb_2u(sch_1):page78_i14@pure_quanta.q_cap(chips)',
 P_PATH='@s9s_mb_2u_lib.s9s_mb_2u(sch_1):page78_i14@pure_quanta.q_cap(chips)',
 PATH='I14',
 DRAWING='@S9S_MB_2U_LIB.S9S_MB_2U(SCH_1):PAGE78',
 PHYS_PAGE='78',
 XY='(-4450,1625)',
 ROT='0',
 VER='1',
 PACK_TYPE='C0805',
 CDS_LIB='pure_quanta',
 CDS_PART_NAME='Q_CAP_C0805-47UF,4V,20%,X6S,CHA',
 TOLERANCE='20%',
 MATERIAL='X6S',
 VOLTAGE='4V',
 VALUE='47UF',
 PRIM_FILE='./archive_libs/logical/q_cap/chips/chips.prt';

PART_NAME
 C313 'Q_CAP_C0805-47UF,4V,20%,X6S,CHA':;

SECTION_NUMBER 1
 '@S9S_MB_2U_LIB.S9S_MB_2U(SCH_1):PAGE78_I58@PURE_QUANTA.Q_CAP(CHIPS)':
 C_PATH='@s9s_mb_2u_lib.s9s_mb_2u(sch_1):page78_i58@pure_quanta.q_cap(chips)',
 P_PATH='@s9s_mb_2u_lib.s9s_mb_2u(sch_1):page78_i58@pure_quanta.q_cap(chips)',
 PATH='I58',
 DRAWING='@S9S_MB_2U_LIB.S9S_MB_2U(SCH_1):PAGE78',
 PHYS_PAGE='78',
 XY='(50,1625)',
 ROT='0',
 VER='1',
 PACK_TYPE='C0805',
 CDS_LIB='pure_quanta',
 CDS_PART_NAME='Q_CAP_C0805-47UF,4V,20%,X6S,CHA',
 TOLERANCE='20%',
 MATERIAL='X6S',
 VOLTAGE='4V',
 VALUE='47UF',
 PRIM_FILE='./archive_libs/logical/q_cap/chips/chips.prt';

PART_NAME
 C314 'Q_CAP_C0805-47UF,4V,20%,X6S,CHA':;

SECTION_NUMBER 1
 '@S9S_MB_2U_LIB.S9S_MB_2U(SCH_1):PAGE78_I37@PURE_QUANTA.Q_CAP(CHIPS)':
 C_PATH='@s9s_mb_2u_lib.s9s_mb_2u(sch_1):page78_i37@pure_quanta.q_cap(chips)',
 P_PATH='@s9s_mb_2u_lib.s9s_mb_2u(sch_1):page78_i37@pure_quanta.q_cap(chips)',
 PATH='I37',
 DRAWING='@S9S_MB_2U_LIB.S9S_MB_2U(SCH_1):PAGE78',
 PHYS_PAGE='78',
 XY='(-4000,2400)',
 ROT='0',
 VER='1',
 PACK_TYPE='C0805',
 CDS_LIB='pure_quanta',
 CDS_PART_NAME='Q_CAP_C0805-47UF,4V,20%,X6S,CHA',
 TOLERANCE='20%',
 MATERIAL='X6S',
 VOLTAGE='4V',
 VALUE='47UF',
 PRIM_FILE='./archive_libs/logical/q_cap/chips/chips.prt';

PART_NAME
 C315 'Q_CAP_C0805-47UF,4V,20%,X6S,CHA':;

SECTION_NUMBER 1
 '@S9S_MB_2U_LIB.S9S_MB_2U(SCH_1):PAGE78_I26@PURE_QUANTA.Q_CAP(CHIPS)':
 C_PATH='@s9s_mb_2u_lib.s9s_mb_2u(sch_1):page78_i26@pure_quanta.q_cap(chips)',
 P_PATH='@s9s_mb_2u_lib.s9s_mb_2u(sch_1):page78_i26@pure_quanta.q_cap(chips)',
 PATH='I26',
 DRAWING='@S9S_MB_2U_LIB.S9S_MB_2U(SCH_1):PAGE78',
 PHYS_PAGE='78',
 XY='(-4000,1625)',
 ROT='0',
 VER='1',
 PACK_TYPE='C0805',
 CDS_LIB='pure_quanta',
 CDS_PART_NAME='Q_CAP_C0805-47UF,4V,20%,X6S,CHA',
 TOLERANCE='20%',
 MATERIAL='X6S',
 VOLTAGE='4V',
 VALUE='47UF',
 PRIM_FILE='./archive_libs/logical/q_cap/chips/chips.prt';

PART_NAME
 C316 'Q_CAP_C0805-47UF,4V,20%,X6S,CHA':;

SECTION_NUMBER 1
 '@S9S_MB_2U_LIB.S9S_MB_2U(SCH_1):PAGE78_I60@PURE_QUANTA.Q_CAP(CHIPS)':
 C_PATH='@s9s_mb_2u_lib.s9s_mb_2u(sch_1):page78_i60@pure_quanta.q_cap(chips)',
 P_PATH='@s9s_mb_2u_lib.s9s_mb_2u(sch_1):page78_i60@pure_quanta.q_cap(chips)',
 PATH='I60',
 DRAWING='@S9S_MB_2U_LIB.S9S_MB_2U(SCH_1):PAGE78',
 PHYS_PAGE='78',
 XY='(500,1625)',
 ROT='0',
 VER='1',
 PACK_TYPE='C0805',
 CDS_LIB='pure_quanta',
 CDS_PART_NAME='Q_CAP_C0805-47UF,4V,20%,X6S,CHA',
 TOLERANCE='20%',
 MATERIAL='X6S',
 VOLTAGE='4V',
 VALUE='47UF',
 PRIM_FILE='./archive_libs/logical/q_cap/chips/chips.prt';

PART_NAME
 C317 'Q_CAP_C0805-47UF,4V,20%,X6S,CHA':;

SECTION_NUMBER 1
 '@S9S_MB_2U_LIB.S9S_MB_2U(SCH_1):PAGE78_I38@PURE_QUANTA.Q_CAP(CHIPS)':
 C_PATH='@s9s_mb_2u_lib.s9s_mb_2u(sch_1):page78_i38@pure_quanta.q_cap(chips)',
 P_PATH='@s9s_mb_2u_lib.s9s_mb_2u(sch_1):page78_i38@pure_quanta.q_cap(chips)',
 PATH='I38',
 DRAWING='@S9S_MB_2U_LIB.S9S_MB_2U(SCH_1):PAGE78',
 PHYS_PAGE='78',
 XY='(-3550,2400)',
 ROT='0',
 VER='1',
 PACK_TYPE='C0805',
 CDS_LIB='pure_quanta',
 CDS_PART_NAME='Q_CAP_C0805-47UF,4V,20%,X6S,CHA',
 TOLERANCE='20%',
 MATERIAL='X6S',
 VOLTAGE='4V',
 VALUE='47UF',
 PRIM_FILE='./archive_libs/logical/q_cap/chips/chips.prt';

PART_NAME
 C318 'Q_CAP_C0805-47UF,4V,20%,X6S,CHA':;

SECTION_NUMBER 1
 '@S9S_MB_2U_LIB.S9S_MB_2U(SCH_1):PAGE78_I27@PURE_QUANTA.Q_CAP(CHIPS)':
 C_PATH='@s9s_mb_2u_lib.s9s_mb_2u(sch_1):page78_i27@pure_quanta.q_cap(chips)',
 P_PATH='@s9s_mb_2u_lib.s9s_mb_2u(sch_1):page78_i27@pure_quanta.q_cap(chips)',
 PATH='I27',
 DRAWING='@S9S_MB_2U_LIB.S9S_MB_2U(SCH_1):PAGE78',
 PHYS_PAGE='78',
 XY='(-3550,1625)',
 ROT='0',
 VER='1',
 PACK_TYPE='C0805',
 CDS_LIB='pure_quanta',
 CDS_PART_NAME='Q_CAP_C0805-47UF,4V,20%,X6S,CHA',
 TOLERANCE='20%',
 MATERIAL='X6S',
 VOLTAGE='4V',
 VALUE='47UF',
 PRIM_FILE='./archive_libs/logical/q_cap/chips/chips.prt';

PART_NAME
 C320 'Q_CAP_C0805-47UF,4V,20%,X6S,CHA':;

SECTION_NUMBER 1
 '@S9S_MB_2U_LIB.S9S_MB_2U(SCH_1):PAGE78_I39@PURE_QUANTA.Q_CAP(CHIPS)':
 C_PATH='@s9s_mb_2u_lib.s9s_mb_2u(sch_1):page78_i39@pure_quanta.q_cap(chips)',
 P_PATH='@s9s_mb_2u_lib.s9s_mb_2u(sch_1):page78_i39@pure_quanta.q_cap(chips)',
 PATH='I39',
 DRAWING='@S9S_MB_2U_LIB.S9S_MB_2U(SCH_1):PAGE78',
 PHYS_PAGE='78',
 XY='(-3100,2400)',
 ROT='0',
 VER='1',
 PACK_TYPE='C0805',
 CDS_LIB='pure_quanta',
 CDS_PART_NAME='Q_CAP_C0805-47UF,4V,20%,X6S,CHA',
 TOLERANCE='20%',
 MATERIAL='X6S',
 VOLTAGE='4V',
 VALUE='47UF',
 PRIM_FILE='./archive_libs/logical/q_cap/chips/chips.prt';

PART_NAME
 C321 'Q_CAP_C0805-47UF,4V,20%,X6S,CHA':;

SECTION_NUMBER 1
 '@S9S_MB_2U_LIB.S9S_MB_2U(SCH_1):PAGE78_I30@PURE_QUANTA.Q_CAP(CHIPS)':
 C_PATH='@s9s_mb_2u_lib.s9s_mb_2u(sch_1):page78_i30@pure_quanta.q_cap(chips)',
 P_PATH='@s9s_mb_2u_lib.s9s_mb_2u(sch_1):page78_i30@pure_quanta.q_cap(chips)',
 PATH='I30',
 DRAWING='@S9S_MB_2U_LIB.S9S_MB_2U(SCH_1):PAGE78',
 PHYS_PAGE='78',
 XY='(-3100,1625)',
 ROT='0',
 VER='1',
 PACK_TYPE='C0805',
 CDS_LIB='pure_quanta',
 CDS_PART_NAME='Q_CAP_C0805-47UF,4V,20%,X6S,CHA',
 TOLERANCE='20%',
 MATERIAL='X6S',
 VOLTAGE='4V',
 VALUE='47UF',
 PRIM_FILE='./archive_libs/logical/q_cap/chips/chips.prt';

PART_NAME
 C322 'Q_CAP_C0805-47UF,4V,20%,X6S,CHA':;

SECTION_NUMBER 1
 '@S9S_MB_2U_LIB.S9S_MB_2U(SCH_1):PAGE79_I46@PURE_QUANTA.Q_CAP(CHIPS)':
 C_PATH='@s9s_mb_2u_lib.s9s_mb_2u(sch_1):page79_i46@pure_quanta.q_cap(chips)',
 P_PATH='@s9s_mb_2u_lib.s9s_mb_2u(sch_1):page79_i46@pure_quanta.q_cap(chips)',
 PATH='I46',
 DRAWING='@S9S_MB_2U_LIB.S9S_MB_2U(SCH_1):PAGE79',
 PHYS_PAGE='79',
 XY='(-1250,2400)',
 ROT='0',
 VER='1',
 PACK_TYPE='C0805',
 CDS_LIB='pure_quanta',
 CDS_PART_NAME='Q_CAP_C0805-47UF,4V,20%,X6S,CHA',
 TOLERANCE='20%',
 MATERIAL='X6S',
 VOLTAGE='4V',
 VALUE='47UF',
 PRIM_FILE='./archive_libs/logical/q_cap/chips/chips.prt';

PART_NAME
 C323 'Q_CAP_C0805-47UF,4V,20%,X6S,CHA':;

SECTION_NUMBER 1
 '@S9S_MB_2U_LIB.S9S_MB_2U(SCH_1):PAGE78_I40@PURE_QUANTA.Q_CAP(CHIPS)':
 C_PATH='@s9s_mb_2u_lib.s9s_mb_2u(sch_1):page78_i40@pure_quanta.q_cap(chips)',
 P_PATH='@s9s_mb_2u_lib.s9s_mb_2u(sch_1):page78_i40@pure_quanta.q_cap(chips)',
 PATH='I40',
 DRAWING='@S9S_MB_2U_LIB.S9S_MB_2U(SCH_1):PAGE78',
 PHYS_PAGE='78',
 XY='(-2650,2400)',
 ROT='0',
 VER='1',
 PACK_TYPE='C0805',
 CDS_LIB='pure_quanta',
 CDS_PART_NAME='Q_CAP_C0805-47UF,4V,20%,X6S,CHA',
 TOLERANCE='20%',
 MATERIAL='X6S',
 VOLTAGE='4V',
 VALUE='47UF',
 PRIM_FILE='./archive_libs/logical/q_cap/chips/chips.prt';

PART_NAME
 C324 'Q_CAP_C0805-47UF,4V,20%,X6S,CHA':;

SECTION_NUMBER 1
 '@S9S_MB_2U_LIB.S9S_MB_2U(SCH_1):PAGE78_I31@PURE_QUANTA.Q_CAP(CHIPS)':
 C_PATH='@s9s_mb_2u_lib.s9s_mb_2u(sch_1):page78_i31@pure_quanta.q_cap(chips)',
 P_PATH='@s9s_mb_2u_lib.s9s_mb_2u(sch_1):page78_i31@pure_quanta.q_cap(chips)',
 PATH='I31',
 DRAWING='@S9S_MB_2U_LIB.S9S_MB_2U(SCH_1):PAGE78',
 PHYS_PAGE='78',
 XY='(-2650,1625)',
 ROT='0',
 VER='1',
 PACK_TYPE='C0805',
 CDS_LIB='pure_quanta',
 CDS_PART_NAME='Q_CAP_C0805-47UF,4V,20%,X6S,CHA',
 TOLERANCE='20%',
 MATERIAL='X6S',
 VOLTAGE='4V',
 VALUE='47UF',
 PRIM_FILE='./archive_libs/logical/q_cap/chips/chips.prt';

PART_NAME
 C325 'Q_CAP_C0805-47UF,4V,20%,X6S,CHA':;

SECTION_NUMBER 1
 '@S9S_MB_2U_LIB.S9S_MB_2U(SCH_1):PAGE79_I47@PURE_QUANTA.Q_CAP(CHIPS)':
 C_PATH='@s9s_mb_2u_lib.s9s_mb_2u(sch_1):page79_i47@pure_quanta.q_cap(chips)',
 P_PATH='@s9s_mb_2u_lib.s9s_mb_2u(sch_1):page79_i47@pure_quanta.q_cap(chips)',
 PATH='I47',
 DRAWING='@S9S_MB_2U_LIB.S9S_MB_2U(SCH_1):PAGE79',
 PHYS_PAGE='79',
 XY='(-800,2400)',
 ROT='0',
 VER='1',
 PACK_TYPE='C0805',
 CDS_LIB='pure_quanta',
 CDS_PART_NAME='Q_CAP_C0805-47UF,4V,20%,X6S,CHA',
 TOLERANCE='20%',
 MATERIAL='X6S',
 VOLTAGE='4V',
 VALUE='47UF',
 PRIM_FILE='./archive_libs/logical/q_cap/chips/chips.prt';

PART_NAME
 C326 'Q_CAP_C0805-47UF,4V,20%,X6S,CHA':;

SECTION_NUMBER 1
 '@S9S_MB_2U_LIB.S9S_MB_2U(SCH_1):PAGE78_I41@PURE_QUANTA.Q_CAP(CHIPS)':
 C_PATH='@s9s_mb_2u_lib.s9s_mb_2u(sch_1):page78_i41@pure_quanta.q_cap(chips)',
 P_PATH='@s9s_mb_2u_lib.s9s_mb_2u(sch_1):page78_i41@pure_quanta.q_cap(chips)',
 PATH='I41',
 DRAWING='@S9S_MB_2U_LIB.S9S_MB_2U(SCH_1):PAGE78',
 PHYS_PAGE='78',
 XY='(-2200,2400)',
 ROT='0',
 VER='1',
 PACK_TYPE='C0805',
 CDS_LIB='pure_quanta',
 CDS_PART_NAME='Q_CAP_C0805-47UF,4V,20%,X6S,CHA',
 TOLERANCE='20%',
 MATERIAL='X6S',
 VOLTAGE='4V',
 VALUE='47UF',
 PRIM_FILE='./archive_libs/logical/q_cap/chips/chips.prt';

PART_NAME
 C327 'Q_CAP_C0805-47UF,4V,20%,X6S,CHA':;

SECTION_NUMBER 1
 '@S9S_MB_2U_LIB.S9S_MB_2U(SCH_1):PAGE78_I32@PURE_QUANTA.Q_CAP(CHIPS)':
 C_PATH='@s9s_mb_2u_lib.s9s_mb_2u(sch_1):page78_i32@pure_quanta.q_cap(chips)',
 P_PATH='@s9s_mb_2u_lib.s9s_mb_2u(sch_1):page78_i32@pure_quanta.q_cap(chips)',
 PATH='I32',
 DRAWING='@S9S_MB_2U_LIB.S9S_MB_2U(SCH_1):PAGE78',
 PHYS_PAGE='78',
 XY='(-2200,1625)',
 ROT='0',
 VER='1',
 PACK_TYPE='C0805',
 CDS_LIB='pure_quanta',
 CDS_PART_NAME='Q_CAP_C0805-47UF,4V,20%,X6S,CHA',
 TOLERANCE='20%',
 MATERIAL='X6S',
 VOLTAGE='4V',
 VALUE='47UF',
 PRIM_FILE='./archive_libs/logical/q_cap/chips/chips.prt';

PART_NAME
 C328 'Q_CAP_C0805-47UF,4V,20%,X6S,CHA':;

SECTION_NUMBER 1
 '@S9S_MB_2U_LIB.S9S_MB_2U(SCH_1):PAGE79_I50@PURE_QUANTA.Q_CAP(CHIPS)':
 C_PATH='@s9s_mb_2u_lib.s9s_mb_2u(sch_1):page79_i50@pure_quanta.q_cap(chips)',
 P_PATH='@s9s_mb_2u_lib.s9s_mb_2u(sch_1):page79_i50@pure_quanta.q_cap(chips)',
 PATH='I50',
 DRAWING='@S9S_MB_2U_LIB.S9S_MB_2U(SCH_1):PAGE79',
 PHYS_PAGE='79',
 XY='(-350,2400)',
 ROT='0',
 VER='1',
 PACK_TYPE='C0805',
 CDS_LIB='pure_quanta',
 CDS_PART_NAME='Q_CAP_C0805-47UF,4V,20%,X6S,CHA',
 TOLERANCE='20%',
 MATERIAL='X6S',
 VOLTAGE='4V',
 VALUE='47UF',
 PRIM_FILE='./archive_libs/logical/q_cap/chips/chips.prt';

PART_NAME
 C329 'Q_CAP_C0805-47UF,4V,20%,X6S,CHA':;

SECTION_NUMBER 1
 '@S9S_MB_2U_LIB.S9S_MB_2U(SCH_1):PAGE78_I42@PURE_QUANTA.Q_CAP(CHIPS)':
 C_PATH='@s9s_mb_2u_lib.s9s_mb_2u(sch_1):page78_i42@pure_quanta.q_cap(chips)',
 P_PATH='@s9s_mb_2u_lib.s9s_mb_2u(sch_1):page78_i42@pure_quanta.q_cap(chips)',
 PATH='I42',
 DRAWING='@S9S_MB_2U_LIB.S9S_MB_2U(SCH_1):PAGE78',
 PHYS_PAGE='78',
 XY='(-1750,2400)',
 ROT='0',
 VER='1',
 PACK_TYPE='C0805',
 CDS_LIB='pure_quanta',
 CDS_PART_NAME='Q_CAP_C0805-47UF,4V,20%,X6S,CHA',
 TOLERANCE='20%',
 MATERIAL='X6S',
 VOLTAGE='4V',
 VALUE='47UF',
 PRIM_FILE='./archive_libs/logical/q_cap/chips/chips.prt';

PART_NAME
 C330 'Q_CAP_C0805-47UF,4V,20%,X6S,CHA':;

SECTION_NUMBER 1
 '@S9S_MB_2U_LIB.S9S_MB_2U(SCH_1):PAGE78_I33@PURE_QUANTA.Q_CAP(CHIPS)':
 C_PATH='@s9s_mb_2u_lib.s9s_mb_2u(sch_1):page78_i33@pure_quanta.q_cap(chips)',
 P_PATH='@s9s_mb_2u_lib.s9s_mb_2u(sch_1):page78_i33@pure_quanta.q_cap(chips)',
 PATH='I33',
 DRAWING='@S9S_MB_2U_LIB.S9S_MB_2U(SCH_1):PAGE78',
 PHYS_PAGE='78',
 XY='(-1750,1625)',
 ROT='0',
 VER='1',
 PACK_TYPE='C0805',
 CDS_LIB='pure_quanta',
 CDS_PART_NAME='Q_CAP_C0805-47UF,4V,20%,X6S,CHA',
 TOLERANCE='20%',
 MATERIAL='X6S',
 VOLTAGE='4V',
 VALUE='47UF',
 PRIM_FILE='./archive_libs/logical/q_cap/chips/chips.prt';

PART_NAME
 C332 'Q_CAP_C0805-47UF,4V,20%,X6S,CHA':;

SECTION_NUMBER 1
 '@S9S_MB_2U_LIB.S9S_MB_2U(SCH_1):PAGE78_I43@PURE_QUANTA.Q_CAP(CHIPS)':
 C_PATH='@s9s_mb_2u_lib.s9s_mb_2u(sch_1):page78_i43@pure_quanta.q_cap(chips)',
 P_PATH='@s9s_mb_2u_lib.s9s_mb_2u(sch_1):page78_i43@pure_quanta.q_cap(chips)',
 PATH='I43',
 DRAWING='@S9S_MB_2U_LIB.S9S_MB_2U(SCH_1):PAGE78',
 PHYS_PAGE='78',
 XY='(-1300,2400)',
 ROT='0',
 VER='1',
 PACK_TYPE='C0805',
 CDS_LIB='pure_quanta',
 CDS_PART_NAME='Q_CAP_C0805-47UF,4V,20%,X6S,CHA',
 TOLERANCE='20%',
 MATERIAL='X6S',
 VOLTAGE='4V',
 VALUE='47UF',
 PRIM_FILE='./archive_libs/logical/q_cap/chips/chips.prt';

PART_NAME
 C333 'Q_CAP_C0805-47UF,4V,20%,X6S,CHA':;

SECTION_NUMBER 1
 '@S9S_MB_2U_LIB.S9S_MB_2U(SCH_1):PAGE78_I34@PURE_QUANTA.Q_CAP(CHIPS)':
 C_PATH='@s9s_mb_2u_lib.s9s_mb_2u(sch_1):page78_i34@pure_quanta.q_cap(chips)',
 P_PATH='@s9s_mb_2u_lib.s9s_mb_2u(sch_1):page78_i34@pure_quanta.q_cap(chips)',
 PATH='I34',
 DRAWING='@S9S_MB_2U_LIB.S9S_MB_2U(SCH_1):PAGE78',
 PHYS_PAGE='78',
 XY='(-1300,1625)',
 ROT='0',
 VER='1',
 PACK_TYPE='C0805',
 CDS_LIB='pure_quanta',
 CDS_PART_NAME='Q_CAP_C0805-47UF,4V,20%,X6S,CHA',
 TOLERANCE='20%',
 MATERIAL='X6S',
 VOLTAGE='4V',
 VALUE='47UF',
 PRIM_FILE='./archive_libs/logical/q_cap/chips/chips.prt';

PART_NAME
 C335 'Q_CAP_C0805-47UF,4V,20%,X6S,CHA':;

SECTION_NUMBER 1
 '@S9S_MB_2U_LIB.S9S_MB_2U(SCH_1):PAGE78_I44@PURE_QUANTA.Q_CAP(CHIPS)':
 C_PATH='@s9s_mb_2u_lib.s9s_mb_2u(sch_1):page78_i44@pure_quanta.q_cap(chips)',
 P_PATH='@s9s_mb_2u_lib.s9s_mb_2u(sch_1):page78_i44@pure_quanta.q_cap(chips)',
 PATH='I44',
 DRAWING='@S9S_MB_2U_LIB.S9S_MB_2U(SCH_1):PAGE78',
 PHYS_PAGE='78',
 XY='(-850,2400)',
 ROT='0',
 VER='1',
 PACK_TYPE='C0805',
 CDS_LIB='pure_quanta',
 CDS_PART_NAME='Q_CAP_C0805-47UF,4V,20%,X6S,CHA',
 TOLERANCE='20%',
 MATERIAL='X6S',
 VOLTAGE='4V',
 VALUE='47UF',
 PRIM_FILE='./archive_libs/logical/q_cap/chips/chips.prt';

PART_NAME
 C336 'Q_CAP_C0805-47UF,4V,20%,X6S,CHA':;

SECTION_NUMBER 1
 '@S9S_MB_2U_LIB.S9S_MB_2U(SCH_1):PAGE78_I35@PURE_QUANTA.Q_CAP(CHIPS)':
 C_PATH='@s9s_mb_2u_lib.s9s_mb_2u(sch_1):page78_i35@pure_quanta.q_cap(chips)',
 P_PATH='@s9s_mb_2u_lib.s9s_mb_2u(sch_1):page78_i35@pure_quanta.q_cap(chips)',
 PATH='I35',
 DRAWING='@S9S_MB_2U_LIB.S9S_MB_2U(SCH_1):PAGE78',
 PHYS_PAGE='78',
 XY='(-850,1625)',
 ROT='0',
 VER='1',
 PACK_TYPE='C0805',
 CDS_LIB='pure_quanta',
 CDS_PART_NAME='Q_CAP_C0805-47UF,4V,20%,X6S,CHA',
 TOLERANCE='20%',
 MATERIAL='X6S',
 VOLTAGE='4V',
 VALUE='47UF',
 PRIM_FILE='./archive_libs/logical/q_cap/chips/chips.prt';

PART_NAME
 C337 'Q_CAP_C0805-47UF,4V,20%,X6S,CHA':;

SECTION_NUMBER 1
 '@S9S_MB_2U_LIB.S9S_MB_2U(SCH_1):PAGE78_I66@PURE_QUANTA.Q_CAP(CHIPS)':
 C_PATH='@s9s_mb_2u_lib.s9s_mb_2u(sch_1):page78_i66@pure_quanta.q_cap(chips)',
 P_PATH='@s9s_mb_2u_lib.s9s_mb_2u(sch_1):page78_i66@pure_quanta.q_cap(chips)',
 PATH='I66',
 DRAWING='@S9S_MB_2U_LIB.S9S_MB_2U(SCH_1):PAGE78',
 PHYS_PAGE='78',
 XY='(1825,2400)',
 ROT='0',
 VER='1',
 PACK_TYPE='C0805',
 CDS_LIB='pure_quanta',
 CDS_PART_NAME='Q_CAP_C0805-47UF,4V,20%,X6S,CHA',
 TOLERANCE='20%',
 MATERIAL='X6S',
 VOLTAGE='4V',
 VALUE='47UF',
 PRIM_FILE='./archive_libs/logical/q_cap/chips/chips.prt';

PART_NAME
 C338 'Q_CAP_C0805-47UF,4V,20%,X6S,CHA':;

SECTION_NUMBER 1
 '@S9S_MB_2U_LIB.S9S_MB_2U(SCH_1):PAGE78_I45@PURE_QUANTA.Q_CAP(CHIPS)':
 C_PATH='@s9s_mb_2u_lib.s9s_mb_2u(sch_1):page78_i45@pure_quanta.q_cap(chips)',
 P_PATH='@s9s_mb_2u_lib.s9s_mb_2u(sch_1):page78_i45@pure_quanta.q_cap(chips)',
 PATH='I45',
 DRAWING='@S9S_MB_2U_LIB.S9S_MB_2U(SCH_1):PAGE78',
 PHYS_PAGE='78',
 XY='(-400,2400)',
 ROT='0',
 VER='1',
 PACK_TYPE='C0805',
 CDS_LIB='pure_quanta',
 CDS_PART_NAME='Q_CAP_C0805-47UF,4V,20%,X6S,CHA',
 TOLERANCE='20%',
 MATERIAL='X6S',
 VOLTAGE='4V',
 VALUE='47UF',
 PRIM_FILE='./archive_libs/logical/q_cap/chips/chips.prt';

PART_NAME
 C339 'Q_CAP_C0805-47UF,4V,20%,X6S,CHA':;

SECTION_NUMBER 1
 '@S9S_MB_2U_LIB.S9S_MB_2U(SCH_1):PAGE78_I36@PURE_QUANTA.Q_CAP(CHIPS)':
 C_PATH='@s9s_mb_2u_lib.s9s_mb_2u(sch_1):page78_i36@pure_quanta.q_cap(chips)',
 P_PATH='@s9s_mb_2u_lib.s9s_mb_2u(sch_1):page78_i36@pure_quanta.q_cap(chips)',
 PATH='I36',
 DRAWING='@S9S_MB_2U_LIB.S9S_MB_2U(SCH_1):PAGE78',
 PHYS_PAGE='78',
 XY='(-400,1625)',
 ROT='0',
 VER='1',
 PACK_TYPE='C0805',
 CDS_LIB='pure_quanta',
 CDS_PART_NAME='Q_CAP_C0805-47UF,4V,20%,X6S,CHA',
 TOLERANCE='20%',
 MATERIAL='X6S',
 VOLTAGE='4V',
 VALUE='47UF',
 PRIM_FILE='./archive_libs/logical/q_cap/chips/chips.prt';

PART_NAME
 C341 'Q_CAP_C0805-47UF,4V,20%,X6S,CHA':;

SECTION_NUMBER 1
 '@S9S_MB_2U_LIB.S9S_MB_2U(SCH_1):PAGE79_I51@PURE_QUANTA.Q_CAP(CHIPS)':
 C_PATH='@s9s_mb_2u_lib.s9s_mb_2u(sch_1):page79_i51@pure_quanta.q_cap(chips)',
 P_PATH='@s9s_mb_2u_lib.s9s_mb_2u(sch_1):page79_i51@pure_quanta.q_cap(chips)',
 PATH='I51',
 DRAWING='@S9S_MB_2U_LIB.S9S_MB_2U(SCH_1):PAGE79',
 PHYS_PAGE='79',
 XY='(100,2400)',
 ROT='0',
 VER='1',
 PACK_TYPE='C0805',
 CDS_LIB='pure_quanta',
 CDS_PART_NAME='Q_CAP_C0805-47UF,4V,20%,X6S,CHA',
 TOLERANCE='20%',
 MATERIAL='X6S',
 VOLTAGE='4V',
 VALUE='47UF',
 PRIM_FILE='./archive_libs/logical/q_cap/chips/chips.prt';

PART_NAME
 C342 'Q_CAP_C0805-47UF,4V,20%,X6S,CHA':;

SECTION_NUMBER 1
 '@S9S_MB_2U_LIB.S9S_MB_2U(SCH_1):PAGE79_I23@PURE_QUANTA.Q_CAP(CHIPS)':
 C_PATH='@s9s_mb_2u_lib.s9s_mb_2u(sch_1):page79_i23@pure_quanta.q_cap(chips)',
 P_PATH='@s9s_mb_2u_lib.s9s_mb_2u(sch_1):page79_i23@pure_quanta.q_cap(chips)',
 PATH='I23',
 DRAWING='@S9S_MB_2U_LIB.S9S_MB_2U(SCH_1):PAGE79',
 PHYS_PAGE='79',
 XY='(-4400,2400)',
 ROT='0',
 VER='1',
 PACK_TYPE='C0805',
 CDS_LIB='pure_quanta',
 CDS_PART_NAME='Q_CAP_C0805-47UF,4V,20%,X6S,CHA',
 TOLERANCE='20%',
 MATERIAL='X6S',
 VOLTAGE='4V',
 VALUE='47UF',
 PRIM_FILE='./archive_libs/logical/q_cap/chips/chips.prt';

PART_NAME
 C343 'Q_CAP_C0805-47UF,4V,20%,X6S,CHA':;

SECTION_NUMBER 1
 '@S9S_MB_2U_LIB.S9S_MB_2U(SCH_1):PAGE79_I52@PURE_QUANTA.Q_CAP(CHIPS)':
 C_PATH='@s9s_mb_2u_lib.s9s_mb_2u(sch_1):page79_i52@pure_quanta.q_cap(chips)',
 P_PATH='@s9s_mb_2u_lib.s9s_mb_2u(sch_1):page79_i52@pure_quanta.q_cap(chips)',
 PATH='I52',
 DRAWING='@S9S_MB_2U_LIB.S9S_MB_2U(SCH_1):PAGE79',
 PHYS_PAGE='79',
 XY='(550,2400)',
 ROT='0',
 VER='1',
 PACK_TYPE='C0805',
 CDS_LIB='pure_quanta',
 CDS_PART_NAME='Q_CAP_C0805-47UF,4V,20%,X6S,CHA',
 TOLERANCE='20%',
 MATERIAL='X6S',
 VOLTAGE='4V',
 VALUE='47UF',
 PRIM_FILE='./archive_libs/logical/q_cap/chips/chips.prt';

PART_NAME
 C344 'Q_CAP_C0805-47UF,4V,20%,X6S,CHA':;

SECTION_NUMBER 1
 '@S9S_MB_2U_LIB.S9S_MB_2U(SCH_1):PAGE79_I24@PURE_QUANTA.Q_CAP(CHIPS)':
 C_PATH='@s9s_mb_2u_lib.s9s_mb_2u(sch_1):page79_i24@pure_quanta.q_cap(chips)',
 P_PATH='@s9s_mb_2u_lib.s9s_mb_2u(sch_1):page79_i24@pure_quanta.q_cap(chips)',
 PATH='I24',
 DRAWING='@S9S_MB_2U_LIB.S9S_MB_2U(SCH_1):PAGE79',
 PHYS_PAGE='79',
 XY='(-3950,2400)',
 ROT='0',
 VER='1',
 PACK_TYPE='C0805',
 CDS_LIB='pure_quanta',
 CDS_PART_NAME='Q_CAP_C0805-47UF,4V,20%,X6S,CHA',
 TOLERANCE='20%',
 MATERIAL='X6S',
 VOLTAGE='4V',
 VALUE='47UF',
 PRIM_FILE='./archive_libs/logical/q_cap/chips/chips.prt';

PART_NAME
 C345 'Q_CAP_C0805-47UF,4V,20%,X6S,CHA':;

SECTION_NUMBER 1
 '@S9S_MB_2U_LIB.S9S_MB_2U(SCH_1):PAGE79_I53@PURE_QUANTA.Q_CAP(CHIPS)':
 C_PATH='@s9s_mb_2u_lib.s9s_mb_2u(sch_1):page79_i53@pure_quanta.q_cap(chips)',
 P_PATH='@s9s_mb_2u_lib.s9s_mb_2u(sch_1):page79_i53@pure_quanta.q_cap(chips)',
 PATH='I53',
 DRAWING='@S9S_MB_2U_LIB.S9S_MB_2U(SCH_1):PAGE79',
 PHYS_PAGE='79',
 XY='(1000,2400)',
 ROT='0',
 VER='1',
 PACK_TYPE='C0805',
 CDS_LIB='pure_quanta',
 CDS_PART_NAME='Q_CAP_C0805-47UF,4V,20%,X6S,CHA',
 TOLERANCE='20%',
 MATERIAL='X6S',
 VOLTAGE='4V',
 VALUE='47UF',
 PRIM_FILE='./archive_libs/logical/q_cap/chips/chips.prt';

PART_NAME
 C346 'Q_CAP_C0805-47UF,4V,20%,X6S,CHA':;

SECTION_NUMBER 1
 '@S9S_MB_2U_LIB.S9S_MB_2U(SCH_1):PAGE79_I25@PURE_QUANTA.Q_CAP(CHIPS)':
 C_PATH='@s9s_mb_2u_lib.s9s_mb_2u(sch_1):page79_i25@pure_quanta.q_cap(chips)',
 P_PATH='@s9s_mb_2u_lib.s9s_mb_2u(sch_1):page79_i25@pure_quanta.q_cap(chips)',
 PATH='I25',
 DRAWING='@S9S_MB_2U_LIB.S9S_MB_2U(SCH_1):PAGE79',
 PHYS_PAGE='79',
 XY='(-3500,2400)',
 ROT='0',
 VER='1',
 PACK_TYPE='C0805',
 CDS_LIB='pure_quanta',
 CDS_PART_NAME='Q_CAP_C0805-47UF,4V,20%,X6S,CHA',
 TOLERANCE='20%',
 MATERIAL='X6S',
 VOLTAGE='4V',
 VALUE='47UF',
 PRIM_FILE='./archive_libs/logical/q_cap/chips/chips.prt';

PART_NAME
 C347 'Q_CAP_C0805-47UF,4V,20%,X6S,CHA':;

SECTION_NUMBER 1
 '@S9S_MB_2U_LIB.S9S_MB_2U(SCH_1):PAGE79_I55@PURE_QUANTA.Q_CAP(CHIPS)':
 C_PATH='@s9s_mb_2u_lib.s9s_mb_2u(sch_1):page79_i55@pure_quanta.q_cap(chips)',
 P_PATH='@s9s_mb_2u_lib.s9s_mb_2u(sch_1):page79_i55@pure_quanta.q_cap(chips)',
 PATH='I55',
 DRAWING='@S9S_MB_2U_LIB.S9S_MB_2U(SCH_1):PAGE79',
 PHYS_PAGE='79',
 XY='(1450,2400)',
 ROT='0',
 VER='1',
 PACK_TYPE='C0805',
 CDS_LIB='pure_quanta',
 CDS_PART_NAME='Q_CAP_C0805-47UF,4V,20%,X6S,CHA',
 TOLERANCE='20%',
 MATERIAL='X6S',
 VOLTAGE='4V',
 VALUE='47UF',
 PRIM_FILE='./archive_libs/logical/q_cap/chips/chips.prt';

PART_NAME
 C348 'Q_CAP_C0805-47UF,4V,20%,X6S,CHA':;

SECTION_NUMBER 1
 '@S9S_MB_2U_LIB.S9S_MB_2U(SCH_1):PAGE79_I32@PURE_QUANTA.Q_CAP(CHIPS)':
 C_PATH='@s9s_mb_2u_lib.s9s_mb_2u(sch_1):page79_i32@pure_quanta.q_cap(chips)',
 P_PATH='@s9s_mb_2u_lib.s9s_mb_2u(sch_1):page79_i32@pure_quanta.q_cap(chips)',
 PATH='I32',
 DRAWING='@S9S_MB_2U_LIB.S9S_MB_2U(SCH_1):PAGE79',
 PHYS_PAGE='79',
 XY='(-3050,2400)',
 ROT='0',
 VER='1',
 PACK_TYPE='C0805',
 CDS_LIB='pure_quanta',
 CDS_PART_NAME='Q_CAP_C0805-47UF,4V,20%,X6S,CHA',
 TOLERANCE='20%',
 MATERIAL='X6S',
 VOLTAGE='4V',
 VALUE='47UF',
 PRIM_FILE='./archive_libs/logical/q_cap/chips/chips.prt';

PART_NAME
 C349 'Q_CAP_C0805-47UF,4V,20%,X6S,CHA':;

SECTION_NUMBER 1
 '@S9S_MB_2U_LIB.S9S_MB_2U(SCH_1):PAGE78_I63@PURE_QUANTA.Q_CAP(CHIPS)':
 C_PATH='@s9s_mb_2u_lib.s9s_mb_2u(sch_1):page78_i63@pure_quanta.q_cap(chips)',
 P_PATH='@s9s_mb_2u_lib.s9s_mb_2u(sch_1):page78_i63@pure_quanta.q_cap(chips)',
 PATH='I63',
 DRAWING='@S9S_MB_2U_LIB.S9S_MB_2U(SCH_1):PAGE78',
 PHYS_PAGE='78',
 XY='(50,2400)',
 ROT='0',
 VER='1',
 PACK_TYPE='C0805',
 CDS_LIB='pure_quanta',
 CDS_PART_NAME='Q_CAP_C0805-47UF,4V,20%,X6S,CHA',
 TOLERANCE='20%',
 MATERIAL='X6S',
 VOLTAGE='4V',
 VALUE='47UF',
 PRIM_FILE='./archive_libs/logical/q_cap/chips/chips.prt';

PART_NAME
 C350 'Q_CAP_C0805-47UF,4V,20%,X6S,CHA':;

SECTION_NUMBER 1
 '@S9S_MB_2U_LIB.S9S_MB_2U(SCH_1):PAGE79_I33@PURE_QUANTA.Q_CAP(CHIPS)':
 C_PATH='@s9s_mb_2u_lib.s9s_mb_2u(sch_1):page79_i33@pure_quanta.q_cap(chips)',
 P_PATH='@s9s_mb_2u_lib.s9s_mb_2u(sch_1):page79_i33@pure_quanta.q_cap(chips)',
 PATH='I33',
 DRAWING='@S9S_MB_2U_LIB.S9S_MB_2U(SCH_1):PAGE79',
 PHYS_PAGE='79',
 XY='(-2600,2400)',
 ROT='0',
 VER='1',
 PACK_TYPE='C0805',
 CDS_LIB='pure_quanta',
 CDS_PART_NAME='Q_CAP_C0805-47UF,4V,20%,X6S,CHA',
 TOLERANCE='20%',
 MATERIAL='X6S',
 VOLTAGE='4V',
 VALUE='47UF',
 PRIM_FILE='./archive_libs/logical/q_cap/chips/chips.prt';

PART_NAME
 C351 'Q_CAP_C0805-47UF,4V,20%,X6S,CHA':;

SECTION_NUMBER 1
 '@S9S_MB_2U_LIB.S9S_MB_2U(SCH_1):PAGE78_I64@PURE_QUANTA.Q_CAP(CHIPS)':
 C_PATH='@s9s_mb_2u_lib.s9s_mb_2u(sch_1):page78_i64@pure_quanta.q_cap(chips)',
 P_PATH='@s9s_mb_2u_lib.s9s_mb_2u(sch_1):page78_i64@pure_quanta.q_cap(chips)',
 PATH='I64',
 DRAWING='@S9S_MB_2U_LIB.S9S_MB_2U(SCH_1):PAGE78',
 PHYS_PAGE='78',
 XY='(500,2400)',
 ROT='0',
 VER='1',
 PACK_TYPE='C0805',
 CDS_LIB='pure_quanta',
 CDS_PART_NAME='Q_CAP_C0805-47UF,4V,20%,X6S,CHA',
 TOLERANCE='20%',
 MATERIAL='X6S',
 VOLTAGE='4V',
 VALUE='47UF',
 PRIM_FILE='./archive_libs/logical/q_cap/chips/chips.prt';

PART_NAME
 C352 'Q_CAP_C0805-47UF,4V,20%,X6S,CHA':;

SECTION_NUMBER 1
 '@S9S_MB_2U_LIB.S9S_MB_2U(SCH_1):PAGE79_I34@PURE_QUANTA.Q_CAP(CHIPS)':
 C_PATH='@s9s_mb_2u_lib.s9s_mb_2u(sch_1):page79_i34@pure_quanta.q_cap(chips)',
 P_PATH='@s9s_mb_2u_lib.s9s_mb_2u(sch_1):page79_i34@pure_quanta.q_cap(chips)',
 PATH='I34',
 DRAWING='@S9S_MB_2U_LIB.S9S_MB_2U(SCH_1):PAGE79',
 PHYS_PAGE='79',
 XY='(-2150,2400)',
 ROT='0',
 VER='1',
 PACK_TYPE='C0805',
 CDS_LIB='pure_quanta',
 CDS_PART_NAME='Q_CAP_C0805-47UF,4V,20%,X6S,CHA',
 TOLERANCE='20%',
 MATERIAL='X6S',
 VOLTAGE='4V',
 VALUE='47UF',
 PRIM_FILE='./archive_libs/logical/q_cap/chips/chips.prt';

PART_NAME
 C353 'Q_CAP_C0805-47UF,4V,20%,X6S,CHA':;

SECTION_NUMBER 1
 '@S9S_MB_2U_LIB.S9S_MB_2U(SCH_1):PAGE78_I65@PURE_QUANTA.Q_CAP(CHIPS)':
 C_PATH='@s9s_mb_2u_lib.s9s_mb_2u(sch_1):page78_i65@pure_quanta.q_cap(chips)',
 P_PATH='@s9s_mb_2u_lib.s9s_mb_2u(sch_1):page78_i65@pure_quanta.q_cap(chips)',
 PATH='I65',
 DRAWING='@S9S_MB_2U_LIB.S9S_MB_2U(SCH_1):PAGE78',
 PHYS_PAGE='78',
 XY='(950,2400)',
 ROT='0',
 VER='1',
 PACK_TYPE='C0805',
 CDS_LIB='pure_quanta',
 CDS_PART_NAME='Q_CAP_C0805-47UF,4V,20%,X6S,CHA',
 TOLERANCE='20%',
 MATERIAL='X6S',
 VOLTAGE='4V',
 VALUE='47UF',
 PRIM_FILE='./archive_libs/logical/q_cap/chips/chips.prt';

PART_NAME
 C354 'Q_CAP_C0805-47UF,4V,20%,X6S,CHA':;

SECTION_NUMBER 1
 '@S9S_MB_2U_LIB.S9S_MB_2U(SCH_1):PAGE79_I35@PURE_QUANTA.Q_CAP(CHIPS)':
 C_PATH='@s9s_mb_2u_lib.s9s_mb_2u(sch_1):page79_i35@pure_quanta.q_cap(chips)',
 P_PATH='@s9s_mb_2u_lib.s9s_mb_2u(sch_1):page79_i35@pure_quanta.q_cap(chips)',
 PATH='I35',
 DRAWING='@S9S_MB_2U_LIB.S9S_MB_2U(SCH_1):PAGE79',
 PHYS_PAGE='79',
 XY='(-1700,2400)',
 ROT='0',
 VER='1',
 PACK_TYPE='C0805',
 CDS_LIB='pure_quanta',
 CDS_PART_NAME='Q_CAP_C0805-47UF,4V,20%,X6S,CHA',
 TOLERANCE='20%',
 MATERIAL='X6S',
 VOLTAGE='4V',
 VALUE='47UF',
 PRIM_FILE='./archive_libs/logical/q_cap/chips/chips.prt';

PART_NAME
 C355 'Q_CAP_C0805-47UF,4V,20%,X6S,CHA':;

SECTION_NUMBER 1
 '@S9S_MB_2U_LIB.S9S_MB_2U(SCH_1):PAGE75_I23@PURE_QUANTA.Q_CAP(CHIPS)':
 C_PATH='@s9s_mb_2u_lib.s9s_mb_2u(sch_1):page75_i23@pure_quanta.q_cap(chips)',
 P_PATH='@s9s_mb_2u_lib.s9s_mb_2u(sch_1):page75_i23@pure_quanta.q_cap(chips)',
 PATH='I23',
 DRAWING='@S9S_MB_2U_LIB.S9S_MB_2U(SCH_1):PAGE75',
 PHYS_PAGE='75',
 XY='(-4425,2450)',
 ROT='0',
 VER='1',
 PACK_TYPE='C0805',
 CDS_LIB='pure_quanta',
 CDS_PART_NAME='Q_CAP_C0805-47UF,4V,20%,X6S,CHA',
 TOLERANCE='20%',
 MATERIAL='X6S',
 VOLTAGE='4V',
 VALUE='47UF',
 PRIM_FILE='./archive_libs/logical/q_cap/chips/chips.prt';

PART_NAME
 C356 'Q_CAP_C0805-47UF,4V,20%,X6S,CHA':;

SECTION_NUMBER 1
 '@S9S_MB_2U_LIB.S9S_MB_2U(SCH_1):PAGE75_I21@PURE_QUANTA.Q_CAP(CHIPS)':
 C_PATH='@s9s_mb_2u_lib.s9s_mb_2u(sch_1):page75_i21@pure_quanta.q_cap(chips)',
 P_PATH='@s9s_mb_2u_lib.s9s_mb_2u(sch_1):page75_i21@pure_quanta.q_cap(chips)',
 PATH='I21',
 DRAWING='@S9S_MB_2U_LIB.S9S_MB_2U(SCH_1):PAGE75',
 PHYS_PAGE='75',
 XY='(-4425,1725)',
 ROT='0',
 VER='1',
 PACK_TYPE='C0805',
 CDS_LIB='pure_quanta',
 CDS_PART_NAME='Q_CAP_C0805-47UF,4V,20%,X6S,CHA',
 TOLERANCE='20%',
 MATERIAL='X6S',
 VOLTAGE='4V',
 VALUE='47UF',
 PRIM_FILE='./archive_libs/logical/q_cap/chips/chips.prt';

PART_NAME
 C357 'Q_CAP_C0805-47UF,4V,20%,X6S,CHA':;

SECTION_NUMBER 1
 '@S9S_MB_2U_LIB.S9S_MB_2U(SCH_1):PAGE75_I38@PURE_QUANTA.Q_CAP(CHIPS)':
 C_PATH='@s9s_mb_2u_lib.s9s_mb_2u(sch_1):page75_i38@pure_quanta.q_cap(chips)',
 P_PATH='@s9s_mb_2u_lib.s9s_mb_2u(sch_1):page75_i38@pure_quanta.q_cap(chips)',
 PATH='I38',
 DRAWING='@S9S_MB_2U_LIB.S9S_MB_2U(SCH_1):PAGE75',
 PHYS_PAGE='75',
 XY='(-1275,1725)',
 ROT='0',
 VER='1',
 PACK_TYPE='C0805',
 CDS_LIB='pure_quanta',
 CDS_PART_NAME='Q_CAP_C0805-47UF,4V,20%,X6S,CHA',
 TOLERANCE='20%',
 MATERIAL='X6S',
 VOLTAGE='4V',
 VALUE='47UF',
 PRIM_FILE='./archive_libs/logical/q_cap/chips/chips.prt';

PART_NAME
 C358 'Q_CAP_C0805-47UF,4V,20%,X6S,CHA':;

SECTION_NUMBER 1
 '@S9S_MB_2U_LIB.S9S_MB_2U(SCH_1):PAGE75_I27@PURE_QUANTA.Q_CAP(CHIPS)':
 C_PATH='@s9s_mb_2u_lib.s9s_mb_2u(sch_1):page75_i27@pure_quanta.q_cap(chips)',
 P_PATH='@s9s_mb_2u_lib.s9s_mb_2u(sch_1):page75_i27@pure_quanta.q_cap(chips)',
 PATH='I27',
 DRAWING='@S9S_MB_2U_LIB.S9S_MB_2U(SCH_1):PAGE75',
 PHYS_PAGE='75',
 XY='(-3975,2450)',
 ROT='0',
 VER='1',
 PACK_TYPE='C0805',
 CDS_LIB='pure_quanta',
 CDS_PART_NAME='Q_CAP_C0805-47UF,4V,20%,X6S,CHA',
 TOLERANCE='20%',
 MATERIAL='X6S',
 VOLTAGE='4V',
 VALUE='47UF',
 PRIM_FILE='./archive_libs/logical/q_cap/chips/chips.prt';

PART_NAME
 C359 'Q_CAP_C0805-47UF,4V,20%,X6S,CHA':;

SECTION_NUMBER 1
 '@S9S_MB_2U_LIB.S9S_MB_2U(SCH_1):PAGE75_I25@PURE_QUANTA.Q_CAP(CHIPS)':
 C_PATH='@s9s_mb_2u_lib.s9s_mb_2u(sch_1):page75_i25@pure_quanta.q_cap(chips)',
 P_PATH='@s9s_mb_2u_lib.s9s_mb_2u(sch_1):page75_i25@pure_quanta.q_cap(chips)',
 PATH='I25',
 DRAWING='@S9S_MB_2U_LIB.S9S_MB_2U(SCH_1):PAGE75',
 PHYS_PAGE='75',
 XY='(-3975,1725)',
 ROT='0',
 VER='1',
 PACK_TYPE='C0805',
 CDS_LIB='pure_quanta',
 CDS_PART_NAME='Q_CAP_C0805-47UF,4V,20%,X6S,CHA',
 TOLERANCE='20%',
 MATERIAL='X6S',
 VOLTAGE='4V',
 VALUE='47UF',
 PRIM_FILE='./archive_libs/logical/q_cap/chips/chips.prt';

PART_NAME
 C360 'Q_CAP_C0805-47UF,4V,20%,X6S,CHA':;

SECTION_NUMBER 1
 '@S9S_MB_2U_LIB.S9S_MB_2U(SCH_1):PAGE75_I54@PURE_QUANTA.Q_CAP(CHIPS)':
 C_PATH='@s9s_mb_2u_lib.s9s_mb_2u(sch_1):page75_i54@pure_quanta.q_cap(chips)',
 P_PATH='@s9s_mb_2u_lib.s9s_mb_2u(sch_1):page75_i54@pure_quanta.q_cap(chips)',
 PATH='I54',
 DRAWING='@S9S_MB_2U_LIB.S9S_MB_2U(SCH_1):PAGE75',
 PHYS_PAGE='75',
 XY='(525,1725)',
 ROT='0',
 VER='1',
 PACK_TYPE='C0805',
 CDS_LIB='pure_quanta',
 CDS_PART_NAME='Q_CAP_C0805-47UF,4V,20%,X6S,CHA',
 TOLERANCE='20%',
 MATERIAL='X6S',
 VOLTAGE='4V',
 VALUE='47UF',
 PRIM_FILE='./archive_libs/logical/q_cap/chips/chips.prt';

PART_NAME
 C361 'Q_CAP_C0805-47UF,4V,20%,X6S,CHA':;

SECTION_NUMBER 1
 '@S9S_MB_2U_LIB.S9S_MB_2U(SCH_1):PAGE75_I28@PURE_QUANTA.Q_CAP(CHIPS)':
 C_PATH='@s9s_mb_2u_lib.s9s_mb_2u(sch_1):page75_i28@pure_quanta.q_cap(chips)',
 P_PATH='@s9s_mb_2u_lib.s9s_mb_2u(sch_1):page75_i28@pure_quanta.q_cap(chips)',
 PATH='I28',
 DRAWING='@S9S_MB_2U_LIB.S9S_MB_2U(SCH_1):PAGE75',
 PHYS_PAGE='75',
 XY='(-3525,2450)',
 ROT='0',
 VER='1',
 PACK_TYPE='C0805',
 CDS_LIB='pure_quanta',
 CDS_PART_NAME='Q_CAP_C0805-47UF,4V,20%,X6S,CHA',
 TOLERANCE='20%',
 MATERIAL='X6S',
 VOLTAGE='4V',
 VALUE='47UF',
 PRIM_FILE='./archive_libs/logical/q_cap/chips/chips.prt';

PART_NAME
 C362 'Q_CAP_C0805-47UF,4V,20%,X6S,CHA':;

SECTION_NUMBER 1
 '@S9S_MB_2U_LIB.S9S_MB_2U(SCH_1):PAGE75_I26@PURE_QUANTA.Q_CAP(CHIPS)':
 C_PATH='@s9s_mb_2u_lib.s9s_mb_2u(sch_1):page75_i26@pure_quanta.q_cap(chips)',
 P_PATH='@s9s_mb_2u_lib.s9s_mb_2u(sch_1):page75_i26@pure_quanta.q_cap(chips)',
 PATH='I26',
 DRAWING='@S9S_MB_2U_LIB.S9S_MB_2U(SCH_1):PAGE75',
 PHYS_PAGE='75',
 XY='(-3525,1725)',
 ROT='0',
 VER='1',
 PACK_TYPE='C0805',
 CDS_LIB='pure_quanta',
 CDS_PART_NAME='Q_CAP_C0805-47UF,4V,20%,X6S,CHA',
 TOLERANCE='20%',
 MATERIAL='X6S',
 VOLTAGE='4V',
 VALUE='47UF',
 PRIM_FILE='./archive_libs/logical/q_cap/chips/chips.prt';

PART_NAME
 C363 'Q_CAP_C0805-47UF,4V,20%,X6S,CHA':;

SECTION_NUMBER 1
 '@S9S_MB_2U_LIB.S9S_MB_2U(SCH_1):PAGE75_I64@PURE_QUANTA.Q_CAP(CHIPS)':
 C_PATH='@s9s_mb_2u_lib.s9s_mb_2u(sch_1):page75_i64@pure_quanta.q_cap(chips)',
 P_PATH='@s9s_mb_2u_lib.s9s_mb_2u(sch_1):page75_i64@pure_quanta.q_cap(chips)',
 PATH='I64',
 DRAWING='@S9S_MB_2U_LIB.S9S_MB_2U(SCH_1):PAGE75',
 PHYS_PAGE='75',
 XY='(975,2450)',
 ROT='0',
 VER='1',
 PACK_TYPE='C0805',
 CDS_LIB='pure_quanta',
 CDS_PART_NAME='Q_CAP_C0805-47UF,4V,20%,X6S,CHA',
 TOLERANCE='20%',
 MATERIAL='X6S',
 VOLTAGE='4V',
 VALUE='47UF',
 PRIM_FILE='./archive_libs/logical/q_cap/chips/chips.prt';

PART_NAME
 C364 'Q_CAP_C0805-47UF,4V,20%,X6S,CHA':;

SECTION_NUMBER 1
 '@S9S_MB_2U_LIB.S9S_MB_2U(SCH_1):PAGE75_I34@PURE_QUANTA.Q_CAP(CHIPS)':
 C_PATH='@s9s_mb_2u_lib.s9s_mb_2u(sch_1):page75_i34@pure_quanta.q_cap(chips)',
 P_PATH='@s9s_mb_2u_lib.s9s_mb_2u(sch_1):page75_i34@pure_quanta.q_cap(chips)',
 PATH='I34',
 DRAWING='@S9S_MB_2U_LIB.S9S_MB_2U(SCH_1):PAGE75',
 PHYS_PAGE='75',
 XY='(-3075,2450)',
 ROT='0',
 VER='1',
 PACK_TYPE='C0805',
 CDS_LIB='pure_quanta',
 CDS_PART_NAME='Q_CAP_C0805-47UF,4V,20%,X6S,CHA',
 TOLERANCE='20%',
 MATERIAL='X6S',
 VOLTAGE='4V',
 VALUE='47UF',
 PRIM_FILE='./archive_libs/logical/q_cap/chips/chips.prt';

PART_NAME
 C365 'Q_CAP_C0805-47UF,4V,20%,X6S,CHA':;

SECTION_NUMBER 1
 '@S9S_MB_2U_LIB.S9S_MB_2U(SCH_1):PAGE75_I32@PURE_QUANTA.Q_CAP(CHIPS)':
 C_PATH='@s9s_mb_2u_lib.s9s_mb_2u(sch_1):page75_i32@pure_quanta.q_cap(chips)',
 P_PATH='@s9s_mb_2u_lib.s9s_mb_2u(sch_1):page75_i32@pure_quanta.q_cap(chips)',
 PATH='I32',
 DRAWING='@S9S_MB_2U_LIB.S9S_MB_2U(SCH_1):PAGE75',
 PHYS_PAGE='75',
 XY='(-3075,1725)',
 ROT='0',
 VER='1',
 PACK_TYPE='C0805',
 CDS_LIB='pure_quanta',
 CDS_PART_NAME='Q_CAP_C0805-47UF,4V,20%,X6S,CHA',
 TOLERANCE='20%',
 MATERIAL='X6S',
 VOLTAGE='4V',
 VALUE='47UF',
 PRIM_FILE='./archive_libs/logical/q_cap/chips/chips.prt';

PART_NAME
 C366 'Q_CAP_C0805-47UF,4V,20%,X6S,CHA':;

SECTION_NUMBER 1
 '@S9S_MB_2U_LIB.S9S_MB_2U(SCH_1):PAGE76_I48@PURE_QUANTA.Q_CAP(CHIPS)':
 C_PATH='@s9s_mb_2u_lib.s9s_mb_2u(sch_1):page76_i48@pure_quanta.q_cap(chips)',
 P_PATH='@s9s_mb_2u_lib.s9s_mb_2u(sch_1):page76_i48@pure_quanta.q_cap(chips)',
 PATH='I48',
 DRAWING='@S9S_MB_2U_LIB.S9S_MB_2U(SCH_1):PAGE76',
 PHYS_PAGE='76',
 XY='(-775,8825)',
 ROT='0',
 VER='1',
 PACK_TYPE='C0805',
 CDS_LIB='pure_quanta',
 CDS_PART_NAME='Q_CAP_C0805-47UF,4V,20%,X6S,CHA',
 TOLERANCE='20%',
 MATERIAL='X6S',
 VOLTAGE='4V',
 VALUE='47UF',
 PRIM_FILE='./archive_libs/logical/q_cap/chips/chips.prt';

PART_NAME
 C367 'Q_CAP_C0805-47UF,4V,20%,X6S,CHA':;

SECTION_NUMBER 1
 '@S9S_MB_2U_LIB.S9S_MB_2U(SCH_1):PAGE75_I35@PURE_QUANTA.Q_CAP(CHIPS)':
 C_PATH='@s9s_mb_2u_lib.s9s_mb_2u(sch_1):page75_i35@pure_quanta.q_cap(chips)',
 P_PATH='@s9s_mb_2u_lib.s9s_mb_2u(sch_1):page75_i35@pure_quanta.q_cap(chips)',
 PATH='I35',
 DRAWING='@S9S_MB_2U_LIB.S9S_MB_2U(SCH_1):PAGE75',
 PHYS_PAGE='75',
 XY='(-2625,2450)',
 ROT='0',
 VER='1',
 PACK_TYPE='C0805',
 CDS_LIB='pure_quanta',
 CDS_PART_NAME='Q_CAP_C0805-47UF,4V,20%,X6S,CHA',
 TOLERANCE='20%',
 MATERIAL='X6S',
 VOLTAGE='4V',
 VALUE='47UF',
 PRIM_FILE='./archive_libs/logical/q_cap/chips/chips.prt';

PART_NAME
 C368 'Q_CAP_C0805-47UF,4V,20%,X6S,CHA':;

SECTION_NUMBER 1
 '@S9S_MB_2U_LIB.S9S_MB_2U(SCH_1):PAGE75_I33@PURE_QUANTA.Q_CAP(CHIPS)':
 C_PATH='@s9s_mb_2u_lib.s9s_mb_2u(sch_1):page75_i33@pure_quanta.q_cap(chips)',
 P_PATH='@s9s_mb_2u_lib.s9s_mb_2u(sch_1):page75_i33@pure_quanta.q_cap(chips)',
 PATH='I33',
 DRAWING='@S9S_MB_2U_LIB.S9S_MB_2U(SCH_1):PAGE75',
 PHYS_PAGE='75',
 XY='(-2625,1725)',
 ROT='0',
 VER='1',
 PACK_TYPE='C0805',
 CDS_LIB='pure_quanta',
 CDS_PART_NAME='Q_CAP_C0805-47UF,4V,20%,X6S,CHA',
 TOLERANCE='20%',
 MATERIAL='X6S',
 VOLTAGE='4V',
 VALUE='47UF',
 PRIM_FILE='./archive_libs/logical/q_cap/chips/chips.prt';

PART_NAME
 C369 'Q_CAP_C0805-47UF,4V,20%,X6S,CHA':;

SECTION_NUMBER 1
 '@S9S_MB_2U_LIB.S9S_MB_2U(SCH_1):PAGE76_I49@PURE_QUANTA.Q_CAP(CHIPS)':
 C_PATH='@s9s_mb_2u_lib.s9s_mb_2u(sch_1):page76_i49@pure_quanta.q_cap(chips)',
 P_PATH='@s9s_mb_2u_lib.s9s_mb_2u(sch_1):page76_i49@pure_quanta.q_cap(chips)',
 PATH='I49',
 DRAWING='@S9S_MB_2U_LIB.S9S_MB_2U(SCH_1):PAGE76',
 PHYS_PAGE='76',
 XY='(-325,8825)',
 ROT='0',
 VER='1',
 PACK_TYPE='C0805',
 CDS_LIB='pure_quanta',
 CDS_PART_NAME='Q_CAP_C0805-47UF,4V,20%,X6S,CHA',
 TOLERANCE='20%',
 MATERIAL='X6S',
 VOLTAGE='4V',
 VALUE='47UF',
 PRIM_FILE='./archive_libs/logical/q_cap/chips/chips.prt';

PART_NAME
 C370 'Q_CAP_C0805-47UF,4V,20%,X6S,CHA':;

SECTION_NUMBER 1
 '@S9S_MB_2U_LIB.S9S_MB_2U(SCH_1):PAGE75_I39@PURE_QUANTA.Q_CAP(CHIPS)':
 C_PATH='@s9s_mb_2u_lib.s9s_mb_2u(sch_1):page75_i39@pure_quanta.q_cap(chips)',
 P_PATH='@s9s_mb_2u_lib.s9s_mb_2u(sch_1):page75_i39@pure_quanta.q_cap(chips)',
 PATH='I39',
 DRAWING='@S9S_MB_2U_LIB.S9S_MB_2U(SCH_1):PAGE75',
 PHYS_PAGE='75',
 XY='(-2175,2450)',
 ROT='0',
 VER='1',
 PACK_TYPE='C0805',
 CDS_LIB='pure_quanta',
 CDS_PART_NAME='Q_CAP_C0805-47UF,4V,20%,X6S,CHA',
 TOLERANCE='20%',
 MATERIAL='X6S',
 VOLTAGE='4V',
 VALUE='47UF',
 PRIM_FILE='./archive_libs/logical/q_cap/chips/chips.prt';

PART_NAME
 C371 'Q_CAP_C0805-47UF,4V,20%,X6S,CHA':;

SECTION_NUMBER 1
 '@S9S_MB_2U_LIB.S9S_MB_2U(SCH_1):PAGE75_I36@PURE_QUANTA.Q_CAP(CHIPS)':
 C_PATH='@s9s_mb_2u_lib.s9s_mb_2u(sch_1):page75_i36@pure_quanta.q_cap(chips)',
 P_PATH='@s9s_mb_2u_lib.s9s_mb_2u(sch_1):page75_i36@pure_quanta.q_cap(chips)',
 PATH='I36',
 DRAWING='@S9S_MB_2U_LIB.S9S_MB_2U(SCH_1):PAGE75',
 PHYS_PAGE='75',
 XY='(-2175,1725)',
 ROT='0',
 VER='1',
 PACK_TYPE='C0805',
 CDS_LIB='pure_quanta',
 CDS_PART_NAME='Q_CAP_C0805-47UF,4V,20%,X6S,CHA',
 TOLERANCE='20%',
 MATERIAL='X6S',
 VOLTAGE='4V',
 VALUE='47UF',
 PRIM_FILE='./archive_libs/logical/q_cap/chips/chips.prt';

PART_NAME
 C372 'Q_CAP_C0805-47UF,4V,20%,X6S,CHA':;

SECTION_NUMBER 1
 '@S9S_MB_2U_LIB.S9S_MB_2U(SCH_1):PAGE76_I50@PURE_QUANTA.Q_CAP(CHIPS)':
 C_PATH='@s9s_mb_2u_lib.s9s_mb_2u(sch_1):page76_i50@pure_quanta.q_cap(chips)',
 P_PATH='@s9s_mb_2u_lib.s9s_mb_2u(sch_1):page76_i50@pure_quanta.q_cap(chips)',
 PATH='I50',
 DRAWING='@S9S_MB_2U_LIB.S9S_MB_2U(SCH_1):PAGE76',
 PHYS_PAGE='76',
 XY='(125,8825)',
 ROT='0',
 VER='1',
 PACK_TYPE='C0805',
 CDS_LIB='pure_quanta',
 CDS_PART_NAME='Q_CAP_C0805-47UF,4V,20%,X6S,CHA',
 TOLERANCE='20%',
 MATERIAL='X6S',
 VOLTAGE='4V',
 VALUE='47UF',
 PRIM_FILE='./archive_libs/logical/q_cap/chips/chips.prt';

PART_NAME
 C373 'Q_CAP_C0805-47UF,4V,20%,X6S,CHA':;

SECTION_NUMBER 1
 '@S9S_MB_2U_LIB.S9S_MB_2U(SCH_1):PAGE75_I40@PURE_QUANTA.Q_CAP(CHIPS)':
 C_PATH='@s9s_mb_2u_lib.s9s_mb_2u(sch_1):page75_i40@pure_quanta.q_cap(chips)',
 P_PATH='@s9s_mb_2u_lib.s9s_mb_2u(sch_1):page75_i40@pure_quanta.q_cap(chips)',
 PATH='I40',
 DRAWING='@S9S_MB_2U_LIB.S9S_MB_2U(SCH_1):PAGE75',
 PHYS_PAGE='75',
 XY='(-1725,2450)',
 ROT='0',
 VER='1',
 PACK_TYPE='C0805',
 CDS_LIB='pure_quanta',
 CDS_PART_NAME='Q_CAP_C0805-47UF,4V,20%,X6S,CHA',
 TOLERANCE='20%',
 MATERIAL='X6S',
 VOLTAGE='4V',
 VALUE='47UF',
 PRIM_FILE='./archive_libs/logical/q_cap/chips/chips.prt';

PART_NAME
 C374 'Q_CAP_C0805-47UF,4V,20%,X6S,CHA':;

SECTION_NUMBER 1
 '@S9S_MB_2U_LIB.S9S_MB_2U(SCH_1):PAGE76_I51@PURE_QUANTA.Q_CAP(CHIPS)':
 C_PATH='@s9s_mb_2u_lib.s9s_mb_2u(sch_1):page76_i51@pure_quanta.q_cap(chips)',
 P_PATH='@s9s_mb_2u_lib.s9s_mb_2u(sch_1):page76_i51@pure_quanta.q_cap(chips)',
 PATH='I51',
 DRAWING='@S9S_MB_2U_LIB.S9S_MB_2U(SCH_1):PAGE76',
 PHYS_PAGE='76',
 XY='(575,8825)',
 ROT='0',
 VER='1',
 PACK_TYPE='C0805',
 CDS_LIB='pure_quanta',
 CDS_PART_NAME='Q_CAP_C0805-47UF,4V,20%,X6S,CHA',
 TOLERANCE='20%',
 MATERIAL='X6S',
 VOLTAGE='4V',
 VALUE='47UF',
 PRIM_FILE='./archive_libs/logical/q_cap/chips/chips.prt';

PART_NAME
 C376 'Q_CAP_C0805-47UF,4V,20%,X6S,CHA':;

SECTION_NUMBER 1
 '@S9S_MB_2U_LIB.S9S_MB_2U(SCH_1):PAGE75_I41@PURE_QUANTA.Q_CAP(CHIPS)':
 C_PATH='@s9s_mb_2u_lib.s9s_mb_2u(sch_1):page75_i41@pure_quanta.q_cap(chips)',
 P_PATH='@s9s_mb_2u_lib.s9s_mb_2u(sch_1):page75_i41@pure_quanta.q_cap(chips)',
 PATH='I41',
 DRAWING='@S9S_MB_2U_LIB.S9S_MB_2U(SCH_1):PAGE75',
 PHYS_PAGE='75',
 XY='(-1275,2450)',
 ROT='0',
 VER='1',
 PACK_TYPE='C0805',
 CDS_LIB='pure_quanta',
 CDS_PART_NAME='Q_CAP_C0805-47UF,4V,20%,X6S,CHA',
 TOLERANCE='20%',
 MATERIAL='X6S',
 VOLTAGE='4V',
 VALUE='47UF',
 PRIM_FILE='./archive_libs/logical/q_cap/chips/chips.prt';

PART_NAME
 C377 'Q_CAP_C0805-47UF,4V,20%,X6S,CHA':;

SECTION_NUMBER 1
 '@S9S_MB_2U_LIB.S9S_MB_2U(SCH_1):PAGE76_I52@PURE_QUANTA.Q_CAP(CHIPS)':
 C_PATH='@s9s_mb_2u_lib.s9s_mb_2u(sch_1):page76_i52@pure_quanta.q_cap(chips)',
 P_PATH='@s9s_mb_2u_lib.s9s_mb_2u(sch_1):page76_i52@pure_quanta.q_cap(chips)',
 PATH='I52',
 DRAWING='@S9S_MB_2U_LIB.S9S_MB_2U(SCH_1):PAGE76',
 PHYS_PAGE='76',
 XY='(1025,8825)',
 ROT='0',
 VER='1',
 PACK_TYPE='C0805',
 CDS_LIB='pure_quanta',
 CDS_PART_NAME='Q_CAP_C0805-47UF,4V,20%,X6S,CHA',
 TOLERANCE='20%',
 MATERIAL='X6S',
 VOLTAGE='4V',
 VALUE='47UF',
 PRIM_FILE='./archive_libs/logical/q_cap/chips/chips.prt';

PART_NAME
 C379 'Q_CAP_C0805-47UF,4V,20%,X6S,CHA':;

SECTION_NUMBER 1
 '@S9S_MB_2U_LIB.S9S_MB_2U(SCH_1):PAGE75_I50@PURE_QUANTA.Q_CAP(CHIPS)':
 C_PATH='@s9s_mb_2u_lib.s9s_mb_2u(sch_1):page75_i50@pure_quanta.q_cap(chips)',
 P_PATH='@s9s_mb_2u_lib.s9s_mb_2u(sch_1):page75_i50@pure_quanta.q_cap(chips)',
 PATH='I50',
 DRAWING='@S9S_MB_2U_LIB.S9S_MB_2U(SCH_1):PAGE75',
 PHYS_PAGE='75',
 XY='(-825,2450)',
 ROT='0',
 VER='1',
 PACK_TYPE='C0805',
 CDS_LIB='pure_quanta',
 CDS_PART_NAME='Q_CAP_C0805-47UF,4V,20%,X6S,CHA',
 TOLERANCE='20%',
 MATERIAL='X6S',
 VOLTAGE='4V',
 VALUE='47UF',
 PRIM_FILE='./archive_libs/logical/q_cap/chips/chips.prt';

PART_NAME
 C380 'Q_CAP_C0805-47UF,4V,20%,X6S,CHA':;

SECTION_NUMBER 1
 '@S9S_MB_2U_LIB.S9S_MB_2U(SCH_1):PAGE76_I53@PURE_QUANTA.Q_CAP(CHIPS)':
 C_PATH='@s9s_mb_2u_lib.s9s_mb_2u(sch_1):page76_i53@pure_quanta.q_cap(chips)',
 P_PATH='@s9s_mb_2u_lib.s9s_mb_2u(sch_1):page76_i53@pure_quanta.q_cap(chips)',
 PATH='I53',
 DRAWING='@S9S_MB_2U_LIB.S9S_MB_2U(SCH_1):PAGE76',
 PHYS_PAGE='76',
 XY='(1475,8825)',
 ROT='0',
 VER='1',
 PACK_TYPE='C0805',
 CDS_LIB='pure_quanta',
 CDS_PART_NAME='Q_CAP_C0805-47UF,4V,20%,X6S,CHA',
 TOLERANCE='20%',
 MATERIAL='X6S',
 VOLTAGE='4V',
 VALUE='47UF',
 PRIM_FILE='./archive_libs/logical/q_cap/chips/chips.prt';

PART_NAME
 C381 'Q_CAP_C0805-47UF,4V,20%,X6S,CHA':;

SECTION_NUMBER 1
 '@S9S_MB_2U_LIB.S9S_MB_2U(SCH_1):PAGE75_I67@PURE_QUANTA.Q_CAP(CHIPS)':
 C_PATH='@s9s_mb_2u_lib.s9s_mb_2u(sch_1):page75_i67@pure_quanta.q_cap(chips)',
 P_PATH='@s9s_mb_2u_lib.s9s_mb_2u(sch_1):page75_i67@pure_quanta.q_cap(chips)',
 PATH='I67',
 DRAWING='@S9S_MB_2U_LIB.S9S_MB_2U(SCH_1):PAGE75',
 PHYS_PAGE='75',
 XY='(2750,2425)',
 ROT='0',
 VER='1',
 PACK_TYPE='C0805',
 CDS_LIB='pure_quanta',
 CDS_PART_NAME='Q_CAP_C0805-47UF,4V,20%,X6S,CHA',
 TOLERANCE='20%',
 MATERIAL='X6S',
 VOLTAGE='4V',
 VALUE='47UF',
 PRIM_FILE='./archive_libs/logical/q_cap/chips/chips.prt';

PART_NAME
 C382 'Q_CAP_C0805-47UF,4V,20%,X6S,CHA':;

SECTION_NUMBER 1
 '@S9S_MB_2U_LIB.S9S_MB_2U(SCH_1):PAGE75_I51@PURE_QUANTA.Q_CAP(CHIPS)':
 C_PATH='@s9s_mb_2u_lib.s9s_mb_2u(sch_1):page75_i51@pure_quanta.q_cap(chips)',
 P_PATH='@s9s_mb_2u_lib.s9s_mb_2u(sch_1):page75_i51@pure_quanta.q_cap(chips)',
 PATH='I51',
 DRAWING='@S9S_MB_2U_LIB.S9S_MB_2U(SCH_1):PAGE75',
 PHYS_PAGE='75',
 XY='(-375,2450)',
 ROT='0',
 VER='1',
 PACK_TYPE='C0805',
 CDS_LIB='pure_quanta',
 CDS_PART_NAME='Q_CAP_C0805-47UF,4V,20%,X6S,CHA',
 TOLERANCE='20%',
 MATERIAL='X6S',
 VOLTAGE='4V',
 VALUE='47UF',
 PRIM_FILE='./archive_libs/logical/q_cap/chips/chips.prt';

PART_NAME
 C383 'Q_CAP_C0805-47UF,4V,20%,X6S,CHA':;

SECTION_NUMBER 1
 '@S9S_MB_2U_LIB.S9S_MB_2U(SCH_1):PAGE76_I54@PURE_QUANTA.Q_CAP(CHIPS)':
 C_PATH='@s9s_mb_2u_lib.s9s_mb_2u(sch_1):page76_i54@pure_quanta.q_cap(chips)',
 P_PATH='@s9s_mb_2u_lib.s9s_mb_2u(sch_1):page76_i54@pure_quanta.q_cap(chips)',
 PATH='I54',
 DRAWING='@S9S_MB_2U_LIB.S9S_MB_2U(SCH_1):PAGE76',
 PHYS_PAGE='76',
 XY='(1925,8825)',
 ROT='0',
 VER='1',
 PACK_TYPE='C0805',
 CDS_LIB='pure_quanta',
 CDS_PART_NAME='Q_CAP_C0805-47UF,4V,20%,X6S,CHA',
 TOLERANCE='20%',
 MATERIAL='X6S',
 VOLTAGE='4V',
 VALUE='47UF',
 PRIM_FILE='./archive_libs/logical/q_cap/chips/chips.prt';

PART_NAME
 C385 'Q_CAP_C0805-47UF,4V,20%,X6S,CHA':;

SECTION_NUMBER 1
 '@S9S_MB_2U_LIB.S9S_MB_2U(SCH_1):PAGE75_I55@PURE_QUANTA.Q_CAP(CHIPS)':
 C_PATH='@s9s_mb_2u_lib.s9s_mb_2u(sch_1):page75_i55@pure_quanta.q_cap(chips)',
 P_PATH='@s9s_mb_2u_lib.s9s_mb_2u(sch_1):page75_i55@pure_quanta.q_cap(chips)',
 PATH='I55',
 DRAWING='@S9S_MB_2U_LIB.S9S_MB_2U(SCH_1):PAGE75',
 PHYS_PAGE='75',
 XY='(75,2450)',
 ROT='0',
 VER='1',
 PACK_TYPE='C0805',
 CDS_LIB='pure_quanta',
 CDS_PART_NAME='Q_CAP_C0805-47UF,4V,20%,X6S,CHA',
 TOLERANCE='20%',
 MATERIAL='X6S',
 VOLTAGE='4V',
 VALUE='47UF',
 PRIM_FILE='./archive_libs/logical/q_cap/chips/chips.prt';

PART_NAME
 C386 'Q_CAP_C0805-47UF,4V,20%,X6S,CHA':;

SECTION_NUMBER 1
 '@S9S_MB_2U_LIB.S9S_MB_2U(SCH_1):PAGE76_I22@PURE_QUANTA.Q_CAP(CHIPS)':
 C_PATH='@s9s_mb_2u_lib.s9s_mb_2u(sch_1):page76_i22@pure_quanta.q_cap(chips)',
 P_PATH='@s9s_mb_2u_lib.s9s_mb_2u(sch_1):page76_i22@pure_quanta.q_cap(chips)',
 PATH='I22',
 DRAWING='@S9S_MB_2U_LIB.S9S_MB_2U(SCH_1):PAGE76',
 PHYS_PAGE='76',
 XY='(-3925,8825)',
 ROT='0',
 VER='1',
 PACK_TYPE='C0805',
 CDS_LIB='pure_quanta',
 CDS_PART_NAME='Q_CAP_C0805-47UF,4V,20%,X6S,CHA',
 TOLERANCE='20%',
 MATERIAL='X6S',
 VOLTAGE='4V',
 VALUE='47UF',
 PRIM_FILE='./archive_libs/logical/q_cap/chips/chips.prt';

PART_NAME
 C387 'Q_CAP_C0805-47UF,4V,20%,X6S,CHA':;

SECTION_NUMBER 1
 '@S9S_MB_2U_LIB.S9S_MB_2U(SCH_1):PAGE75_I56@PURE_QUANTA.Q_CAP(CHIPS)':
 C_PATH='@s9s_mb_2u_lib.s9s_mb_2u(sch_1):page75_i56@pure_quanta.q_cap(chips)',
 P_PATH='@s9s_mb_2u_lib.s9s_mb_2u(sch_1):page75_i56@pure_quanta.q_cap(chips)',
 PATH='I56',
 DRAWING='@S9S_MB_2U_LIB.S9S_MB_2U(SCH_1):PAGE75',
 PHYS_PAGE='75',
 XY='(525,2450)',
 ROT='0',
 VER='1',
 PACK_TYPE='C0805',
 CDS_LIB='pure_quanta',
 CDS_PART_NAME='Q_CAP_C0805-47UF,4V,20%,X6S,CHA',
 TOLERANCE='20%',
 MATERIAL='X6S',
 VOLTAGE='4V',
 VALUE='47UF',
 PRIM_FILE='./archive_libs/logical/q_cap/chips/chips.prt';

PART_NAME
 C388 'Q_CAP_C0805-47UF,4V,20%,X6S,CHA':;

SECTION_NUMBER 1
 '@S9S_MB_2U_LIB.S9S_MB_2U(SCH_1):PAGE76_I23@PURE_QUANTA.Q_CAP(CHIPS)':
 C_PATH='@s9s_mb_2u_lib.s9s_mb_2u(sch_1):page76_i23@pure_quanta.q_cap(chips)',
 P_PATH='@s9s_mb_2u_lib.s9s_mb_2u(sch_1):page76_i23@pure_quanta.q_cap(chips)',
 PATH='I23',
 DRAWING='@S9S_MB_2U_LIB.S9S_MB_2U(SCH_1):PAGE76',
 PHYS_PAGE='76',
 XY='(-3475,8825)',
 ROT='0',
 VER='1',
 PACK_TYPE='C0805',
 CDS_LIB='pure_quanta',
 CDS_PART_NAME='Q_CAP_C0805-47UF,4V,20%,X6S,CHA',
 TOLERANCE='20%',
 MATERIAL='X6S',
 VOLTAGE='4V',
 VALUE='47UF',
 PRIM_FILE='./archive_libs/logical/q_cap/chips/chips.prt';

PART_NAME
 C389 'Q_CAP_C0805-47UF,4V,20%,X6S,CHA':;

SECTION_NUMBER 1
 '@S9S_MB_2U_LIB.S9S_MB_2U(SCH_1):PAGE75_I48@PURE_QUANTA.Q_CAP(CHIPS)':
 C_PATH='@s9s_mb_2u_lib.s9s_mb_2u(sch_1):page75_i48@pure_quanta.q_cap(chips)',
 P_PATH='@s9s_mb_2u_lib.s9s_mb_2u(sch_1):page75_i48@pure_quanta.q_cap(chips)',
 PATH='I48',
 DRAWING='@S9S_MB_2U_LIB.S9S_MB_2U(SCH_1):PAGE75',
 PHYS_PAGE='75',
 XY='(-825,1725)',
 ROT='0',
 VER='1',
 PACK_TYPE='C0805',
 CDS_LIB='pure_quanta',
 CDS_PART_NAME='Q_CAP_C0805-47UF,4V,20%,X6S,CHA',
 TOLERANCE='20%',
 MATERIAL='X6S',
 VOLTAGE='4V',
 VALUE='47UF',
 PRIM_FILE='./archive_libs/logical/q_cap/chips/chips.prt';

PART_NAME
 C390 'Q_CAP_C0805-47UF,4V,20%,X6S,CHA':;

SECTION_NUMBER 1
 '@S9S_MB_2U_LIB.S9S_MB_2U(SCH_1):PAGE76_I25@PURE_QUANTA.Q_CAP(CHIPS)':
 C_PATH='@s9s_mb_2u_lib.s9s_mb_2u(sch_1):page76_i25@pure_quanta.q_cap(chips)',
 P_PATH='@s9s_mb_2u_lib.s9s_mb_2u(sch_1):page76_i25@pure_quanta.q_cap(chips)',
 PATH='I25',
 DRAWING='@S9S_MB_2U_LIB.S9S_MB_2U(SCH_1):PAGE76',
 PHYS_PAGE='76',
 XY='(-3025,8825)',
 ROT='0',
 VER='1',
 PACK_TYPE='C0805',
 CDS_LIB='pure_quanta',
 CDS_PART_NAME='Q_CAP_C0805-47UF,4V,20%,X6S,CHA',
 TOLERANCE='20%',
 MATERIAL='X6S',
 VOLTAGE='4V',
 VALUE='47UF',
 PRIM_FILE='./archive_libs/logical/q_cap/chips/chips.prt';

PART_NAME
 C391 'Q_CAP_C0805-47UF,4V,20%,X6S,CHA':;

SECTION_NUMBER 1
 '@S9S_MB_2U_LIB.S9S_MB_2U(SCH_1):PAGE75_I49@PURE_QUANTA.Q_CAP(CHIPS)':
 C_PATH='@s9s_mb_2u_lib.s9s_mb_2u(sch_1):page75_i49@pure_quanta.q_cap(chips)',
 P_PATH='@s9s_mb_2u_lib.s9s_mb_2u(sch_1):page75_i49@pure_quanta.q_cap(chips)',
 PATH='I49',
 DRAWING='@S9S_MB_2U_LIB.S9S_MB_2U(SCH_1):PAGE75',
 PHYS_PAGE='75',
 XY='(-375,1725)',
 ROT='0',
 VER='1',
 PACK_TYPE='C0805',
 CDS_LIB='pure_quanta',
 CDS_PART_NAME='Q_CAP_C0805-47UF,4V,20%,X6S,CHA',
 TOLERANCE='20%',
 MATERIAL='X6S',
 VOLTAGE='4V',
 VALUE='47UF',
 PRIM_FILE='./archive_libs/logical/q_cap/chips/chips.prt';

PART_NAME
 C392 'Q_CAP_C0805-47UF,4V,20%,X6S,CHA':;

SECTION_NUMBER 1
 '@S9S_MB_2U_LIB.S9S_MB_2U(SCH_1):PAGE76_I44@PURE_QUANTA.Q_CAP(CHIPS)':
 C_PATH='@s9s_mb_2u_lib.s9s_mb_2u(sch_1):page76_i44@pure_quanta.q_cap(chips)',
 P_PATH='@s9s_mb_2u_lib.s9s_mb_2u(sch_1):page76_i44@pure_quanta.q_cap(chips)',
 PATH='I44',
 DRAWING='@S9S_MB_2U_LIB.S9S_MB_2U(SCH_1):PAGE76',
 PHYS_PAGE='76',
 XY='(-2575,8825)',
 ROT='0',
 VER='1',
 PACK_TYPE='C0805',
 CDS_LIB='pure_quanta',
 CDS_PART_NAME='Q_CAP_C0805-47UF,4V,20%,X6S,CHA',
 TOLERANCE='20%',
 MATERIAL='X6S',
 VOLTAGE='4V',
 VALUE='47UF',
 PRIM_FILE='./archive_libs/logical/q_cap/chips/chips.prt';

PART_NAME
 C393 'Q_CAP_C0805-47UF,4V,20%,X6S,CHA':;

SECTION_NUMBER 1
 '@S9S_MB_2U_LIB.S9S_MB_2U(SCH_1):PAGE75_I52@PURE_QUANTA.Q_CAP(CHIPS)':
 C_PATH='@s9s_mb_2u_lib.s9s_mb_2u(sch_1):page75_i52@pure_quanta.q_cap(chips)',
 P_PATH='@s9s_mb_2u_lib.s9s_mb_2u(sch_1):page75_i52@pure_quanta.q_cap(chips)',
 PATH='I52',
 DRAWING='@S9S_MB_2U_LIB.S9S_MB_2U(SCH_1):PAGE75',
 PHYS_PAGE='75',
 XY='(75,1725)',
 ROT='0',
 VER='1',
 PACK_TYPE='C0805',
 CDS_LIB='pure_quanta',
 CDS_PART_NAME='Q_CAP_C0805-47UF,4V,20%,X6S,CHA',
 TOLERANCE='20%',
 MATERIAL='X6S',
 VOLTAGE='4V',
 VALUE='47UF',
 PRIM_FILE='./archive_libs/logical/q_cap/chips/chips.prt';

PART_NAME
 C394 'Q_CAP_C0805-47UF,4V,20%,X6S,CHA':;

SECTION_NUMBER 1
 '@S9S_MB_2U_LIB.S9S_MB_2U(SCH_1):PAGE76_I45@PURE_QUANTA.Q_CAP(CHIPS)':
 C_PATH='@s9s_mb_2u_lib.s9s_mb_2u(sch_1):page76_i45@pure_quanta.q_cap(chips)',
 P_PATH='@s9s_mb_2u_lib.s9s_mb_2u(sch_1):page76_i45@pure_quanta.q_cap(chips)',
 PATH='I45',
 DRAWING='@S9S_MB_2U_LIB.S9S_MB_2U(SCH_1):PAGE76',
 PHYS_PAGE='76',
 XY='(-2125,8825)',
 ROT='0',
 VER='1',
 PACK_TYPE='C0805',
 CDS_LIB='pure_quanta',
 CDS_PART_NAME='Q_CAP_C0805-47UF,4V,20%,X6S,CHA',
 TOLERANCE='20%',
 MATERIAL='X6S',
 VOLTAGE='4V',
 VALUE='47UF',
 PRIM_FILE='./archive_libs/logical/q_cap/chips/chips.prt';

PART_NAME
 C395 'Q_CAP_C0805-47UF,4V,20%,X6S,CHA':;

SECTION_NUMBER 1
 '@S9S_MB_2U_LIB.S9S_MB_2U(SCH_1):PAGE75_I46@PURE_QUANTA.Q_CAP(CHIPS)':
 C_PATH='@s9s_mb_2u_lib.s9s_mb_2u(sch_1):page75_i46@pure_quanta.q_cap(chips)',
 P_PATH='@s9s_mb_2u_lib.s9s_mb_2u(sch_1):page75_i46@pure_quanta.q_cap(chips)',
 PATH='I46',
 DRAWING='@S9S_MB_2U_LIB.S9S_MB_2U(SCH_1):PAGE75',
 PHYS_PAGE='75',
 XY='(325,-175)',
 ROT='0',
 VER='1',
 PACK_TYPE='C0805',
 CDS_LIB='pure_quanta',
 CDS_PART_NAME='Q_CAP_C0805-47UF,4V,20%,X6S,CHA',
 TOLERANCE='20%',
 MATERIAL='X6S',
 VOLTAGE='4V',
 VALUE='47UF',
 PRIM_FILE='./archive_libs/logical/q_cap/chips/chips.prt';

PART_NAME
 C396 'Q_CAP_C0805-47UF,4V,20%,X6S,CHA':;

SECTION_NUMBER 1
 '@S9S_MB_2U_LIB.S9S_MB_2U(SCH_1):PAGE76_I46@PURE_QUANTA.Q_CAP(CHIPS)':
 C_PATH='@s9s_mb_2u_lib.s9s_mb_2u(sch_1):page76_i46@pure_quanta.q_cap(chips)',
 P_PATH='@s9s_mb_2u_lib.s9s_mb_2u(sch_1):page76_i46@pure_quanta.q_cap(chips)',
 PATH='I46',
 DRAWING='@S9S_MB_2U_LIB.S9S_MB_2U(SCH_1):PAGE76',
 PHYS_PAGE='76',
 XY='(-1675,8825)',
 ROT='0',
 VER='1',
 PACK_TYPE='C0805',
 CDS_LIB='pure_quanta',
 CDS_PART_NAME='Q_CAP_C0805-47UF,4V,20%,X6S,CHA',
 TOLERANCE='20%',
 MATERIAL='X6S',
 VOLTAGE='4V',
 VALUE='47UF',
 PRIM_FILE='./archive_libs/logical/q_cap/chips/chips.prt';

PART_NAME
 C397 'Q_CAP_C0805-47UF,4V,20%,X6S,CHA':;

SECTION_NUMBER 1
 '@S9S_MB_2U_LIB.S9S_MB_2U(SCH_1):PAGE75_I37@PURE_QUANTA.Q_CAP(CHIPS)':
 C_PATH='@s9s_mb_2u_lib.s9s_mb_2u(sch_1):page75_i37@pure_quanta.q_cap(chips)',
 P_PATH='@s9s_mb_2u_lib.s9s_mb_2u(sch_1):page75_i37@pure_quanta.q_cap(chips)',
 PATH='I37',
 DRAWING='@S9S_MB_2U_LIB.S9S_MB_2U(SCH_1):PAGE75',
 PHYS_PAGE='75',
 XY='(-1725,1725)',
 ROT='0',
 VER='1',
 PACK_TYPE='C0805',
 CDS_LIB='pure_quanta',
 CDS_PART_NAME='Q_CAP_C0805-47UF,4V,20%,X6S,CHA',
 TOLERANCE='20%',
 MATERIAL='X6S',
 VOLTAGE='4V',
 VALUE='47UF',
 PRIM_FILE='./archive_libs/logical/q_cap/chips/chips.prt';

PART_NAME
 C398 'Q_CAP_C0805-47UF,4V,20%,X6S,CHA':;

SECTION_NUMBER 1
 '@S9S_MB_2U_LIB.S9S_MB_2U(SCH_1):PAGE76_I47@PURE_QUANTA.Q_CAP(CHIPS)':
 C_PATH='@s9s_mb_2u_lib.s9s_mb_2u(sch_1):page76_i47@pure_quanta.q_cap(chips)',
 P_PATH='@s9s_mb_2u_lib.s9s_mb_2u(sch_1):page76_i47@pure_quanta.q_cap(chips)',
 PATH='I47',
 DRAWING='@S9S_MB_2U_LIB.S9S_MB_2U(SCH_1):PAGE76',
 PHYS_PAGE='76',
 XY='(-1225,8825)',
 ROT='0',
 VER='1',
 PACK_TYPE='C0805',
 CDS_LIB='pure_quanta',
 CDS_PART_NAME='Q_CAP_C0805-47UF,4V,20%,X6S,CHA',
 TOLERANCE='20%',
 MATERIAL='X6S',
 VOLTAGE='4V',
 VALUE='47UF',
 PRIM_FILE='./archive_libs/logical/q_cap/chips/chips.prt';

PART_NAME
 C399 'Q_CAP_C0402-22UF,4V,20%,X6S,CHA':;

SECTION_NUMBER 1
 '@S9S_MB_2U_LIB.S9S_MB_2U(SCH_1):PAGE74_I11@PURE_QUANTA.Q_CAP(CHIPS)':
 C_PATH='@s9s_mb_2u_lib.s9s_mb_2u(sch_1):page74_i11@pure_quanta.q_cap(chips)',
 P_PATH='@s9s_mb_2u_lib.s9s_mb_2u(sch_1):page74_i11@pure_quanta.q_cap(chips)',
 PATH='I11',
 DRAWING='@S9S_MB_2U_LIB.S9S_MB_2U(SCH_1):PAGE74',
 PHYS_PAGE='74',
 XY='(-4250,-850)',
 ROT='0',
 VER='1',
 PACK_TYPE='C0402',
 CDS_LIB='pure_quanta',
 CDS_PART_NAME='Q_CAP_C0402-22UF,4V,20%,X6S,CHA',
 TOLERANCE='20%',
 MATERIAL='X6S',
 VOLTAGE='4V',
 VALUE='22UF',
 PRIM_FILE='./archive_libs/logical/q_cap/chips/chips.prt';

PART_NAME
 C400 'Q_CAP_C0402-22UF,4V,20%,X6S,CHA':;

SECTION_NUMBER 1
 '@S9S_MB_2U_LIB.S9S_MB_2U(SCH_1):PAGE74_I1@PURE_QUANTA.Q_CAP(CHIPS)':
 C_PATH='@s9s_mb_2u_lib.s9s_mb_2u(sch_1):page74_i1@pure_quanta.q_cap(chips)',
 P_PATH='@s9s_mb_2u_lib.s9s_mb_2u(sch_1):page74_i1@pure_quanta.q_cap(chips)',
 PATH='I1',
 DRAWING='@S9S_MB_2U_LIB.S9S_MB_2U(SCH_1):PAGE74',
 PHYS_PAGE='74',
 XY='(-4250,-1650)',
 ROT='0',
 VER='1',
 PACK_TYPE='C0402',
 CDS_LIB='pure_quanta',
 CDS_PART_NAME='Q_CAP_C0402-22UF,4V,20%,X6S,CHA',
 TOLERANCE='20%',
 MATERIAL='X6S',
 VOLTAGE='4V',
 VALUE='22UF',
 PRIM_FILE='./archive_libs/logical/q_cap/chips/chips.prt';

PART_NAME
 C401 'Q_CAP_C0402-22UF,4V,20%,X6S,CHA':;

SECTION_NUMBER 1
 '@S9S_MB_2U_LIB.S9S_MB_2U(SCH_1):PAGE74_I17@PURE_QUANTA.Q_CAP(CHIPS)':
 C_PATH='@s9s_mb_2u_lib.s9s_mb_2u(sch_1):page74_i17@pure_quanta.q_cap(chips)',
 P_PATH='@s9s_mb_2u_lib.s9s_mb_2u(sch_1):page74_i17@pure_quanta.q_cap(chips)',
 PATH='I17',
 DRAWING='@S9S_MB_2U_LIB.S9S_MB_2U(SCH_1):PAGE74',
 PHYS_PAGE='74',
 XY='(-3800,-850)',
 ROT='0',
 VER='1',
 PACK_TYPE='C0402',
 CDS_LIB='pure_quanta',
 CDS_PART_NAME='Q_CAP_C0402-22UF,4V,20%,X6S,CHA',
 TOLERANCE='20%',
 MATERIAL='X6S',
 VOLTAGE='4V',
 VALUE='22UF',
 PRIM_FILE='./archive_libs/logical/q_cap/chips/chips.prt';

PART_NAME
 C402 'Q_CAP_C0402-22UF,4V,20%,X6S,CHA':;

SECTION_NUMBER 1
 '@S9S_MB_2U_LIB.S9S_MB_2U(SCH_1):PAGE74_I3@PURE_QUANTA.Q_CAP(CHIPS)':
 C_PATH='@s9s_mb_2u_lib.s9s_mb_2u(sch_1):page74_i3@pure_quanta.q_cap(chips)',
 P_PATH='@s9s_mb_2u_lib.s9s_mb_2u(sch_1):page74_i3@pure_quanta.q_cap(chips)',
 PATH='I3',
 DRAWING='@S9S_MB_2U_LIB.S9S_MB_2U(SCH_1):PAGE74',
 PHYS_PAGE='74',
 XY='(-3800,-1650)',
 ROT='0',
 VER='1',
 PACK_TYPE='C0402',
 CDS_LIB='pure_quanta',
 CDS_PART_NAME='Q_CAP_C0402-22UF,4V,20%,X6S,CHA',
 TOLERANCE='20%',
 MATERIAL='X6S',
 VOLTAGE='4V',
 VALUE='22UF',
 PRIM_FILE='./archive_libs/logical/q_cap/chips/chips.prt';

PART_NAME
 C403 'Q_CAP_C0402-22UF,4V,20%,X6S,CHA':;

SECTION_NUMBER 1
 '@S9S_MB_2U_LIB.S9S_MB_2U(SCH_1):PAGE74_I19@PURE_QUANTA.Q_CAP(CHIPS)':
 C_PATH='@s9s_mb_2u_lib.s9s_mb_2u(sch_1):page74_i19@pure_quanta.q_cap(chips)',
 P_PATH='@s9s_mb_2u_lib.s9s_mb_2u(sch_1):page74_i19@pure_quanta.q_cap(chips)',
 PATH='I19',
 DRAWING='@S9S_MB_2U_LIB.S9S_MB_2U(SCH_1):PAGE74',
 PHYS_PAGE='74',
 XY='(-3350,-850)',
 ROT='0',
 VER='1',
 PACK_TYPE='C0402',
 CDS_LIB='pure_quanta',
 CDS_PART_NAME='Q_CAP_C0402-22UF,4V,20%,X6S,CHA',
 TOLERANCE='20%',
 MATERIAL='X6S',
 VOLTAGE='4V',
 VALUE='22UF',
 PRIM_FILE='./archive_libs/logical/q_cap/chips/chips.prt';

PART_NAME
 C404 'Q_CAP_C0402-22UF,4V,20%,X6S,CHA':;

SECTION_NUMBER 1
 '@S9S_MB_2U_LIB.S9S_MB_2U(SCH_1):PAGE74_I4@PURE_QUANTA.Q_CAP(CHIPS)':
 C_PATH='@s9s_mb_2u_lib.s9s_mb_2u(sch_1):page74_i4@pure_quanta.q_cap(chips)',
 P_PATH='@s9s_mb_2u_lib.s9s_mb_2u(sch_1):page74_i4@pure_quanta.q_cap(chips)',
 PATH='I4',
 DRAWING='@S9S_MB_2U_LIB.S9S_MB_2U(SCH_1):PAGE74',
 PHYS_PAGE='74',
 XY='(-3350,-1650)',
 ROT='0',
 VER='1',
 PACK_TYPE='C0402',
 CDS_LIB='pure_quanta',
 CDS_PART_NAME='Q_CAP_C0402-22UF,4V,20%,X6S,CHA',
 TOLERANCE='20%',
 MATERIAL='X6S',
 VOLTAGE='4V',
 VALUE='22UF',
 PRIM_FILE='./archive_libs/logical/q_cap/chips/chips.prt';

PART_NAME
 C405 'Q_CAP_C0402-22UF,4V,20%,X6S,CHA':;

SECTION_NUMBER 1
 '@S9S_MB_2U_LIB.S9S_MB_2U(SCH_1):PAGE74_I34@PURE_QUANTA.Q_CAP(CHIPS)':
 C_PATH='@s9s_mb_2u_lib.s9s_mb_2u(sch_1):page74_i34@pure_quanta.q_cap(chips)',
 P_PATH='@s9s_mb_2u_lib.s9s_mb_2u(sch_1):page74_i34@pure_quanta.q_cap(chips)',
 PATH='I34',
 DRAWING='@S9S_MB_2U_LIB.S9S_MB_2U(SCH_1):PAGE74',
 PHYS_PAGE='74',
 XY='(-2900,-850)',
 ROT='0',
 VER='1',
 PACK_TYPE='C0402',
 CDS_LIB='pure_quanta',
 CDS_PART_NAME='Q_CAP_C0402-22UF,4V,20%,X6S,CHA',
 TOLERANCE='20%',
 MATERIAL='X6S',
 VOLTAGE='4V',
 VALUE='22UF',
 PRIM_FILE='./archive_libs/logical/q_cap/chips/chips.prt';

PART_NAME
 C406 'Q_CAP_C0402-22UF,4V,20%,X6S,CHA':;

SECTION_NUMBER 1
 '@S9S_MB_2U_LIB.S9S_MB_2U(SCH_1):PAGE74_I5@PURE_QUANTA.Q_CAP(CHIPS)':
 C_PATH='@s9s_mb_2u_lib.s9s_mb_2u(sch_1):page74_i5@pure_quanta.q_cap(chips)',
 P_PATH='@s9s_mb_2u_lib.s9s_mb_2u(sch_1):page74_i5@pure_quanta.q_cap(chips)',
 PATH='I5',
 DRAWING='@S9S_MB_2U_LIB.S9S_MB_2U(SCH_1):PAGE74',
 PHYS_PAGE='74',
 XY='(-2900,-1650)',
 ROT='0',
 VER='1',
 PACK_TYPE='C0402',
 CDS_LIB='pure_quanta',
 CDS_PART_NAME='Q_CAP_C0402-22UF,4V,20%,X6S,CHA',
 TOLERANCE='20%',
 MATERIAL='X6S',
 VOLTAGE='4V',
 VALUE='22UF',
 PRIM_FILE='./archive_libs/logical/q_cap/chips/chips.prt';

PART_NAME
 C407 'Q_CAP_C0402-22UF,4V,20%,X6S,CHA':;

SECTION_NUMBER 1
 '@S9S_MB_2U_LIB.S9S_MB_2U(SCH_1):PAGE74_I7@PURE_QUANTA.Q_CAP(CHIPS)':
 C_PATH='@s9s_mb_2u_lib.s9s_mb_2u(sch_1):page74_i7@pure_quanta.q_cap(chips)',
 P_PATH='@s9s_mb_2u_lib.s9s_mb_2u(sch_1):page74_i7@pure_quanta.q_cap(chips)',
 PATH='I7',
 DRAWING='@S9S_MB_2U_LIB.S9S_MB_2U(SCH_1):PAGE74',
 PHYS_PAGE='74',
 XY='(-2450,-1650)',
 ROT='0',
 VER='1',
 PACK_TYPE='C0402',
 CDS_LIB='pure_quanta',
 CDS_PART_NAME='Q_CAP_C0402-22UF,4V,20%,X6S,CHA',
 TOLERANCE='20%',
 MATERIAL='X6S',
 VOLTAGE='4V',
 VALUE='22UF',
 PRIM_FILE='./archive_libs/logical/q_cap/chips/chips.prt';

PART_NAME
 C408 'Q_CAP_C0402-22UF,4V,20%,X6S,CHA':;

SECTION_NUMBER 1
 '@S9S_MB_2U_LIB.S9S_MB_2U(SCH_1):PAGE74_I142@PURE_QUANTA.Q_CAP(CHIPS)':
 C_PATH='@s9s_mb_2u_lib.s9s_mb_2u(sch_1):page74_i142@pure_quanta.q_cap(chips)',
 P_PATH='@s9s_mb_2u_lib.s9s_mb_2u(sch_1):page74_i142@pure_quanta.q_cap(chips)',
 PATH='I142',
 DRAWING='@S9S_MB_2U_LIB.S9S_MB_2U(SCH_1):PAGE74',
 PHYS_PAGE='74',
 XY='(-2000,-850)',
 ROT='0',
 VER='1',
 PACK_TYPE='C0402',
 CDS_LIB='pure_quanta',
 CDS_PART_NAME='Q_CAP_C0402-22UF,4V,20%,X6S,CHA',
 TOLERANCE='20%',
 MATERIAL='X6S',
 VOLTAGE='4V',
 VALUE='22UF',
 PRIM_FILE='./archive_libs/logical/q_cap/chips/chips.prt';

PART_NAME
 C409 'Q_CAP_C0402-22UF,4V,20%,X6S,CHA':;

SECTION_NUMBER 1
 '@S9S_MB_2U_LIB.S9S_MB_2U(SCH_1):PAGE74_I8@PURE_QUANTA.Q_CAP(CHIPS)':
 C_PATH='@s9s_mb_2u_lib.s9s_mb_2u(sch_1):page74_i8@pure_quanta.q_cap(chips)',
 P_PATH='@s9s_mb_2u_lib.s9s_mb_2u(sch_1):page74_i8@pure_quanta.q_cap(chips)',
 PATH='I8',
 DRAWING='@S9S_MB_2U_LIB.S9S_MB_2U(SCH_1):PAGE74',
 PHYS_PAGE='74',
 XY='(-2000,-1650)',
 ROT='0',
 VER='1',
 PACK_TYPE='C0402',
 CDS_LIB='pure_quanta',
 CDS_PART_NAME='Q_CAP_C0402-22UF,4V,20%,X6S,CHA',
 TOLERANCE='20%',
 MATERIAL='X6S',
 VOLTAGE='4V',
 VALUE='22UF',
 PRIM_FILE='./archive_libs/logical/q_cap/chips/chips.prt';

PART_NAME
 C410 'Q_CAP_C0402-22UF,4V,20%,X6S,CHA':;

SECTION_NUMBER 1
 '@S9S_MB_2U_LIB.S9S_MB_2U(SCH_1):PAGE74_I41@PURE_QUANTA.Q_CAP(CHIPS)':
 C_PATH='@s9s_mb_2u_lib.s9s_mb_2u(sch_1):page74_i41@pure_quanta.q_cap(chips)',
 P_PATH='@s9s_mb_2u_lib.s9s_mb_2u(sch_1):page74_i41@pure_quanta.q_cap(chips)',
 PATH='I41',
 DRAWING='@S9S_MB_2U_LIB.S9S_MB_2U(SCH_1):PAGE74',
 PHYS_PAGE='74',
 XY='(-1550,-850)',
 ROT='0',
 VER='1',
 PACK_TYPE='C0402',
 CDS_LIB='pure_quanta',
 CDS_PART_NAME='Q_CAP_C0402-22UF,4V,20%,X6S,CHA',
 TOLERANCE='20%',
 MATERIAL='X6S',
 VOLTAGE='4V',
 VALUE='22UF',
 PRIM_FILE='./archive_libs/logical/q_cap/chips/chips.prt';

PART_NAME
 C411 'Q_CAP_C0402-22UF,4V,20%,X6S,CHA':;

SECTION_NUMBER 1
 '@S9S_MB_2U_LIB.S9S_MB_2U(SCH_1):PAGE74_I9@PURE_QUANTA.Q_CAP(CHIPS)':
 C_PATH='@s9s_mb_2u_lib.s9s_mb_2u(sch_1):page74_i9@pure_quanta.q_cap(chips)',
 P_PATH='@s9s_mb_2u_lib.s9s_mb_2u(sch_1):page74_i9@pure_quanta.q_cap(chips)',
 PATH='I9',
 DRAWING='@S9S_MB_2U_LIB.S9S_MB_2U(SCH_1):PAGE74',
 PHYS_PAGE='74',
 XY='(-1550,-1650)',
 ROT='0',
 VER='1',
 PACK_TYPE='C0402',
 CDS_LIB='pure_quanta',
 CDS_PART_NAME='Q_CAP_C0402-22UF,4V,20%,X6S,CHA',
 TOLERANCE='20%',
 MATERIAL='X6S',
 VOLTAGE='4V',
 VALUE='22UF',
 PRIM_FILE='./archive_libs/logical/q_cap/chips/chips.prt';

PART_NAME
 C412 'Q_CAP_C0402-22UF,4V,20%,X6S,CHA':;

SECTION_NUMBER 1
 '@S9S_MB_2U_LIB.S9S_MB_2U(SCH_1):PAGE74_I42@PURE_QUANTA.Q_CAP(CHIPS)':
 C_PATH='@s9s_mb_2u_lib.s9s_mb_2u(sch_1):page74_i42@pure_quanta.q_cap(chips)',
 P_PATH='@s9s_mb_2u_lib.s9s_mb_2u(sch_1):page74_i42@pure_quanta.q_cap(chips)',
 PATH='I42',
 DRAWING='@S9S_MB_2U_LIB.S9S_MB_2U(SCH_1):PAGE74',
 PHYS_PAGE='74',
 XY='(-1100,-850)',
 ROT='0',
 VER='1',
 PACK_TYPE='C0402',
 CDS_LIB='pure_quanta',
 CDS_PART_NAME='Q_CAP_C0402-22UF,4V,20%,X6S,CHA',
 TOLERANCE='20%',
 MATERIAL='X6S',
 VOLTAGE='4V',
 VALUE='22UF',
 PRIM_FILE='./archive_libs/logical/q_cap/chips/chips.prt';

PART_NAME
 C413 'Q_CAP_C0402-22UF,4V,20%,X6S,CHA':;

SECTION_NUMBER 1
 '@S9S_MB_2U_LIB.S9S_MB_2U(SCH_1):PAGE74_I10@PURE_QUANTA.Q_CAP(CHIPS)':
 C_PATH='@s9s_mb_2u_lib.s9s_mb_2u(sch_1):page74_i10@pure_quanta.q_cap(chips)',
 P_PATH='@s9s_mb_2u_lib.s9s_mb_2u(sch_1):page74_i10@pure_quanta.q_cap(chips)',
 PATH='I10',
 DRAWING='@S9S_MB_2U_LIB.S9S_MB_2U(SCH_1):PAGE74',
 PHYS_PAGE='74',
 XY='(-1100,-1650)',
 ROT='0',
 VER='1',
 PACK_TYPE='C0402',
 CDS_LIB='pure_quanta',
 CDS_PART_NAME='Q_CAP_C0402-22UF,4V,20%,X6S,CHA',
 TOLERANCE='20%',
 MATERIAL='X6S',
 VOLTAGE='4V',
 VALUE='22UF',
 PRIM_FILE='./archive_libs/logical/q_cap/chips/chips.prt';

PART_NAME
 C414 'Q_CAP_C0402-22UF,4V,20%,X6S,CHA':;

SECTION_NUMBER 1
 '@S9S_MB_2U_LIB.S9S_MB_2U(SCH_1):PAGE74_I70@PURE_QUANTA.Q_CAP(CHIPS)':
 C_PATH='@s9s_mb_2u_lib.s9s_mb_2u(sch_1):page74_i70@pure_quanta.q_cap(chips)',
 P_PATH='@s9s_mb_2u_lib.s9s_mb_2u(sch_1):page74_i70@pure_quanta.q_cap(chips)',
 PATH='I70',
 DRAWING='@S9S_MB_2U_LIB.S9S_MB_2U(SCH_1):PAGE74',
 PHYS_PAGE='74',
 XY='(-650,-850)',
 ROT='0',
 VER='1',
 PACK_TYPE='C0402',
 CDS_LIB='pure_quanta',
 CDS_PART_NAME='Q_CAP_C0402-22UF,4V,20%,X6S,CHA',
 TOLERANCE='20%',
 MATERIAL='X6S',
 VOLTAGE='4V',
 VALUE='22UF',
 PRIM_FILE='./archive_libs/logical/q_cap/chips/chips.prt';

PART_NAME
 C415 'Q_CAP_C0402-22UF,4V,20%,X6S,CHA':;

SECTION_NUMBER 1
 '@S9S_MB_2U_LIB.S9S_MB_2U(SCH_1):PAGE74_I64@PURE_QUANTA.Q_CAP(CHIPS)':
 C_PATH='@s9s_mb_2u_lib.s9s_mb_2u(sch_1):page74_i64@pure_quanta.q_cap(chips)',
 P_PATH='@s9s_mb_2u_lib.s9s_mb_2u(sch_1):page74_i64@pure_quanta.q_cap(chips)',
 PATH='I64',
 DRAWING='@S9S_MB_2U_LIB.S9S_MB_2U(SCH_1):PAGE74',
 PHYS_PAGE='74',
 XY='(-650,-1650)',
 ROT='0',
 VER='1',
 PACK_TYPE='C0402',
 CDS_LIB='pure_quanta',
 CDS_PART_NAME='Q_CAP_C0402-22UF,4V,20%,X6S,CHA',
 TOLERANCE='20%',
 MATERIAL='X6S',
 VOLTAGE='4V',
 VALUE='22UF',
 PRIM_FILE='./archive_libs/logical/q_cap/chips/chips.prt';

PART_NAME
 C416 'Q_CAP_C0402-22UF,4V,20%,X6S,CHA':;

SECTION_NUMBER 1
 '@S9S_MB_2U_LIB.S9S_MB_2U(SCH_1):PAGE74_I72@PURE_QUANTA.Q_CAP(CHIPS)':
 C_PATH='@s9s_mb_2u_lib.s9s_mb_2u(sch_1):page74_i72@pure_quanta.q_cap(chips)',
 P_PATH='@s9s_mb_2u_lib.s9s_mb_2u(sch_1):page74_i72@pure_quanta.q_cap(chips)',
 PATH='I72',
 DRAWING='@S9S_MB_2U_LIB.S9S_MB_2U(SCH_1):PAGE74',
 PHYS_PAGE='74',
 XY='(-200,-850)',
 ROT='0',
 VER='1',
 PACK_TYPE='C0402',
 CDS_LIB='pure_quanta',
 CDS_PART_NAME='Q_CAP_C0402-22UF,4V,20%,X6S,CHA',
 TOLERANCE='20%',
 MATERIAL='X6S',
 VOLTAGE='4V',
 VALUE='22UF',
 PRIM_FILE='./archive_libs/logical/q_cap/chips/chips.prt';

PART_NAME
 C417 'Q_CAP_C0402-22UF,4V,20%,X6S,CHA':;

SECTION_NUMBER 1
 '@S9S_MB_2U_LIB.S9S_MB_2U(SCH_1):PAGE74_I65@PURE_QUANTA.Q_CAP(CHIPS)':
 C_PATH='@s9s_mb_2u_lib.s9s_mb_2u(sch_1):page74_i65@pure_quanta.q_cap(chips)',
 P_PATH='@s9s_mb_2u_lib.s9s_mb_2u(sch_1):page74_i65@pure_quanta.q_cap(chips)',
 PATH='I65',
 DRAWING='@S9S_MB_2U_LIB.S9S_MB_2U(SCH_1):PAGE74',
 PHYS_PAGE='74',
 XY='(-200,-1650)',
 ROT='0',
 VER='1',
 PACK_TYPE='C0402',
 CDS_LIB='pure_quanta',
 CDS_PART_NAME='Q_CAP_C0402-22UF,4V,20%,X6S,CHA',
 TOLERANCE='20%',
 MATERIAL='X6S',
 VOLTAGE='4V',
 VALUE='22UF',
 PRIM_FILE='./archive_libs/logical/q_cap/chips/chips.prt';

PART_NAME
 C418 'Q_CAP_C0402-22UF,4V,20%,X6S,CHA':;

SECTION_NUMBER 1
 '@S9S_MB_2U_LIB.S9S_MB_2U(SCH_1):PAGE74_I68@PURE_QUANTA.Q_CAP(CHIPS)':
 C_PATH='@s9s_mb_2u_lib.s9s_mb_2u(sch_1):page74_i68@pure_quanta.q_cap(chips)',
 P_PATH='@s9s_mb_2u_lib.s9s_mb_2u(sch_1):page74_i68@pure_quanta.q_cap(chips)',
 PATH='I68',
 DRAWING='@S9S_MB_2U_LIB.S9S_MB_2U(SCH_1):PAGE74',
 PHYS_PAGE='74',
 XY='(250,-1650)',
 ROT='0',
 VER='1',
 PACK_TYPE='C0402',
 CDS_LIB='pure_quanta',
 CDS_PART_NAME='Q_CAP_C0402-22UF,4V,20%,X6S,CHA',
 TOLERANCE='20%',
 MATERIAL='X6S',
 VOLTAGE='4V',
 VALUE='22UF',
 PRIM_FILE='./archive_libs/logical/q_cap/chips/chips.prt';

PART_NAME
 C419 'Q_CAP_C0402-22UF,4V,20%,X6S,CHA':;

SECTION_NUMBER 1
 '@S9S_MB_2U_LIB.S9S_MB_2U(SCH_1):PAGE74_I98@PURE_QUANTA.Q_CAP(CHIPS)':
 C_PATH='@s9s_mb_2u_lib.s9s_mb_2u(sch_1):page74_i98@pure_quanta.q_cap(chips)',
 P_PATH='@s9s_mb_2u_lib.s9s_mb_2u(sch_1):page74_i98@pure_quanta.q_cap(chips)',
 PATH='I98',
 DRAWING='@S9S_MB_2U_LIB.S9S_MB_2U(SCH_1):PAGE74',
 PHYS_PAGE='74',
 XY='(1025,-850)',
 ROT='0',
 VER='1',
 PACK_TYPE='C0402',
 CDS_LIB='pure_quanta',
 CDS_PART_NAME='Q_CAP_C0402-22UF,4V,20%,X6S,CHA',
 TOLERANCE='20%',
 MATERIAL='X6S',
 VOLTAGE='4V',
 VALUE='22UF',
 PRIM_FILE='./archive_libs/logical/q_cap/chips/chips.prt';

PART_NAME
 C420 'Q_CAP_C0402-22UF,4V,20%,X6S,CHA':;

SECTION_NUMBER 1
 '@S9S_MB_2U_LIB.S9S_MB_2U(SCH_1):PAGE74_I100@PURE_QUANTA.Q_CAP(CHIPS)':
 C_PATH='@s9s_mb_2u_lib.s9s_mb_2u(sch_1):page74_i100@pure_quanta.q_cap(chips)',
 P_PATH='@s9s_mb_2u_lib.s9s_mb_2u(sch_1):page74_i100@pure_quanta.q_cap(chips)',
 PATH='I100',
 DRAWING='@S9S_MB_2U_LIB.S9S_MB_2U(SCH_1):PAGE74',
 PHYS_PAGE='74',
 XY='(1475,-850)',
 ROT='0',
 VER='1',
 PACK_TYPE='C0402',
 CDS_LIB='pure_quanta',
 CDS_PART_NAME='Q_CAP_C0402-22UF,4V,20%,X6S,CHA',
 TOLERANCE='20%',
 MATERIAL='X6S',
 VOLTAGE='4V',
 VALUE='22UF',
 PRIM_FILE='./archive_libs/logical/q_cap/chips/chips.prt';

PART_NAME
 C421 'Q_CAP_C0402-22UF,4V,20%,X6S,CHA':;

SECTION_NUMBER 1
 '@S9S_MB_2U_LIB.S9S_MB_2U(SCH_1):PAGE74_I103@PURE_QUANTA.Q_CAP(CHIPS)':
 C_PATH='@s9s_mb_2u_lib.s9s_mb_2u(sch_1):page74_i103@pure_quanta.q_cap(chips)',
 P_PATH='@s9s_mb_2u_lib.s9s_mb_2u(sch_1):page74_i103@pure_quanta.q_cap(chips)',
 PATH='I103',
 DRAWING='@S9S_MB_2U_LIB.S9S_MB_2U(SCH_1):PAGE74',
 PHYS_PAGE='74',
 XY='(1925,-850)',
 ROT='0',
 VER='1',
 PACK_TYPE='C0402',
 CDS_LIB='pure_quanta',
 CDS_PART_NAME='Q_CAP_C0402-22UF,4V,20%,X6S,CHA',
 TOLERANCE='20%',
 MATERIAL='X6S',
 VOLTAGE='4V',
 VALUE='22UF',
 PRIM_FILE='./archive_libs/logical/q_cap/chips/chips.prt';

PART_NAME
 C422 'Q_CAP_C0402-22UF,4V,20%,X6S,CHA':;

SECTION_NUMBER 1
 '@S9S_MB_2U_LIB.S9S_MB_2U(SCH_1):PAGE74_I107@PURE_QUANTA.Q_CAP(CHIPS)':
 C_PATH='@s9s_mb_2u_lib.s9s_mb_2u(sch_1):page74_i107@pure_quanta.q_cap(chips)',
 P_PATH='@s9s_mb_2u_lib.s9s_mb_2u(sch_1):page74_i107@pure_quanta.q_cap(chips)',
 PATH='I107',
 DRAWING='@S9S_MB_2U_LIB.S9S_MB_2U(SCH_1):PAGE74',
 PHYS_PAGE='74',
 XY='(2375,-850)',
 ROT='0',
 VER='1',
 PACK_TYPE='C0402',
 CDS_LIB='pure_quanta',
 CDS_PART_NAME='Q_CAP_C0402-22UF,4V,20%,X6S,CHA',
 TOLERANCE='20%',
 MATERIAL='X6S',
 VOLTAGE='4V',
 VALUE='22UF',
 PRIM_FILE='./archive_libs/logical/q_cap/chips/chips.prt';

PART_NAME
 C423 'Q_CAP_C0402-22UF,4V,20%,X6S,CHA':;

SECTION_NUMBER 1
 '@S9S_MB_2U_LIB.S9S_MB_2U(SCH_1):PAGE77_I7@PURE_QUANTA.Q_CAP(CHIPS)':
 C_PATH='@s9s_mb_2u_lib.s9s_mb_2u(sch_1):page77_i7@pure_quanta.q_cap(chips)',
 P_PATH='@s9s_mb_2u_lib.s9s_mb_2u(sch_1):page77_i7@pure_quanta.q_cap(chips)',
 PATH='I7',
 DRAWING='@S9S_MB_2U_LIB.S9S_MB_2U(SCH_1):PAGE77',
 PHYS_PAGE='77',
 XY='(-7250,3050)',
 ROT='0',
 VER='1',
 PACK_TYPE='C0402',
 CDS_LIB='pure_quanta',
 CDS_PART_NAME='Q_CAP_C0402-22UF,4V,20%,X6S,CHA',
 TOLERANCE='20%',
 MATERIAL='X6S',
 VOLTAGE='4V',
 VALUE='22UF',
 PRIM_FILE='./archive_libs/logical/q_cap/chips/chips.prt';

PART_NAME
 C424 'Q_CAP_C0402-22UF,4V,20%,X6S,CHA':;

SECTION_NUMBER 1
 '@S9S_MB_2U_LIB.S9S_MB_2U(SCH_1):PAGE77_I1@PURE_QUANTA.Q_CAP(CHIPS)':
 C_PATH='@s9s_mb_2u_lib.s9s_mb_2u(sch_1):page77_i1@pure_quanta.q_cap(chips)',
 P_PATH='@s9s_mb_2u_lib.s9s_mb_2u(sch_1):page77_i1@pure_quanta.q_cap(chips)',
 PATH='I1',
 DRAWING='@S9S_MB_2U_LIB.S9S_MB_2U(SCH_1):PAGE77',
 PHYS_PAGE='77',
 XY='(-7250,2225)',
 ROT='0',
 VER='1',
 PACK_TYPE='C0402',
 CDS_LIB='pure_quanta',
 CDS_PART_NAME='Q_CAP_C0402-22UF,4V,20%,X6S,CHA',
 TOLERANCE='20%',
 MATERIAL='X6S',
 VOLTAGE='4V',
 VALUE='22UF',
 PRIM_FILE='./archive_libs/logical/q_cap/chips/chips.prt';

PART_NAME
 C425 'Q_CAP_C0402-22UF,4V,20%,X6S,CHA':;

SECTION_NUMBER 1
 '@S9S_MB_2U_LIB.S9S_MB_2U(SCH_1):PAGE77_I8@PURE_QUANTA.Q_CAP(CHIPS)':
 C_PATH='@s9s_mb_2u_lib.s9s_mb_2u(sch_1):page77_i8@pure_quanta.q_cap(chips)',
 P_PATH='@s9s_mb_2u_lib.s9s_mb_2u(sch_1):page77_i8@pure_quanta.q_cap(chips)',
 PATH='I8',
 DRAWING='@S9S_MB_2U_LIB.S9S_MB_2U(SCH_1):PAGE77',
 PHYS_PAGE='77',
 XY='(-6800,3050)',
 ROT='0',
 VER='1',
 PACK_TYPE='C0402',
 CDS_LIB='pure_quanta',
 CDS_PART_NAME='Q_CAP_C0402-22UF,4V,20%,X6S,CHA',
 TOLERANCE='20%',
 MATERIAL='X6S',
 VOLTAGE='4V',
 VALUE='22UF',
 PRIM_FILE='./archive_libs/logical/q_cap/chips/chips.prt';

PART_NAME
 C426 'Q_CAP_C0402-22UF,4V,20%,X6S,CHA':;

SECTION_NUMBER 1
 '@S9S_MB_2U_LIB.S9S_MB_2U(SCH_1):PAGE77_I2@PURE_QUANTA.Q_CAP(CHIPS)':
 C_PATH='@s9s_mb_2u_lib.s9s_mb_2u(sch_1):page77_i2@pure_quanta.q_cap(chips)',
 P_PATH='@s9s_mb_2u_lib.s9s_mb_2u(sch_1):page77_i2@pure_quanta.q_cap(chips)',
 PATH='I2',
 DRAWING='@S9S_MB_2U_LIB.S9S_MB_2U(SCH_1):PAGE77',
 PHYS_PAGE='77',
 XY='(-6800,2225)',
 ROT='0',
 VER='1',
 PACK_TYPE='C0402',
 CDS_LIB='pure_quanta',
 CDS_PART_NAME='Q_CAP_C0402-22UF,4V,20%,X6S,CHA',
 TOLERANCE='20%',
 MATERIAL='X6S',
 VOLTAGE='4V',
 VALUE='22UF',
 PRIM_FILE='./archive_libs/logical/q_cap/chips/chips.prt';

PART_NAME
 C427 'Q_CAP_C0402-22UF,4V,20%,X6S,CHA':;

SECTION_NUMBER 1
 '@S9S_MB_2U_LIB.S9S_MB_2U(SCH_1):PAGE77_I15@PURE_QUANTA.Q_CAP(CHIPS)':
 C_PATH='@s9s_mb_2u_lib.s9s_mb_2u(sch_1):page77_i15@pure_quanta.q_cap(chips)',
 P_PATH='@s9s_mb_2u_lib.s9s_mb_2u(sch_1):page77_i15@pure_quanta.q_cap(chips)',
 PATH='I15',
 DRAWING='@S9S_MB_2U_LIB.S9S_MB_2U(SCH_1):PAGE77',
 PHYS_PAGE='77',
 XY='(-6350,3050)',
 ROT='0',
 VER='1',
 PACK_TYPE='C0402',
 CDS_LIB='pure_quanta',
 CDS_PART_NAME='Q_CAP_C0402-22UF,4V,20%,X6S,CHA',
 TOLERANCE='20%',
 MATERIAL='X6S',
 VOLTAGE='4V',
 VALUE='22UF',
 PRIM_FILE='./archive_libs/logical/q_cap/chips/chips.prt';

PART_NAME
 C428 'Q_CAP_C0402-22UF,4V,20%,X6S,CHA':;

SECTION_NUMBER 1
 '@S9S_MB_2U_LIB.S9S_MB_2U(SCH_1):PAGE77_I4@PURE_QUANTA.Q_CAP(CHIPS)':
 C_PATH='@s9s_mb_2u_lib.s9s_mb_2u(sch_1):page77_i4@pure_quanta.q_cap(chips)',
 P_PATH='@s9s_mb_2u_lib.s9s_mb_2u(sch_1):page77_i4@pure_quanta.q_cap(chips)',
 PATH='I4',
 DRAWING='@S9S_MB_2U_LIB.S9S_MB_2U(SCH_1):PAGE77',
 PHYS_PAGE='77',
 XY='(-6350,2225)',
 ROT='0',
 VER='1',
 PACK_TYPE='C0402',
 CDS_LIB='pure_quanta',
 CDS_PART_NAME='Q_CAP_C0402-22UF,4V,20%,X6S,CHA',
 TOLERANCE='20%',
 MATERIAL='X6S',
 VOLTAGE='4V',
 VALUE='22UF',
 PRIM_FILE='./archive_libs/logical/q_cap/chips/chips.prt';

PART_NAME
 C429 'Q_CAP_C0402-22UF,4V,20%,X6S,CHA':;

SECTION_NUMBER 1
 '@S9S_MB_2U_LIB.S9S_MB_2U(SCH_1):PAGE77_I17@PURE_QUANTA.Q_CAP(CHIPS)':
 C_PATH='@s9s_mb_2u_lib.s9s_mb_2u(sch_1):page77_i17@pure_quanta.q_cap(chips)',
 P_PATH='@s9s_mb_2u_lib.s9s_mb_2u(sch_1):page77_i17@pure_quanta.q_cap(chips)',
 PATH='I17',
 DRAWING='@S9S_MB_2U_LIB.S9S_MB_2U(SCH_1):PAGE77',
 PHYS_PAGE='77',
 XY='(-5900,3050)',
 ROT='0',
 VER='1',
 PACK_TYPE='C0402',
 CDS_LIB='pure_quanta',
 CDS_PART_NAME='Q_CAP_C0402-22UF,4V,20%,X6S,CHA',
 TOLERANCE='20%',
 MATERIAL='X6S',
 VOLTAGE='4V',
 VALUE='22UF',
 PRIM_FILE='./archive_libs/logical/q_cap/chips/chips.prt';

PART_NAME
 C430 'Q_CAP_C0402-22UF,4V,20%,X6S,CHA':;

SECTION_NUMBER 1
 '@S9S_MB_2U_LIB.S9S_MB_2U(SCH_1):PAGE77_I5@PURE_QUANTA.Q_CAP(CHIPS)':
 C_PATH='@s9s_mb_2u_lib.s9s_mb_2u(sch_1):page77_i5@pure_quanta.q_cap(chips)',
 P_PATH='@s9s_mb_2u_lib.s9s_mb_2u(sch_1):page77_i5@pure_quanta.q_cap(chips)',
 PATH='I5',
 DRAWING='@S9S_MB_2U_LIB.S9S_MB_2U(SCH_1):PAGE77',
 PHYS_PAGE='77',
 XY='(-5900,2225)',
 ROT='0',
 VER='1',
 PACK_TYPE='C0402',
 CDS_LIB='pure_quanta',
 CDS_PART_NAME='Q_CAP_C0402-22UF,4V,20%,X6S,CHA',
 TOLERANCE='20%',
 MATERIAL='X6S',
 VOLTAGE='4V',
 VALUE='22UF',
 PRIM_FILE='./archive_libs/logical/q_cap/chips/chips.prt';

PART_NAME
 C431 'Q_CAP_C0402-22UF,4V,20%,X6S,CHA':;

SECTION_NUMBER 1
 '@S9S_MB_2U_LIB.S9S_MB_2U(SCH_1):PAGE77_I37@PURE_QUANTA.Q_CAP(CHIPS)':
 C_PATH='@s9s_mb_2u_lib.s9s_mb_2u(sch_1):page77_i37@pure_quanta.q_cap(chips)',
 P_PATH='@s9s_mb_2u_lib.s9s_mb_2u(sch_1):page77_i37@pure_quanta.q_cap(chips)',
 PATH='I37',
 DRAWING='@S9S_MB_2U_LIB.S9S_MB_2U(SCH_1):PAGE77',
 PHYS_PAGE='77',
 XY='(-5450,2225)',
 ROT='0',
 VER='1',
 PACK_TYPE='C0402',
 CDS_LIB='pure_quanta',
 CDS_PART_NAME='Q_CAP_C0402-22UF,4V,20%,X6S,CHA',
 TOLERANCE='20%',
 MATERIAL='X6S',
 VOLTAGE='4V',
 VALUE='22UF',
 PRIM_FILE='./archive_libs/logical/q_cap/chips/chips.prt';

PART_NAME
 C432 'Q_CAP_C0402-22UF,4V,20%,X6S,CHA':;

SECTION_NUMBER 1
 '@S9S_MB_2U_LIB.S9S_MB_2U(SCH_1):PAGE77_I42@PURE_QUANTA.Q_CAP(CHIPS)':
 C_PATH='@s9s_mb_2u_lib.s9s_mb_2u(sch_1):page77_i42@pure_quanta.q_cap(chips)',
 P_PATH='@s9s_mb_2u_lib.s9s_mb_2u(sch_1):page77_i42@pure_quanta.q_cap(chips)',
 PATH='I42',
 DRAWING='@S9S_MB_2U_LIB.S9S_MB_2U(SCH_1):PAGE77',
 PHYS_PAGE='77',
 XY='(-5000,3050)',
 ROT='0',
 VER='1',
 PACK_TYPE='C0402',
 CDS_LIB='pure_quanta',
 CDS_PART_NAME='Q_CAP_C0402-22UF,4V,20%,X6S,CHA',
 TOLERANCE='20%',
 MATERIAL='X6S',
 VOLTAGE='4V',
 VALUE='22UF',
 PRIM_FILE='./archive_libs/logical/q_cap/chips/chips.prt';

PART_NAME
 C433 'Q_CAP_C0402-22UF,4V,20%,X6S,CHA':;

SECTION_NUMBER 1
 '@S9S_MB_2U_LIB.S9S_MB_2U(SCH_1):PAGE77_I38@PURE_QUANTA.Q_CAP(CHIPS)':
 C_PATH='@s9s_mb_2u_lib.s9s_mb_2u(sch_1):page77_i38@pure_quanta.q_cap(chips)',
 P_PATH='@s9s_mb_2u_lib.s9s_mb_2u(sch_1):page77_i38@pure_quanta.q_cap(chips)',
 PATH='I38',
 DRAWING='@S9S_MB_2U_LIB.S9S_MB_2U(SCH_1):PAGE77',
 PHYS_PAGE='77',
 XY='(-5000,2225)',
 ROT='0',
 VER='1',
 PACK_TYPE='C0402',
 CDS_LIB='pure_quanta',
 CDS_PART_NAME='Q_CAP_C0402-22UF,4V,20%,X6S,CHA',
 TOLERANCE='20%',
 MATERIAL='X6S',
 VOLTAGE='4V',
 VALUE='22UF',
 PRIM_FILE='./archive_libs/logical/q_cap/chips/chips.prt';

PART_NAME
 C434 'Q_CAP_C0402-22UF,4V,20%,X6S,CHA':;

SECTION_NUMBER 1
 '@S9S_MB_2U_LIB.S9S_MB_2U(SCH_1):PAGE77_I47@PURE_QUANTA.Q_CAP(CHIPS)':
 C_PATH='@s9s_mb_2u_lib.s9s_mb_2u(sch_1):page77_i47@pure_quanta.q_cap(chips)',
 P_PATH='@s9s_mb_2u_lib.s9s_mb_2u(sch_1):page77_i47@pure_quanta.q_cap(chips)',
 PATH='I47',
 DRAWING='@S9S_MB_2U_LIB.S9S_MB_2U(SCH_1):PAGE77',
 PHYS_PAGE='77',
 XY='(-4550,3050)',
 ROT='0',
 VER='1',
 PACK_TYPE='C0402',
 CDS_LIB='pure_quanta',
 CDS_PART_NAME='Q_CAP_C0402-22UF,4V,20%,X6S,CHA',
 TOLERANCE='20%',
 MATERIAL='X6S',
 VOLTAGE='4V',
 VALUE='22UF',
 PRIM_FILE='./archive_libs/logical/q_cap/chips/chips.prt';

PART_NAME
 C435 'Q_CAP_C0402-22UF,4V,20%,X6S,CHA':;

SECTION_NUMBER 1
 '@S9S_MB_2U_LIB.S9S_MB_2U(SCH_1):PAGE77_I39@PURE_QUANTA.Q_CAP(CHIPS)':
 C_PATH='@s9s_mb_2u_lib.s9s_mb_2u(sch_1):page77_i39@pure_quanta.q_cap(chips)',
 P_PATH='@s9s_mb_2u_lib.s9s_mb_2u(sch_1):page77_i39@pure_quanta.q_cap(chips)',
 PATH='I39',
 DRAWING='@S9S_MB_2U_LIB.S9S_MB_2U(SCH_1):PAGE77',
 PHYS_PAGE='77',
 XY='(-4550,2225)',
 ROT='0',
 VER='1',
 PACK_TYPE='C0402',
 CDS_LIB='pure_quanta',
 CDS_PART_NAME='Q_CAP_C0402-22UF,4V,20%,X6S,CHA',
 TOLERANCE='20%',
 MATERIAL='X6S',
 VOLTAGE='4V',
 VALUE='22UF',
 PRIM_FILE='./archive_libs/logical/q_cap/chips/chips.prt';

PART_NAME
 C436 'Q_CAP_C0402-22UF,4V,20%,X6S,CHA':;

SECTION_NUMBER 1
 '@S9S_MB_2U_LIB.S9S_MB_2U(SCH_1):PAGE77_I49@PURE_QUANTA.Q_CAP(CHIPS)':
 C_PATH='@s9s_mb_2u_lib.s9s_mb_2u(sch_1):page77_i49@pure_quanta.q_cap(chips)',
 P_PATH='@s9s_mb_2u_lib.s9s_mb_2u(sch_1):page77_i49@pure_quanta.q_cap(chips)',
 PATH='I49',
 DRAWING='@S9S_MB_2U_LIB.S9S_MB_2U(SCH_1):PAGE77',
 PHYS_PAGE='77',
 XY='(-4100,3050)',
 ROT='0',
 VER='1',
 PACK_TYPE='C0402',
 CDS_LIB='pure_quanta',
 CDS_PART_NAME='Q_CAP_C0402-22UF,4V,20%,X6S,CHA',
 TOLERANCE='20%',
 MATERIAL='X6S',
 VOLTAGE='4V',
 VALUE='22UF',
 PRIM_FILE='./archive_libs/logical/q_cap/chips/chips.prt';

PART_NAME
 C437 'Q_CAP_C0402-22UF,4V,20%,X6S,CHA':;

SECTION_NUMBER 1
 '@S9S_MB_2U_LIB.S9S_MB_2U(SCH_1):PAGE77_I40@PURE_QUANTA.Q_CAP(CHIPS)':
 C_PATH='@s9s_mb_2u_lib.s9s_mb_2u(sch_1):page77_i40@pure_quanta.q_cap(chips)',
 P_PATH='@s9s_mb_2u_lib.s9s_mb_2u(sch_1):page77_i40@pure_quanta.q_cap(chips)',
 PATH='I40',
 DRAWING='@S9S_MB_2U_LIB.S9S_MB_2U(SCH_1):PAGE77',
 PHYS_PAGE='77',
 XY='(-4100,2225)',
 ROT='0',
 VER='1',
 PACK_TYPE='C0402',
 CDS_LIB='pure_quanta',
 CDS_PART_NAME='Q_CAP_C0402-22UF,4V,20%,X6S,CHA',
 TOLERANCE='20%',
 MATERIAL='X6S',
 VOLTAGE='4V',
 VALUE='22UF',
 PRIM_FILE='./archive_libs/logical/q_cap/chips/chips.prt';

PART_NAME
 C438 'Q_CAP_C0402-22UF,4V,20%,X6S,CHA':;

SECTION_NUMBER 1
 '@S9S_MB_2U_LIB.S9S_MB_2U(SCH_1):PAGE77_I58@PURE_QUANTA.Q_CAP(CHIPS)':
 C_PATH='@s9s_mb_2u_lib.s9s_mb_2u(sch_1):page77_i58@pure_quanta.q_cap(chips)',
 P_PATH='@s9s_mb_2u_lib.s9s_mb_2u(sch_1):page77_i58@pure_quanta.q_cap(chips)',
 PATH='I58',
 DRAWING='@S9S_MB_2U_LIB.S9S_MB_2U(SCH_1):PAGE77',
 PHYS_PAGE='77',
 XY='(-3650,3050)',
 ROT='0',
 VER='1',
 PACK_TYPE='C0402',
 CDS_LIB='pure_quanta',
 CDS_PART_NAME='Q_CAP_C0402-22UF,4V,20%,X6S,CHA',
 TOLERANCE='20%',
 MATERIAL='X6S',
 VOLTAGE='4V',
 VALUE='22UF',
 PRIM_FILE='./archive_libs/logical/q_cap/chips/chips.prt';

PART_NAME
 C439 'Q_CAP_C0402-22UF,4V,20%,X6S,CHA':;

SECTION_NUMBER 1
 '@S9S_MB_2U_LIB.S9S_MB_2U(SCH_1):PAGE77_I53@PURE_QUANTA.Q_CAP(CHIPS)':
 C_PATH='@s9s_mb_2u_lib.s9s_mb_2u(sch_1):page77_i53@pure_quanta.q_cap(chips)',
 P_PATH='@s9s_mb_2u_lib.s9s_mb_2u(sch_1):page77_i53@pure_quanta.q_cap(chips)',
 PATH='I53',
 DRAWING='@S9S_MB_2U_LIB.S9S_MB_2U(SCH_1):PAGE77',
 PHYS_PAGE='77',
 XY='(-3650,2225)',
 ROT='0',
 VER='1',
 PACK_TYPE='C0402',
 CDS_LIB='pure_quanta',
 CDS_PART_NAME='Q_CAP_C0402-22UF,4V,20%,X6S,CHA',
 TOLERANCE='20%',
 MATERIAL='X6S',
 VOLTAGE='4V',
 VALUE='22UF',
 PRIM_FILE='./archive_libs/logical/q_cap/chips/chips.prt';

PART_NAME
 C440 'Q_CAP_C0402-22UF,4V,20%,X6S,CHA':;

SECTION_NUMBER 1
 '@S9S_MB_2U_LIB.S9S_MB_2U(SCH_1):PAGE77_I61@PURE_QUANTA.Q_CAP(CHIPS)':
 C_PATH='@s9s_mb_2u_lib.s9s_mb_2u(sch_1):page77_i61@pure_quanta.q_cap(chips)',
 P_PATH='@s9s_mb_2u_lib.s9s_mb_2u(sch_1):page77_i61@pure_quanta.q_cap(chips)',
 PATH='I61',
 DRAWING='@S9S_MB_2U_LIB.S9S_MB_2U(SCH_1):PAGE77',
 PHYS_PAGE='77',
 XY='(-3200,3050)',
 ROT='0',
 VER='1',
 PACK_TYPE='C0402',
 CDS_LIB='pure_quanta',
 CDS_PART_NAME='Q_CAP_C0402-22UF,4V,20%,X6S,CHA',
 TOLERANCE='20%',
 MATERIAL='X6S',
 VOLTAGE='4V',
 VALUE='22UF',
 PRIM_FILE='./archive_libs/logical/q_cap/chips/chips.prt';

PART_NAME
 C441 'Q_CAP_C0402-22UF,4V,20%,X6S,CHA':;

SECTION_NUMBER 1
 '@S9S_MB_2U_LIB.S9S_MB_2U(SCH_1):PAGE77_I55@PURE_QUANTA.Q_CAP(CHIPS)':
 C_PATH='@s9s_mb_2u_lib.s9s_mb_2u(sch_1):page77_i55@pure_quanta.q_cap(chips)',
 P_PATH='@s9s_mb_2u_lib.s9s_mb_2u(sch_1):page77_i55@pure_quanta.q_cap(chips)',
 PATH='I55',
 DRAWING='@S9S_MB_2U_LIB.S9S_MB_2U(SCH_1):PAGE77',
 PHYS_PAGE='77',
 XY='(-3200,2225)',
 ROT='0',
 VER='1',
 PACK_TYPE='C0402',
 CDS_LIB='pure_quanta',
 CDS_PART_NAME='Q_CAP_C0402-22UF,4V,20%,X6S,CHA',
 TOLERANCE='20%',
 MATERIAL='X6S',
 VOLTAGE='4V',
 VALUE='22UF',
 PRIM_FILE='./archive_libs/logical/q_cap/chips/chips.prt';

PART_NAME
 C442 'Q_CAP_C0402-22UF,4V,20%,X6S,CHA':;

SECTION_NUMBER 1
 '@S9S_MB_2U_LIB.S9S_MB_2U(SCH_1):PAGE77_I57@PURE_QUANTA.Q_CAP(CHIPS)':
 C_PATH='@s9s_mb_2u_lib.s9s_mb_2u(sch_1):page77_i57@pure_quanta.q_cap(chips)',
 P_PATH='@s9s_mb_2u_lib.s9s_mb_2u(sch_1):page77_i57@pure_quanta.q_cap(chips)',
 PATH='I57',
 DRAWING='@S9S_MB_2U_LIB.S9S_MB_2U(SCH_1):PAGE77',
 PHYS_PAGE='77',
 XY='(-2750,2225)',
 ROT='0',
 VER='1',
 PACK_TYPE='C0402',
 CDS_LIB='pure_quanta',
 CDS_PART_NAME='Q_CAP_C0402-22UF,4V,20%,X6S,CHA',
 TOLERANCE='20%',
 MATERIAL='X6S',
 VOLTAGE='4V',
 VALUE='22UF',
 PRIM_FILE='./archive_libs/logical/q_cap/chips/chips.prt';

PART_NAME
 C443 'Q_CAP_C0402-22UF,4V,20%,X6S,CHA':;

SECTION_NUMBER 1
 '@S9S_MB_2U_LIB.S9S_MB_2U(SCH_1):PAGE77_I67@PURE_QUANTA.Q_CAP(CHIPS)':
 C_PATH='@s9s_mb_2u_lib.s9s_mb_2u(sch_1):page77_i67@pure_quanta.q_cap(chips)',
 P_PATH='@s9s_mb_2u_lib.s9s_mb_2u(sch_1):page77_i67@pure_quanta.q_cap(chips)',
 PATH='I67',
 DRAWING='@S9S_MB_2U_LIB.S9S_MB_2U(SCH_1):PAGE77',
 PHYS_PAGE='77',
 XY='(-1975,3050)',
 ROT='0',
 VER='1',
 PACK_TYPE='C0402',
 CDS_LIB='pure_quanta',
 CDS_PART_NAME='Q_CAP_C0402-22UF,4V,20%,X6S,CHA',
 TOLERANCE='20%',
 MATERIAL='X6S',
 VOLTAGE='4V',
 VALUE='22UF',
 PRIM_FILE='./archive_libs/logical/q_cap/chips/chips.prt';

PART_NAME
 C444 'Q_CAP_C0402-22UF,4V,20%,X6S,CHA':;

SECTION_NUMBER 1
 '@S9S_MB_2U_LIB.S9S_MB_2U(SCH_1):PAGE77_I109@PURE_QUANTA.Q_CAP(CHIPS)':
 C_PATH='@s9s_mb_2u_lib.s9s_mb_2u(sch_1):page77_i109@pure_quanta.q_cap(chips)',
 P_PATH='@s9s_mb_2u_lib.s9s_mb_2u(sch_1):page77_i109@pure_quanta.q_cap(chips)',
 PATH='I109',
 DRAWING='@S9S_MB_2U_LIB.S9S_MB_2U(SCH_1):PAGE77',
 PHYS_PAGE='77',
 XY='(-1525,3050)',
 ROT='0',
 VER='1',
 PACK_TYPE='C0402',
 CDS_LIB='pure_quanta',
 CDS_PART_NAME='Q_CAP_C0402-22UF,4V,20%,X6S,CHA',
 TOLERANCE='20%',
 MATERIAL='X6S',
 VOLTAGE='4V',
 VALUE='22UF',
 PRIM_FILE='./archive_libs/logical/q_cap/chips/chips.prt';

PART_NAME
 C445 'Q_CAP_C0402-22UF,4V,20%,X6S,CHA':;

SECTION_NUMBER 1
 '@S9S_MB_2U_LIB.S9S_MB_2U(SCH_1):PAGE77_I110@PURE_QUANTA.Q_CAP(CHIPS)':
 C_PATH='@s9s_mb_2u_lib.s9s_mb_2u(sch_1):page77_i110@pure_quanta.q_cap(chips)',
 P_PATH='@s9s_mb_2u_lib.s9s_mb_2u(sch_1):page77_i110@pure_quanta.q_cap(chips)',
 PATH='I110',
 DRAWING='@S9S_MB_2U_LIB.S9S_MB_2U(SCH_1):PAGE77',
 PHYS_PAGE='77',
 XY='(-1075,3050)',
 ROT='0',
 VER='1',
 PACK_TYPE='C0402',
 CDS_LIB='pure_quanta',
 CDS_PART_NAME='Q_CAP_C0402-22UF,4V,20%,X6S,CHA',
 TOLERANCE='20%',
 MATERIAL='X6S',
 VOLTAGE='4V',
 VALUE='22UF',
 PRIM_FILE='./archive_libs/logical/q_cap/chips/chips.prt';

PART_NAME
 C446 'Q_CAP_C0402-22UF,4V,20%,X6S,CHA':;

SECTION_NUMBER 1
 '@S9S_MB_2U_LIB.S9S_MB_2U(SCH_1):PAGE77_I113@PURE_QUANTA.Q_CAP(CHIPS)':
 C_PATH='@s9s_mb_2u_lib.s9s_mb_2u(sch_1):page77_i113@pure_quanta.q_cap(chips)',
 P_PATH='@s9s_mb_2u_lib.s9s_mb_2u(sch_1):page77_i113@pure_quanta.q_cap(chips)',
 PATH='I113',
 DRAWING='@S9S_MB_2U_LIB.S9S_MB_2U(SCH_1):PAGE77',
 PHYS_PAGE='77',
 XY='(-625,3050)',
 ROT='0',
 VER='1',
 PACK_TYPE='C0402',
 CDS_LIB='pure_quanta',
 CDS_PART_NAME='Q_CAP_C0402-22UF,4V,20%,X6S,CHA',
 TOLERANCE='20%',
 MATERIAL='X6S',
 VOLTAGE='4V',
 VALUE='22UF',
 PRIM_FILE='./archive_libs/logical/q_cap/chips/chips.prt';

PART_NAME
 C447 'Q_CAP_C0805-47UF,4V,20%,X6S,CHA':;

SECTION_NUMBER 1
 '@S9S_MB_2U_LIB.S9S_MB_2U(SCH_1):PAGE78_I12@PURE_QUANTA.Q_CAP(CHIPS)':
 C_PATH='@s9s_mb_2u_lib.s9s_mb_2u(sch_1):page78_i12@pure_quanta.q_cap(chips)',
 P_PATH='@s9s_mb_2u_lib.s9s_mb_2u(sch_1):page78_i12@pure_quanta.q_cap(chips)',
 PATH='I12',
 DRAWING='@S9S_MB_2U_LIB.S9S_MB_2U(SCH_1):PAGE78',
 PHYS_PAGE='78',
 XY='(-4450,675)',
 ROT='0',
 VER='1',
 PACK_TYPE='C0805',
 CDS_LIB='pure_quanta',
 CDS_PART_NAME='Q_CAP_C0805-47UF,4V,20%,X6S,CHA',
 TOLERANCE='20%',
 MATERIAL='X6S',
 VOLTAGE='4V',
 VALUE='47UF',
 PRIM_FILE='./archive_libs/logical/q_cap/chips/chips.prt';

PART_NAME
 C448 'Q_CAP_C0805-47UF,4V,20%,X6S,CHA':;

SECTION_NUMBER 1
 '@S9S_MB_2U_LIB.S9S_MB_2U(SCH_1):PAGE78_I10@PURE_QUANTA.Q_CAP(CHIPS)':
 C_PATH='@s9s_mb_2u_lib.s9s_mb_2u(sch_1):page78_i10@pure_quanta.q_cap(chips)',
 P_PATH='@s9s_mb_2u_lib.s9s_mb_2u(sch_1):page78_i10@pure_quanta.q_cap(chips)',
 PATH='I10',
 DRAWING='@S9S_MB_2U_LIB.S9S_MB_2U(SCH_1):PAGE78',
 PHYS_PAGE='78',
 XY='(-4450,-225)',
 ROT='0',
 VER='1',
 PACK_TYPE='C0805',
 CDS_LIB='pure_quanta',
 CDS_PART_NAME='Q_CAP_C0805-47UF,4V,20%,X6S,CHA',
 TOLERANCE='20%',
 MATERIAL='X6S',
 VOLTAGE='4V',
 VALUE='47UF',
 PRIM_FILE='./archive_libs/logical/q_cap/chips/chips.prt';

PART_NAME
 C449 'Q_CAP_C0805-47UF,4V,20%,X6S,CHA':;

SECTION_NUMBER 1
 '@S9S_MB_2U_LIB.S9S_MB_2U(SCH_1):PAGE78_I1@PURE_QUANTA.Q_CAP(CHIPS)':
 C_PATH='@s9s_mb_2u_lib.s9s_mb_2u(sch_1):page78_i1@pure_quanta.q_cap(chips)',
 P_PATH='@s9s_mb_2u_lib.s9s_mb_2u(sch_1):page78_i1@pure_quanta.q_cap(chips)',
 PATH='I1',
 DRAWING='@S9S_MB_2U_LIB.S9S_MB_2U(SCH_1):PAGE78',
 PHYS_PAGE='78',
 XY='(-4450,-2200)',
 ROT='0',
 VER='1',
 PACK_TYPE='C0805',
 CDS_LIB='pure_quanta',
 CDS_PART_NAME='Q_CAP_C0805-47UF,4V,20%,X6S,CHA',
 TOLERANCE='20%',
 MATERIAL='X6S',
 VOLTAGE='4V',
 VALUE='47UF',
 PRIM_FILE='./archive_libs/logical/q_cap/chips/chips.prt';

PART_NAME
 C450 'Q_CAP_C0805-47UF,4V,20%,X6S,CHA':;

SECTION_NUMBER 1
 '@S9S_MB_2U_LIB.S9S_MB_2U(SCH_1):PAGE79_I1@PURE_QUANTA.Q_CAP(CHIPS)':
 C_PATH='@s9s_mb_2u_lib.s9s_mb_2u(sch_1):page79_i1@pure_quanta.q_cap(chips)',
 P_PATH='@s9s_mb_2u_lib.s9s_mb_2u(sch_1):page79_i1@pure_quanta.q_cap(chips)',
 PATH='I1',
 DRAWING='@S9S_MB_2U_LIB.S9S_MB_2U(SCH_1):PAGE79',
 PHYS_PAGE='79',
 XY='(-4425,-2375)',
 ROT='0',
 VER='1',
 PACK_TYPE='C0805',
 CDS_LIB='pure_quanta',
 CDS_PART_NAME='Q_CAP_C0805-47UF,4V,20%,X6S,CHA',
 TOLERANCE='20%',
 MATERIAL='X6S',
 VOLTAGE='4V',
 VALUE='47UF',
 PRIM_FILE='./archive_libs/logical/q_cap/chips/chips.prt';

PART_NAME
 C451 'Q_CAP_C0805-47UF,4V,20%,X6S,CHA':;

SECTION_NUMBER 1
 '@S9S_MB_2U_LIB.S9S_MB_2U(SCH_1):PAGE78_I24@PURE_QUANTA.Q_CAP(CHIPS)':
 C_PATH='@s9s_mb_2u_lib.s9s_mb_2u(sch_1):page78_i24@pure_quanta.q_cap(chips)',
 P_PATH='@s9s_mb_2u_lib.s9s_mb_2u(sch_1):page78_i24@pure_quanta.q_cap(chips)',
 PATH='I24',
 DRAWING='@S9S_MB_2U_LIB.S9S_MB_2U(SCH_1):PAGE78',
 PHYS_PAGE='78',
 XY='(-4000,675)',
 ROT='0',
 VER='1',
 PACK_TYPE='C0805',
 CDS_LIB='pure_quanta',
 CDS_PART_NAME='Q_CAP_C0805-47UF,4V,20%,X6S,CHA',
 TOLERANCE='20%',
 MATERIAL='X6S',
 VOLTAGE='4V',
 VALUE='47UF',
 PRIM_FILE='./archive_libs/logical/q_cap/chips/chips.prt';

PART_NAME
 C452 'Q_CAP_C0805-47UF,4V,20%,X6S,CHA':;

SECTION_NUMBER 1
 '@S9S_MB_2U_LIB.S9S_MB_2U(SCH_1):PAGE78_I21@PURE_QUANTA.Q_CAP(CHIPS)':
 C_PATH='@s9s_mb_2u_lib.s9s_mb_2u(sch_1):page78_i21@pure_quanta.q_cap(chips)',
 P_PATH='@s9s_mb_2u_lib.s9s_mb_2u(sch_1):page78_i21@pure_quanta.q_cap(chips)',
 PATH='I21',
 DRAWING='@S9S_MB_2U_LIB.S9S_MB_2U(SCH_1):PAGE78',
 PHYS_PAGE='78',
 XY='(-4000,-225)',
 ROT='0',
 VER='1',
 PACK_TYPE='C0805',
 CDS_LIB='pure_quanta',
 CDS_PART_NAME='Q_CAP_C0805-47UF,4V,20%,X6S,CHA',
 TOLERANCE='20%',
 MATERIAL='X6S',
 VOLTAGE='4V',
 VALUE='47UF',
 PRIM_FILE='./archive_libs/logical/q_cap/chips/chips.prt';

PART_NAME
 C453 'Q_CAP_C0805-47UF,4V,20%,X6S,CHA':;

SECTION_NUMBER 1
 '@S9S_MB_2U_LIB.S9S_MB_2U(SCH_1):PAGE78_I3@PURE_QUANTA.Q_CAP(CHIPS)':
 C_PATH='@s9s_mb_2u_lib.s9s_mb_2u(sch_1):page78_i3@pure_quanta.q_cap(chips)',
 P_PATH='@s9s_mb_2u_lib.s9s_mb_2u(sch_1):page78_i3@pure_quanta.q_cap(chips)',
 PATH='I3',
 DRAWING='@S9S_MB_2U_LIB.S9S_MB_2U(SCH_1):PAGE78',
 PHYS_PAGE='78',
 XY='(-4000,-2200)',
 ROT='0',
 VER='1',
 PACK_TYPE='C0805',
 CDS_LIB='pure_quanta',
 CDS_PART_NAME='Q_CAP_C0805-47UF,4V,20%,X6S,CHA',
 TOLERANCE='20%',
 MATERIAL='X6S',
 VOLTAGE='4V',
 VALUE='47UF',
 PRIM_FILE='./archive_libs/logical/q_cap/chips/chips.prt';

PART_NAME
 C454 'Q_CAP_C0805-47UF,4V,20%,X6S,CHA':;

SECTION_NUMBER 1
 '@S9S_MB_2U_LIB.S9S_MB_2U(SCH_1):PAGE79_I3@PURE_QUANTA.Q_CAP(CHIPS)':
 C_PATH='@s9s_mb_2u_lib.s9s_mb_2u(sch_1):page79_i3@pure_quanta.q_cap(chips)',
 P_PATH='@s9s_mb_2u_lib.s9s_mb_2u(sch_1):page79_i3@pure_quanta.q_cap(chips)',
 PATH='I3',
 DRAWING='@S9S_MB_2U_LIB.S9S_MB_2U(SCH_1):PAGE79',
 PHYS_PAGE='79',
 XY='(-3975,-2375)',
 ROT='0',
 VER='1',
 PACK_TYPE='C0805',
 CDS_LIB='pure_quanta',
 CDS_PART_NAME='Q_CAP_C0805-47UF,4V,20%,X6S,CHA',
 TOLERANCE='20%',
 MATERIAL='X6S',
 VOLTAGE='4V',
 VALUE='47UF',
 PRIM_FILE='./archive_libs/logical/q_cap/chips/chips.prt';

PART_NAME
 C455 'Q_CAP_C0805-47UF,4V,20%,X6S,CHA':;

SECTION_NUMBER 1
 '@S9S_MB_2U_LIB.S9S_MB_2U(SCH_1):PAGE79_I19@PURE_QUANTA.Q_CAP(CHIPS)':
 C_PATH='@s9s_mb_2u_lib.s9s_mb_2u(sch_1):page79_i19@pure_quanta.q_cap(chips)',
 P_PATH='@s9s_mb_2u_lib.s9s_mb_2u(sch_1):page79_i19@pure_quanta.q_cap(chips)',
 PATH='I19',
 DRAWING='@S9S_MB_2U_LIB.S9S_MB_2U(SCH_1):PAGE79',
 PHYS_PAGE='79',
 XY='(-4400,1475)',
 ROT='0',
 VER='1',
 PACK_TYPE='C0805',
 CDS_LIB='pure_quanta',
 CDS_PART_NAME='Q_CAP_C0805-47UF,4V,20%,X6S,CHA',
 TOLERANCE='20%',
 MATERIAL='X6S',
 VOLTAGE='4V',
 VALUE='47UF',
 PRIM_FILE='./archive_libs/logical/q_cap/chips/chips.prt';

PART_NAME
 C456 'Q_CAP_C0805-47UF,4V,20%,X6S,CHA':;

SECTION_NUMBER 1
 '@S9S_MB_2U_LIB.S9S_MB_2U(SCH_1):PAGE79_I15@PURE_QUANTA.Q_CAP(CHIPS)':
 C_PATH='@s9s_mb_2u_lib.s9s_mb_2u(sch_1):page79_i15@pure_quanta.q_cap(chips)',
 P_PATH='@s9s_mb_2u_lib.s9s_mb_2u(sch_1):page79_i15@pure_quanta.q_cap(chips)',
 PATH='I15',
 DRAWING='@S9S_MB_2U_LIB.S9S_MB_2U(SCH_1):PAGE79',
 PHYS_PAGE='79',
 XY='(-4425,-400)',
 ROT='0',
 VER='1',
 PACK_TYPE='C0805',
 CDS_LIB='pure_quanta',
 CDS_PART_NAME='Q_CAP_C0805-47UF,4V,20%,X6S,CHA',
 TOLERANCE='20%',
 MATERIAL='X6S',
 VOLTAGE='4V',
 VALUE='47UF',
 PRIM_FILE='./archive_libs/logical/q_cap/chips/chips.prt';

PART_NAME
 C457 'Q_CAP_C0805-47UF,4V,20%,X6S,CHA':;

SECTION_NUMBER 1
 '@S9S_MB_2U_LIB.S9S_MB_2U(SCH_1):PAGE78_I4@PURE_QUANTA.Q_CAP(CHIPS)':
 C_PATH='@s9s_mb_2u_lib.s9s_mb_2u(sch_1):page78_i4@pure_quanta.q_cap(chips)',
 P_PATH='@s9s_mb_2u_lib.s9s_mb_2u(sch_1):page78_i4@pure_quanta.q_cap(chips)',
 PATH='I4',
 DRAWING='@S9S_MB_2U_LIB.S9S_MB_2U(SCH_1):PAGE78',
 PHYS_PAGE='78',
 XY='(-3550,-2200)',
 ROT='0',
 VER='1',
 PACK_TYPE='C0805',
 CDS_LIB='pure_quanta',
 CDS_PART_NAME='Q_CAP_C0805-47UF,4V,20%,X6S,CHA',
 TOLERANCE='20%',
 MATERIAL='X6S',
 VOLTAGE='4V',
 VALUE='47UF',
 PRIM_FILE='./archive_libs/logical/q_cap/chips/chips.prt';

PART_NAME
 C458 'Q_CAP_C0805-47UF,4V,20%,X6S,CHA':;

SECTION_NUMBER 1
 '@S9S_MB_2U_LIB.S9S_MB_2U(SCH_1):PAGE79_I4@PURE_QUANTA.Q_CAP(CHIPS)':
 C_PATH='@s9s_mb_2u_lib.s9s_mb_2u(sch_1):page79_i4@pure_quanta.q_cap(chips)',
 P_PATH='@s9s_mb_2u_lib.s9s_mb_2u(sch_1):page79_i4@pure_quanta.q_cap(chips)',
 PATH='I4',
 DRAWING='@S9S_MB_2U_LIB.S9S_MB_2U(SCH_1):PAGE79',
 PHYS_PAGE='79',
 XY='(-3525,-2375)',
 ROT='0',
 VER='1',
 PACK_TYPE='C0805',
 CDS_LIB='pure_quanta',
 CDS_PART_NAME='Q_CAP_C0805-47UF,4V,20%,X6S,CHA',
 TOLERANCE='20%',
 MATERIAL='X6S',
 VOLTAGE='4V',
 VALUE='47UF',
 PRIM_FILE='./archive_libs/logical/q_cap/chips/chips.prt';

PART_NAME
 C459 'Q_CAP_C0805-47UF,4V,20%,X6S,CHA':;

SECTION_NUMBER 1
 '@S9S_MB_2U_LIB.S9S_MB_2U(SCH_1):PAGE79_I20@PURE_QUANTA.Q_CAP(CHIPS)':
 C_PATH='@s9s_mb_2u_lib.s9s_mb_2u(sch_1):page79_i20@pure_quanta.q_cap(chips)',
 P_PATH='@s9s_mb_2u_lib.s9s_mb_2u(sch_1):page79_i20@pure_quanta.q_cap(chips)',
 PATH='I20',
 DRAWING='@S9S_MB_2U_LIB.S9S_MB_2U(SCH_1):PAGE79',
 PHYS_PAGE='79',
 XY='(-3950,1475)',
 ROT='0',
 VER='1',
 PACK_TYPE='C0805',
 CDS_LIB='pure_quanta',
 CDS_PART_NAME='Q_CAP_C0805-47UF,4V,20%,X6S,CHA',
 TOLERANCE='20%',
 MATERIAL='X6S',
 VOLTAGE='4V',
 VALUE='47UF',
 PRIM_FILE='./archive_libs/logical/q_cap/chips/chips.prt';

PART_NAME
 C460 'Q_CAP_C0805-47UF,4V,20%,X6S,CHA':;

SECTION_NUMBER 1
 '@S9S_MB_2U_LIB.S9S_MB_2U(SCH_1):PAGE79_I16@PURE_QUANTA.Q_CAP(CHIPS)':
 C_PATH='@s9s_mb_2u_lib.s9s_mb_2u(sch_1):page79_i16@pure_quanta.q_cap(chips)',
 P_PATH='@s9s_mb_2u_lib.s9s_mb_2u(sch_1):page79_i16@pure_quanta.q_cap(chips)',
 PATH='I16',
 DRAWING='@S9S_MB_2U_LIB.S9S_MB_2U(SCH_1):PAGE79',
 PHYS_PAGE='79',
 XY='(-3975,-400)',
 ROT='0',
 VER='1',
 PACK_TYPE='C0805',
 CDS_LIB='pure_quanta',
 CDS_PART_NAME='Q_CAP_C0805-47UF,4V,20%,X6S,CHA',
 TOLERANCE='20%',
 MATERIAL='X6S',
 VOLTAGE='4V',
 VALUE='47UF',
 PRIM_FILE='./archive_libs/logical/q_cap/chips/chips.prt';

PART_NAME
 C461 'Q_CAP_C0805-47UF,4V,20%,X6S,CHA':;

SECTION_NUMBER 1
 '@S9S_MB_2U_LIB.S9S_MB_2U(SCH_1):PAGE78_I5@PURE_QUANTA.Q_CAP(CHIPS)':
 C_PATH='@s9s_mb_2u_lib.s9s_mb_2u(sch_1):page78_i5@pure_quanta.q_cap(chips)',
 P_PATH='@s9s_mb_2u_lib.s9s_mb_2u(sch_1):page78_i5@pure_quanta.q_cap(chips)',
 PATH='I5',
 DRAWING='@S9S_MB_2U_LIB.S9S_MB_2U(SCH_1):PAGE78',
 PHYS_PAGE='78',
 XY='(-3100,-2200)',
 ROT='0',
 VER='1',
 PACK_TYPE='C0805',
 CDS_LIB='pure_quanta',
 CDS_PART_NAME='Q_CAP_C0805-47UF,4V,20%,X6S,CHA',
 TOLERANCE='20%',
 MATERIAL='X6S',
 VOLTAGE='4V',
 VALUE='47UF',
 PRIM_FILE='./archive_libs/logical/q_cap/chips/chips.prt';

PART_NAME
 C462 'Q_CAP_C0805-47UF,4V,20%,X6S,CHA':;

SECTION_NUMBER 1
 '@S9S_MB_2U_LIB.S9S_MB_2U(SCH_1):PAGE79_I5@PURE_QUANTA.Q_CAP(CHIPS)':
 C_PATH='@s9s_mb_2u_lib.s9s_mb_2u(sch_1):page79_i5@pure_quanta.q_cap(chips)',
 P_PATH='@s9s_mb_2u_lib.s9s_mb_2u(sch_1):page79_i5@pure_quanta.q_cap(chips)',
 PATH='I5',
 DRAWING='@S9S_MB_2U_LIB.S9S_MB_2U(SCH_1):PAGE79',
 PHYS_PAGE='79',
 XY='(-3075,-2375)',
 ROT='0',
 VER='1',
 PACK_TYPE='C0805',
 CDS_LIB='pure_quanta',
 CDS_PART_NAME='Q_CAP_C0805-47UF,4V,20%,X6S,CHA',
 TOLERANCE='20%',
 MATERIAL='X6S',
 VOLTAGE='4V',
 VALUE='47UF',
 PRIM_FILE='./archive_libs/logical/q_cap/chips/chips.prt';

PART_NAME
 C463 'Q_CAP_C0805-47UF,4V,20%,X6S,CHA':;

SECTION_NUMBER 1
 '@S9S_MB_2U_LIB.S9S_MB_2U(SCH_1):PAGE79_I21@PURE_QUANTA.Q_CAP(CHIPS)':
 C_PATH='@s9s_mb_2u_lib.s9s_mb_2u(sch_1):page79_i21@pure_quanta.q_cap(chips)',
 P_PATH='@s9s_mb_2u_lib.s9s_mb_2u(sch_1):page79_i21@pure_quanta.q_cap(chips)',
 PATH='I21',
 DRAWING='@S9S_MB_2U_LIB.S9S_MB_2U(SCH_1):PAGE79',
 PHYS_PAGE='79',
 XY='(-3500,1475)',
 ROT='0',
 VER='1',
 PACK_TYPE='C0805',
 CDS_LIB='pure_quanta',
 CDS_PART_NAME='Q_CAP_C0805-47UF,4V,20%,X6S,CHA',
 TOLERANCE='20%',
 MATERIAL='X6S',
 VOLTAGE='4V',
 VALUE='47UF',
 PRIM_FILE='./archive_libs/logical/q_cap/chips/chips.prt';

PART_NAME
 C464 'Q_CAP_C0805-47UF,4V,20%,X6S,CHA':;

SECTION_NUMBER 1
 '@S9S_MB_2U_LIB.S9S_MB_2U(SCH_1):PAGE79_I17@PURE_QUANTA.Q_CAP(CHIPS)':
 C_PATH='@s9s_mb_2u_lib.s9s_mb_2u(sch_1):page79_i17@pure_quanta.q_cap(chips)',
 P_PATH='@s9s_mb_2u_lib.s9s_mb_2u(sch_1):page79_i17@pure_quanta.q_cap(chips)',
 PATH='I17',
 DRAWING='@S9S_MB_2U_LIB.S9S_MB_2U(SCH_1):PAGE79',
 PHYS_PAGE='79',
 XY='(-3525,-400)',
 ROT='0',
 VER='1',
 PACK_TYPE='C0805',
 CDS_LIB='pure_quanta',
 CDS_PART_NAME='Q_CAP_C0805-47UF,4V,20%,X6S,CHA',
 TOLERANCE='20%',
 MATERIAL='X6S',
 VOLTAGE='4V',
 VALUE='47UF',
 PRIM_FILE='./archive_libs/logical/q_cap/chips/chips.prt';

PART_NAME
 C465 'Q_CAP_C0603-47UF,2.5V,20%,X6S,A':;

SECTION_NUMBER 1
 '@S9S_MB_2U_LIB.S9S_MB_2U(SCH_1):PAGE78_I7@PURE_QUANTA.Q_CAP(CHIPS)':
 C_PATH='@s9s_mb_2u_lib.s9s_mb_2u(sch_1):page78_i7@pure_quanta.q_cap(chips)',
 P_PATH='@s9s_mb_2u_lib.s9s_mb_2u(sch_1):page78_i7@pure_quanta.q_cap(chips)',
 PATH='I7',
 DRAWING='@S9S_MB_2U_LIB.S9S_MB_2U(SCH_1):PAGE78',
 PHYS_PAGE='78',
 XY='(-2650,-2200)',
 ROT='0',
 VER='1',
 PACK_TYPE='C0603',
 CDS_LIB='pure_quanta',
 CDS_PART_NAME='Q_CAP_C0603-47UF,2.5V,20%,X6S,A',
 TOLERANCE='20%',
 MATERIAL='X6S',
 VOLTAGE='2.5V',
 VALUE='47UF',
 PRIM_FILE='./archive_libs/logical/q_cap/chips/chips.prt';

PART_NAME
 C466 'Q_CAP_C0805-47UF,4V,20%,X6S,CHA':;

SECTION_NUMBER 1
 '@S9S_MB_2U_LIB.S9S_MB_2U(SCH_1):PAGE79_I7@PURE_QUANTA.Q_CAP(CHIPS)':
 C_PATH='@s9s_mb_2u_lib.s9s_mb_2u(sch_1):page79_i7@pure_quanta.q_cap(chips)',
 P_PATH='@s9s_mb_2u_lib.s9s_mb_2u(sch_1):page79_i7@pure_quanta.q_cap(chips)',
 PATH='I7',
 DRAWING='@S9S_MB_2U_LIB.S9S_MB_2U(SCH_1):PAGE79',
 PHYS_PAGE='79',
 XY='(-2625,-2375)',
 ROT='0',
 VER='1',
 PACK_TYPE='C0805',
 CDS_LIB='pure_quanta',
 CDS_PART_NAME='Q_CAP_C0805-47UF,4V,20%,X6S,CHA',
 TOLERANCE='20%',
 MATERIAL='X6S',
 VOLTAGE='4V',
 VALUE='47UF',
 PRIM_FILE='./archive_libs/logical/q_cap/chips/chips.prt';

PART_NAME
 C467 'Q_CAP_C0805-47UF,4V,20%,X6S,CHA':;

SECTION_NUMBER 1
 '@S9S_MB_2U_LIB.S9S_MB_2U(SCH_1):PAGE79_I31@PURE_QUANTA.Q_CAP(CHIPS)':
 C_PATH='@s9s_mb_2u_lib.s9s_mb_2u(sch_1):page79_i31@pure_quanta.q_cap(chips)',
 P_PATH='@s9s_mb_2u_lib.s9s_mb_2u(sch_1):page79_i31@pure_quanta.q_cap(chips)',
 PATH='I31',
 DRAWING='@S9S_MB_2U_LIB.S9S_MB_2U(SCH_1):PAGE79',
 PHYS_PAGE='79',
 XY='(-3050,1475)',
 ROT='0',
 VER='1',
 PACK_TYPE='C0805',
 CDS_LIB='pure_quanta',
 CDS_PART_NAME='Q_CAP_C0805-47UF,4V,20%,X6S,CHA',
 TOLERANCE='20%',
 MATERIAL='X6S',
 VOLTAGE='4V',
 VALUE='47UF',
 PRIM_FILE='./archive_libs/logical/q_cap/chips/chips.prt';

PART_NAME
 C468 'Q_CAP_C0805-47UF,4V,20%,X6S,CHA':;

SECTION_NUMBER 1
 '@S9S_MB_2U_LIB.S9S_MB_2U(SCH_1):PAGE79_I26@PURE_QUANTA.Q_CAP(CHIPS)':
 C_PATH='@s9s_mb_2u_lib.s9s_mb_2u(sch_1):page79_i26@pure_quanta.q_cap(chips)',
 P_PATH='@s9s_mb_2u_lib.s9s_mb_2u(sch_1):page79_i26@pure_quanta.q_cap(chips)',
 PATH='I26',
 DRAWING='@S9S_MB_2U_LIB.S9S_MB_2U(SCH_1):PAGE79',
 PHYS_PAGE='79',
 XY='(-3075,-400)',
 ROT='0',
 VER='1',
 PACK_TYPE='C0805',
 CDS_LIB='pure_quanta',
 CDS_PART_NAME='Q_CAP_C0805-47UF,4V,20%,X6S,CHA',
 TOLERANCE='20%',
 MATERIAL='X6S',
 VOLTAGE='4V',
 VALUE='47UF',
 PRIM_FILE='./archive_libs/logical/q_cap/chips/chips.prt';

PART_NAME
 C470 'Q_CAP_C0805-47UF,4V,20%,X6S,CHA':;

SECTION_NUMBER 1
 '@S9S_MB_2U_LIB.S9S_MB_2U(SCH_1):PAGE79_I8@PURE_QUANTA.Q_CAP(CHIPS)':
 C_PATH='@s9s_mb_2u_lib.s9s_mb_2u(sch_1):page79_i8@pure_quanta.q_cap(chips)',
 P_PATH='@s9s_mb_2u_lib.s9s_mb_2u(sch_1):page79_i8@pure_quanta.q_cap(chips)',
 PATH='I8',
 DRAWING='@S9S_MB_2U_LIB.S9S_MB_2U(SCH_1):PAGE79',
 PHYS_PAGE='79',
 XY='(-2175,-2375)',
 ROT='0',
 VER='1',
 PACK_TYPE='C0805',
 CDS_LIB='pure_quanta',
 CDS_PART_NAME='Q_CAP_C0805-47UF,4V,20%,X6S,CHA',
 TOLERANCE='20%',
 MATERIAL='X6S',
 VOLTAGE='4V',
 VALUE='47UF',
 PRIM_FILE='./archive_libs/logical/q_cap/chips/chips.prt';

PART_NAME
 C471 'Q_CAP_C0805-47UF,4V,20%,X6S,CHA':;

SECTION_NUMBER 1
 '@S9S_MB_2U_LIB.S9S_MB_2U(SCH_1):PAGE78_I25@PURE_QUANTA.Q_CAP(CHIPS)':
 C_PATH='@s9s_mb_2u_lib.s9s_mb_2u(sch_1):page78_i25@pure_quanta.q_cap(chips)',
 P_PATH='@s9s_mb_2u_lib.s9s_mb_2u(sch_1):page78_i25@pure_quanta.q_cap(chips)',
 PATH='I25',
 DRAWING='@S9S_MB_2U_LIB.S9S_MB_2U(SCH_1):PAGE78',
 PHYS_PAGE='78',
 XY='(-3550,675)',
 ROT='0',
 VER='1',
 PACK_TYPE='C0805',
 CDS_LIB='pure_quanta',
 CDS_PART_NAME='Q_CAP_C0805-47UF,4V,20%,X6S,CHA',
 TOLERANCE='20%',
 MATERIAL='X6S',
 VOLTAGE='4V',
 VALUE='47UF',
 PRIM_FILE='./archive_libs/logical/q_cap/chips/chips.prt';

PART_NAME
 C472 'Q_CAP_C0603-47UF,2.5V,20%,X6S,A':;

SECTION_NUMBER 1
 '@S9S_MB_2U_LIB.S9S_MB_2U(SCH_1):PAGE79_I27@PURE_QUANTA.Q_CAP(CHIPS)':
 C_PATH='@s9s_mb_2u_lib.s9s_mb_2u(sch_1):page79_i27@pure_quanta.q_cap(chips)',
 P_PATH='@s9s_mb_2u_lib.s9s_mb_2u(sch_1):page79_i27@pure_quanta.q_cap(chips)',
 PATH='I27',
 DRAWING='@S9S_MB_2U_LIB.S9S_MB_2U(SCH_1):PAGE79',
 PHYS_PAGE='79',
 XY='(-2625,-400)',
 ROT='0',
 VER='1',
 PACK_TYPE='C0603',
 CDS_LIB='pure_quanta',
 CDS_PART_NAME='Q_CAP_C0603-47UF,2.5V,20%,X6S,A',
 TOLERANCE='20%',
 MATERIAL='X6S',
 VOLTAGE='2.5V',
 VALUE='47UF',
 PRIM_FILE='./archive_libs/logical/q_cap/chips/chips.prt';

PART_NAME
 C473 'Q_CAP_C0805-47UF,4V,20%,X6S,CHA':;

SECTION_NUMBER 1
 '@S9S_MB_2U_LIB.S9S_MB_2U(SCH_1):PAGE79_I9@PURE_QUANTA.Q_CAP(CHIPS)':
 C_PATH='@s9s_mb_2u_lib.s9s_mb_2u(sch_1):page79_i9@pure_quanta.q_cap(chips)',
 P_PATH='@s9s_mb_2u_lib.s9s_mb_2u(sch_1):page79_i9@pure_quanta.q_cap(chips)',
 PATH='I9',
 DRAWING='@S9S_MB_2U_LIB.S9S_MB_2U(SCH_1):PAGE79',
 PHYS_PAGE='79',
 XY='(-1725,-2375)',
 ROT='0',
 VER='1',
 PACK_TYPE='C0805',
 CDS_LIB='pure_quanta',
 CDS_PART_NAME='Q_CAP_C0805-47UF,4V,20%,X6S,CHA',
 TOLERANCE='20%',
 MATERIAL='X6S',
 VOLTAGE='4V',
 VALUE='47UF',
 PRIM_FILE='./archive_libs/logical/q_cap/chips/chips.prt';

PART_NAME
 C474 'Q_CAP_C0805-47UF,4V,20%,X6S,CHA':;

SECTION_NUMBER 1
 '@S9S_MB_2U_LIB.S9S_MB_2U(SCH_1):PAGE78_I29@PURE_QUANTA.Q_CAP(CHIPS)':
 C_PATH='@s9s_mb_2u_lib.s9s_mb_2u(sch_1):page78_i29@pure_quanta.q_cap(chips)',
 P_PATH='@s9s_mb_2u_lib.s9s_mb_2u(sch_1):page78_i29@pure_quanta.q_cap(chips)',
 PATH='I29',
 DRAWING='@S9S_MB_2U_LIB.S9S_MB_2U(SCH_1):PAGE78',
 PHYS_PAGE='78',
 XY='(-3100,675)',
 ROT='0',
 VER='1',
 PACK_TYPE='C0805',
 CDS_LIB='pure_quanta',
 CDS_PART_NAME='Q_CAP_C0805-47UF,4V,20%,X6S,CHA',
 TOLERANCE='20%',
 MATERIAL='X6S',
 VOLTAGE='4V',
 VALUE='47UF',
 PRIM_FILE='./archive_libs/logical/q_cap/chips/chips.prt';

PART_NAME
 C475 'Q_CAP_C0603-47UF,2.5V,20%,X6S,A':;

SECTION_NUMBER 1
 '@S9S_MB_2U_LIB.S9S_MB_2U(SCH_1):PAGE79_I29@PURE_QUANTA.Q_CAP(CHIPS)':
 C_PATH='@s9s_mb_2u_lib.s9s_mb_2u(sch_1):page79_i29@pure_quanta.q_cap(chips)',
 P_PATH='@s9s_mb_2u_lib.s9s_mb_2u(sch_1):page79_i29@pure_quanta.q_cap(chips)',
 PATH='I29',
 DRAWING='@S9S_MB_2U_LIB.S9S_MB_2U(SCH_1):PAGE79',
 PHYS_PAGE='79',
 XY='(-2175,-400)',
 ROT='0',
 VER='1',
 PACK_TYPE='C0603',
 CDS_LIB='pure_quanta',
 CDS_PART_NAME='Q_CAP_C0603-47UF,2.5V,20%,X6S,A',
 TOLERANCE='20%',
 MATERIAL='X6S',
 VOLTAGE='2.5V',
 VALUE='47UF',
 PRIM_FILE='./archive_libs/logical/q_cap/chips/chips.prt';

PART_NAME
 C476 'Q_CAP_C0805-47UF,4V,20%,X6S,CHA':;

SECTION_NUMBER 1
 '@S9S_MB_2U_LIB.S9S_MB_2U(SCH_1):PAGE79_I37@PURE_QUANTA.Q_CAP(CHIPS)':
 C_PATH='@s9s_mb_2u_lib.s9s_mb_2u(sch_1):page79_i37@pure_quanta.q_cap(chips)',
 P_PATH='@s9s_mb_2u_lib.s9s_mb_2u(sch_1):page79_i37@pure_quanta.q_cap(chips)',
 PATH='I37',
 DRAWING='@S9S_MB_2U_LIB.S9S_MB_2U(SCH_1):PAGE79',
 PHYS_PAGE='79',
 XY='(-1275,-2375)',
 ROT='0',
 VER='1',
 PACK_TYPE='C0805',
 CDS_LIB='pure_quanta',
 CDS_PART_NAME='Q_CAP_C0805-47UF,4V,20%,X6S,CHA',
 TOLERANCE='20%',
 MATERIAL='X6S',
 VOLTAGE='4V',
 VALUE='47UF',
 PRIM_FILE='./archive_libs/logical/q_cap/chips/chips.prt';

PART_NAME
 C477 'Q_CAP_C0805-47UF,4V,20%,X6S,CHA':;

SECTION_NUMBER 1
 '@S9S_MB_2U_LIB.S9S_MB_2U(SCH_1):PAGE79_I38@PURE_QUANTA.Q_CAP(CHIPS)':
 C_PATH='@s9s_mb_2u_lib.s9s_mb_2u(sch_1):page79_i38@pure_quanta.q_cap(chips)',
 P_PATH='@s9s_mb_2u_lib.s9s_mb_2u(sch_1):page79_i38@pure_quanta.q_cap(chips)',
 PATH='I38',
 DRAWING='@S9S_MB_2U_LIB.S9S_MB_2U(SCH_1):PAGE79',
 PHYS_PAGE='79',
 XY='(-825,-2375)',
 ROT='0',
 VER='1',
 PACK_TYPE='C0805',
 CDS_LIB='pure_quanta',
 CDS_PART_NAME='Q_CAP_C0805-47UF,4V,20%,X6S,CHA',
 TOLERANCE='20%',
 MATERIAL='X6S',
 VOLTAGE='4V',
 VALUE='47UF',
 PRIM_FILE='./archive_libs/logical/q_cap/chips/chips.prt';

PART_NAME
 C478 'Q_CAP_C0805-47UF,4V,20%,X6S,CHA':;

SECTION_NUMBER 1
 '@S9S_MB_2U_LIB.S9S_MB_2U(SCH_1):PAGE78_I8@PURE_QUANTA.Q_CAP(CHIPS)':
 C_PATH='@s9s_mb_2u_lib.s9s_mb_2u(sch_1):page78_i8@pure_quanta.q_cap(chips)',
 P_PATH='@s9s_mb_2u_lib.s9s_mb_2u(sch_1):page78_i8@pure_quanta.q_cap(chips)',
 PATH='I8',
 DRAWING='@S9S_MB_2U_LIB.S9S_MB_2U(SCH_1):PAGE78',
 PHYS_PAGE='78',
 XY='(-4450,-1250)',
 ROT='0',
 VER='1',
 PACK_TYPE='C0805',
 CDS_LIB='pure_quanta',
 CDS_PART_NAME='Q_CAP_C0805-47UF,4V,20%,X6S,CHA',
 TOLERANCE='20%',
 MATERIAL='X6S',
 VOLTAGE='4V',
 VALUE='47UF',
 PRIM_FILE='./archive_libs/logical/q_cap/chips/chips.prt';

PART_NAME
 C479 'Q_CAP_C0805-47UF,4V,20%,X6S,CHA':;

SECTION_NUMBER 1
 '@S9S_MB_2U_LIB.S9S_MB_2U(SCH_1):PAGE79_I39@PURE_QUANTA.Q_CAP(CHIPS)':
 C_PATH='@s9s_mb_2u_lib.s9s_mb_2u(sch_1):page79_i39@pure_quanta.q_cap(chips)',
 P_PATH='@s9s_mb_2u_lib.s9s_mb_2u(sch_1):page79_i39@pure_quanta.q_cap(chips)',
 PATH='I39',
 DRAWING='@S9S_MB_2U_LIB.S9S_MB_2U(SCH_1):PAGE79',
 PHYS_PAGE='79',
 XY='(-375,-2375)',
 ROT='0',
 VER='1',
 PACK_TYPE='C0805',
 CDS_LIB='pure_quanta',
 CDS_PART_NAME='Q_CAP_C0805-47UF,4V,20%,X6S,CHA',
 TOLERANCE='20%',
 MATERIAL='X6S',
 VOLTAGE='4V',
 VALUE='47UF',
 PRIM_FILE='./archive_libs/logical/q_cap/chips/chips.prt';

PART_NAME
 C481 'Q_CAP_C0805-47UF,4V,20%,X6S,CHA':;

SECTION_NUMBER 1
 '@S9S_MB_2U_LIB.S9S_MB_2U(SCH_1):PAGE79_I13@PURE_QUANTA.Q_CAP(CHIPS)':
 C_PATH='@s9s_mb_2u_lib.s9s_mb_2u(sch_1):page79_i13@pure_quanta.q_cap(chips)',
 P_PATH='@s9s_mb_2u_lib.s9s_mb_2u(sch_1):page79_i13@pure_quanta.q_cap(chips)',
 PATH='I13',
 DRAWING='@S9S_MB_2U_LIB.S9S_MB_2U(SCH_1):PAGE79',
 PHYS_PAGE='79',
 XY='(-4425,-1400)',
 ROT='0',
 VER='1',
 PACK_TYPE='C0805',
 CDS_LIB='pure_quanta',
 CDS_PART_NAME='Q_CAP_C0805-47UF,4V,20%,X6S,CHA',
 TOLERANCE='20%',
 MATERIAL='X6S',
 VOLTAGE='4V',
 VALUE='47UF',
 PRIM_FILE='./archive_libs/logical/q_cap/chips/chips.prt';

PART_NAME
 C482 'Q_CAP_C0805-47UF,4V,20%,X6S,CHA':;

SECTION_NUMBER 1
 '@S9S_MB_2U_LIB.S9S_MB_2U(SCH_1):PAGE79_I41@PURE_QUANTA.Q_CAP(CHIPS)':
 C_PATH='@s9s_mb_2u_lib.s9s_mb_2u(sch_1):page79_i41@pure_quanta.q_cap(chips)',
 P_PATH='@s9s_mb_2u_lib.s9s_mb_2u(sch_1):page79_i41@pure_quanta.q_cap(chips)',
 PATH='I41',
 DRAWING='@S9S_MB_2U_LIB.S9S_MB_2U(SCH_1):PAGE79',
 PHYS_PAGE='79',
 XY='(75,-2375)',
 ROT='0',
 VER='1',
 PACK_TYPE='C0805',
 CDS_LIB='pure_quanta',
 CDS_PART_NAME='Q_CAP_C0805-47UF,4V,20%,X6S,CHA',
 TOLERANCE='20%',
 MATERIAL='X6S',
 VOLTAGE='4V',
 VALUE='47UF',
 PRIM_FILE='./archive_libs/logical/q_cap/chips/chips.prt';

PART_NAME
 C483 'Q_CAP_C0805-47UF,4V,20%,X6S,CHA':;

SECTION_NUMBER 1
 '@S9S_MB_2U_LIB.S9S_MB_2U(SCH_1):PAGE78_I68@PURE_QUANTA.Q_CAP(CHIPS)':
 C_PATH='@s9s_mb_2u_lib.s9s_mb_2u(sch_1):page78_i68@pure_quanta.q_cap(chips)',
 P_PATH='@s9s_mb_2u_lib.s9s_mb_2u(sch_1):page78_i68@pure_quanta.q_cap(chips)',
 PATH='I68',
 DRAWING='@S9S_MB_2U_LIB.S9S_MB_2U(SCH_1):PAGE78',
 PHYS_PAGE='78',
 XY='(2275,2400)',
 ROT='0',
 VER='1',
 PACK_TYPE='C0805',
 CDS_LIB='pure_quanta',
 CDS_PART_NAME='Q_CAP_C0805-47UF,4V,20%,X6S,CHA',
 TOLERANCE='20%',
 MATERIAL='X6S',
 VOLTAGE='4V',
 VALUE='47UF',
 PRIM_FILE='./archive_libs/logical/q_cap/chips/chips.prt';

PART_NAME
 C484 'Q_CAP_C0805-47UF,4V,20%,X6S,CHA':;

SECTION_NUMBER 1
 '@S9S_MB_2U_LIB.S9S_MB_2U(SCH_1):PAGE79_I12@PURE_QUANTA.Q_CAP(CHIPS)':
 C_PATH='@s9s_mb_2u_lib.s9s_mb_2u(sch_1):page79_i12@pure_quanta.q_cap(chips)',
 P_PATH='@s9s_mb_2u_lib.s9s_mb_2u(sch_1):page79_i12@pure_quanta.q_cap(chips)',
 PATH='I12',
 DRAWING='@S9S_MB_2U_LIB.S9S_MB_2U(SCH_1):PAGE79',
 PHYS_PAGE='79',
 XY='(-3975,-1400)',
 ROT='0',
 VER='1',
 PACK_TYPE='C0805',
 CDS_LIB='pure_quanta',
 CDS_PART_NAME='Q_CAP_C0805-47UF,4V,20%,X6S,CHA',
 TOLERANCE='20%',
 MATERIAL='X6S',
 VOLTAGE='4V',
 VALUE='47UF',
 PRIM_FILE='./archive_libs/logical/q_cap/chips/chips.prt';

PART_NAME
 C485 'Q_CAP_C0805-47UF,4V,20%,X6S,CHA':;

SECTION_NUMBER 1
 '@S9S_MB_2U_LIB.S9S_MB_2U(SCH_1):PAGE79_I42@PURE_QUANTA.Q_CAP(CHIPS)':
 C_PATH='@s9s_mb_2u_lib.s9s_mb_2u(sch_1):page79_i42@pure_quanta.q_cap(chips)',
 P_PATH='@s9s_mb_2u_lib.s9s_mb_2u(sch_1):page79_i42@pure_quanta.q_cap(chips)',
 PATH='I42',
 DRAWING='@S9S_MB_2U_LIB.S9S_MB_2U(SCH_1):PAGE79',
 PHYS_PAGE='79',
 XY='(525,-2375)',
 ROT='0',
 VER='1',
 PACK_TYPE='C0805',
 CDS_LIB='pure_quanta',
 CDS_PART_NAME='Q_CAP_C0805-47UF,4V,20%,X6S,CHA',
 TOLERANCE='20%',
 MATERIAL='X6S',
 VOLTAGE='4V',
 VALUE='47UF',
 PRIM_FILE='./archive_libs/logical/q_cap/chips/chips.prt';

PART_NAME
 C486 'Q_CAP_C0805-47UF,4V,20%,X6S,CHA':;

SECTION_NUMBER 1
 '@S9S_MB_2U_LIB.S9S_MB_2U(SCH_1):PAGE79_I11@PURE_QUANTA.Q_CAP(CHIPS)':
 C_PATH='@s9s_mb_2u_lib.s9s_mb_2u(sch_1):page79_i11@pure_quanta.q_cap(chips)',
 P_PATH='@s9s_mb_2u_lib.s9s_mb_2u(sch_1):page79_i11@pure_quanta.q_cap(chips)',
 PATH='I11',
 DRAWING='@S9S_MB_2U_LIB.S9S_MB_2U(SCH_1):PAGE79',
 PHYS_PAGE='79',
 XY='(-3525,-1400)',
 ROT='0',
 VER='1',
 PACK_TYPE='C0805',
 CDS_LIB='pure_quanta',
 CDS_PART_NAME='Q_CAP_C0805-47UF,4V,20%,X6S,CHA',
 TOLERANCE='20%',
 MATERIAL='X6S',
 VOLTAGE='4V',
 VALUE='47UF',
 PRIM_FILE='./archive_libs/logical/q_cap/chips/chips.prt';

PART_NAME
 C487 'Q_CAP_C0805-47UF,4V,20%,X6S,CHA':;

SECTION_NUMBER 1
 '@S9S_MB_2U_LIB.S9S_MB_2U(SCH_1):PAGE79_I10@PURE_QUANTA.Q_CAP(CHIPS)':
 C_PATH='@s9s_mb_2u_lib.s9s_mb_2u(sch_1):page79_i10@pure_quanta.q_cap(chips)',
 P_PATH='@s9s_mb_2u_lib.s9s_mb_2u(sch_1):page79_i10@pure_quanta.q_cap(chips)',
 PATH='I10',
 DRAWING='@S9S_MB_2U_LIB.S9S_MB_2U(SCH_1):PAGE79',
 PHYS_PAGE='79',
 XY='(-3075,-1400)',
 ROT='0',
 VER='1',
 PACK_TYPE='C0805',
 CDS_LIB='pure_quanta',
 CDS_PART_NAME='Q_CAP_C0805-47UF,4V,20%,X6S,CHA',
 TOLERANCE='20%',
 MATERIAL='X6S',
 VOLTAGE='4V',
 VALUE='47UF',
 PRIM_FILE='./archive_libs/logical/q_cap/chips/chips.prt';

PART_NAME
 C488 'Q_CAP_C0603-47UF,2.5V,20%,X6S,A':;

SECTION_NUMBER 1
 '@S9S_MB_2U_LIB.S9S_MB_2U(SCH_1):PAGE78_I18@PURE_QUANTA.Q_CAP(CHIPS)':
 C_PATH='@s9s_mb_2u_lib.s9s_mb_2u(sch_1):page78_i18@pure_quanta.q_cap(chips)',
 P_PATH='@s9s_mb_2u_lib.s9s_mb_2u(sch_1):page78_i18@pure_quanta.q_cap(chips)',
 PATH='I18',
 DRAWING='@S9S_MB_2U_LIB.S9S_MB_2U(SCH_1):PAGE78',
 PHYS_PAGE='78',
 XY='(-4000,-1250)',
 ROT='0',
 VER='1',
 PACK_TYPE='C0603',
 CDS_LIB='pure_quanta',
 CDS_PART_NAME='Q_CAP_C0603-47UF,2.5V,20%,X6S,A',
 TOLERANCE='20%',
 MATERIAL='X6S',
 VOLTAGE='2.5V',
 VALUE='47UF',
 PRIM_FILE='./archive_libs/logical/q_cap/chips/chips.prt';

PART_NAME
 C489 'Q_CAP_C0603-47UF,2.5V,20%,X6S,A':;

SECTION_NUMBER 1
 '@S9S_MB_2U_LIB.S9S_MB_2U(SCH_1):PAGE78_I19@PURE_QUANTA.Q_CAP(CHIPS)':
 C_PATH='@s9s_mb_2u_lib.s9s_mb_2u(sch_1):page78_i19@pure_quanta.q_cap(chips)',
 P_PATH='@s9s_mb_2u_lib.s9s_mb_2u(sch_1):page78_i19@pure_quanta.q_cap(chips)',
 PATH='I19',
 DRAWING='@S9S_MB_2U_LIB.S9S_MB_2U(SCH_1):PAGE78',
 PHYS_PAGE='78',
 XY='(-3550,-1250)',
 ROT='0',
 VER='1',
 PACK_TYPE='C0603',
 CDS_LIB='pure_quanta',
 CDS_PART_NAME='Q_CAP_C0603-47UF,2.5V,20%,X6S,A',
 TOLERANCE='20%',
 MATERIAL='X6S',
 VOLTAGE='2.5V',
 VALUE='47UF',
 PRIM_FILE='./archive_libs/logical/q_cap/chips/chips.prt';

PART_NAME
 C490 'Q_CAP_C0402-22UF,4V,20%,X6S,CHA':;

SECTION_NUMBER 1
 '@S9S_MB_2U_LIB.S9S_MB_2U(SCH_1):PAGE78_I23@PURE_QUANTA.Q_CAP(CHIPS)':
 C_PATH='@s9s_mb_2u_lib.s9s_mb_2u(sch_1):page78_i23@pure_quanta.q_cap(chips)',
 P_PATH='@s9s_mb_2u_lib.s9s_mb_2u(sch_1):page78_i23@pure_quanta.q_cap(chips)',
 PATH='I23',
 DRAWING='@S9S_MB_2U_LIB.S9S_MB_2U(SCH_1):PAGE78',
 PHYS_PAGE='78',
 XY='(-3100,-1250)',
 ROT='0',
 VER='1',
 PACK_TYPE='C0402',
 CDS_LIB='pure_quanta',
 CDS_PART_NAME='Q_CAP_C0402-22UF,4V,20%,X6S,CHA',
 TOLERANCE='20%',
 MATERIAL='X6S',
 VOLTAGE='4V',
 VALUE='22UF',
 PRIM_FILE='./archive_libs/logical/q_cap/chips/chips.prt';

PART_NAME
 C491 'Q_CAP_C0805-47UF,4V,20%,X6S,CHA':;

SECTION_NUMBER 1
 '@S9S_MB_2U_LIB.S9S_MB_2U(SCH_1):PAGE75_I13@PURE_QUANTA.Q_CAP(CHIPS)':
 C_PATH='@s9s_mb_2u_lib.s9s_mb_2u(sch_1):page75_i13@pure_quanta.q_cap(chips)',
 P_PATH='@s9s_mb_2u_lib.s9s_mb_2u(sch_1):page75_i13@pure_quanta.q_cap(chips)',
 PATH='I13',
 DRAWING='@S9S_MB_2U_LIB.S9S_MB_2U(SCH_1):PAGE75',
 PHYS_PAGE='75',
 XY='(-4425,725)',
 ROT='0',
 VER='1',
 PACK_TYPE='C0805',
 CDS_LIB='pure_quanta',
 CDS_PART_NAME='Q_CAP_C0805-47UF,4V,20%,X6S,CHA',
 TOLERANCE='20%',
 MATERIAL='X6S',
 VOLTAGE='4V',
 VALUE='47UF',
 PRIM_FILE='./archive_libs/logical/q_cap/chips/chips.prt';

PART_NAME
 C492 'Q_CAP_C0805-47UF,4V,20%,X6S,CHA':;

SECTION_NUMBER 1
 '@S9S_MB_2U_LIB.S9S_MB_2U(SCH_1):PAGE75_I11@PURE_QUANTA.Q_CAP(CHIPS)':
 C_PATH='@s9s_mb_2u_lib.s9s_mb_2u(sch_1):page75_i11@pure_quanta.q_cap(chips)',
 P_PATH='@s9s_mb_2u_lib.s9s_mb_2u(sch_1):page75_i11@pure_quanta.q_cap(chips)',
 PATH='I11',
 DRAWING='@S9S_MB_2U_LIB.S9S_MB_2U(SCH_1):PAGE75',
 PHYS_PAGE='75',
 XY='(-4425,-250)',
 ROT='0',
 VER='1',
 PACK_TYPE='C0805',
 CDS_LIB='pure_quanta',
 CDS_PART_NAME='Q_CAP_C0805-47UF,4V,20%,X6S,CHA',
 TOLERANCE='20%',
 MATERIAL='X6S',
 VOLTAGE='4V',
 VALUE='47UF',
 PRIM_FILE='./archive_libs/logical/q_cap/chips/chips.prt';

PART_NAME
 C493 'Q_CAP_C0805-47UF,4V,20%,X6S,CHA':;

SECTION_NUMBER 1
 '@S9S_MB_2U_LIB.S9S_MB_2U(SCH_1):PAGE75_I1@PURE_QUANTA.Q_CAP(CHIPS)':
 C_PATH='@s9s_mb_2u_lib.s9s_mb_2u(sch_1):page75_i1@pure_quanta.q_cap(chips)',
 P_PATH='@s9s_mb_2u_lib.s9s_mb_2u(sch_1):page75_i1@pure_quanta.q_cap(chips)',
 PATH='I1',
 DRAWING='@S9S_MB_2U_LIB.S9S_MB_2U(SCH_1):PAGE75',
 PHYS_PAGE='75',
 XY='(-4425,-2225)',
 ROT='0',
 VER='1',
 PACK_TYPE='C0805',
 CDS_LIB='pure_quanta',
 CDS_PART_NAME='Q_CAP_C0805-47UF,4V,20%,X6S,CHA',
 TOLERANCE='20%',
 MATERIAL='X6S',
 VOLTAGE='4V',
 VALUE='47UF',
 PRIM_FILE='./archive_libs/logical/q_cap/chips/chips.prt';

PART_NAME
 C494 'Q_CAP_C0805-47UF,4V,20%,X6S,CHA':;

SECTION_NUMBER 1
 '@S9S_MB_2U_LIB.S9S_MB_2U(SCH_1):PAGE76_I1@PURE_QUANTA.Q_CAP(CHIPS)':
 C_PATH='@s9s_mb_2u_lib.s9s_mb_2u(sch_1):page76_i1@pure_quanta.q_cap(chips)',
 P_PATH='@s9s_mb_2u_lib.s9s_mb_2u(sch_1):page76_i1@pure_quanta.q_cap(chips)',
 PATH='I1',
 DRAWING='@S9S_MB_2U_LIB.S9S_MB_2U(SCH_1):PAGE76',
 PHYS_PAGE='76',
 XY='(-3925,4025)',
 ROT='0',
 VER='1',
 PACK_TYPE='C0805',
 CDS_LIB='pure_quanta',
 CDS_PART_NAME='Q_CAP_C0805-47UF,4V,20%,X6S,CHA',
 TOLERANCE='20%',
 MATERIAL='X6S',
 VOLTAGE='4V',
 VALUE='47UF',
 PRIM_FILE='./archive_libs/logical/q_cap/chips/chips.prt';

PART_NAME
 C495 'Q_CAP_C0805-47UF,4V,20%,X6S,CHA':;

SECTION_NUMBER 1
 '@S9S_MB_2U_LIB.S9S_MB_2U(SCH_1):PAGE75_I18@PURE_QUANTA.Q_CAP(CHIPS)':
 C_PATH='@s9s_mb_2u_lib.s9s_mb_2u(sch_1):page75_i18@pure_quanta.q_cap(chips)',
 P_PATH='@s9s_mb_2u_lib.s9s_mb_2u(sch_1):page75_i18@pure_quanta.q_cap(chips)',
 PATH='I18',
 DRAWING='@S9S_MB_2U_LIB.S9S_MB_2U(SCH_1):PAGE75',
 PHYS_PAGE='75',
 XY='(-3975,725)',
 ROT='0',
 VER='1',
 PACK_TYPE='C0805',
 CDS_LIB='pure_quanta',
 CDS_PART_NAME='Q_CAP_C0805-47UF,4V,20%,X6S,CHA',
 TOLERANCE='20%',
 MATERIAL='X6S',
 VOLTAGE='4V',
 VALUE='47UF',
 PRIM_FILE='./archive_libs/logical/q_cap/chips/chips.prt';

PART_NAME
 C496 'Q_CAP_C0805-47UF,4V,20%,X6S,CHA':;

SECTION_NUMBER 1
 '@S9S_MB_2U_LIB.S9S_MB_2U(SCH_1):PAGE75_I16@PURE_QUANTA.Q_CAP(CHIPS)':
 C_PATH='@s9s_mb_2u_lib.s9s_mb_2u(sch_1):page75_i16@pure_quanta.q_cap(chips)',
 P_PATH='@s9s_mb_2u_lib.s9s_mb_2u(sch_1):page75_i16@pure_quanta.q_cap(chips)',
 PATH='I16',
 DRAWING='@S9S_MB_2U_LIB.S9S_MB_2U(SCH_1):PAGE75',
 PHYS_PAGE='75',
 XY='(-3975,-250)',
 ROT='0',
 VER='1',
 PACK_TYPE='C0805',
 CDS_LIB='pure_quanta',
 CDS_PART_NAME='Q_CAP_C0805-47UF,4V,20%,X6S,CHA',
 TOLERANCE='20%',
 MATERIAL='X6S',
 VOLTAGE='4V',
 VALUE='47UF',
 PRIM_FILE='./archive_libs/logical/q_cap/chips/chips.prt';

PART_NAME
 C497 'Q_CAP_C0805-47UF,4V,20%,X6S,CHA':;

SECTION_NUMBER 1
 '@S9S_MB_2U_LIB.S9S_MB_2U(SCH_1):PAGE75_I3@PURE_QUANTA.Q_CAP(CHIPS)':
 C_PATH='@s9s_mb_2u_lib.s9s_mb_2u(sch_1):page75_i3@pure_quanta.q_cap(chips)',
 P_PATH='@s9s_mb_2u_lib.s9s_mb_2u(sch_1):page75_i3@pure_quanta.q_cap(chips)',
 PATH='I3',
 DRAWING='@S9S_MB_2U_LIB.S9S_MB_2U(SCH_1):PAGE75',
 PHYS_PAGE='75',
 XY='(-3975,-2225)',
 ROT='0',
 VER='1',
 PACK_TYPE='C0805',
 CDS_LIB='pure_quanta',
 CDS_PART_NAME='Q_CAP_C0805-47UF,4V,20%,X6S,CHA',
 TOLERANCE='20%',
 MATERIAL='X6S',
 VOLTAGE='4V',
 VALUE='47UF',
 PRIM_FILE='./archive_libs/logical/q_cap/chips/chips.prt';

PART_NAME
 C498 'Q_CAP_C0805-47UF,4V,20%,X6S,CHA':;

SECTION_NUMBER 1
 '@S9S_MB_2U_LIB.S9S_MB_2U(SCH_1):PAGE76_I2@PURE_QUANTA.Q_CAP(CHIPS)':
 C_PATH='@s9s_mb_2u_lib.s9s_mb_2u(sch_1):page76_i2@pure_quanta.q_cap(chips)',
 P_PATH='@s9s_mb_2u_lib.s9s_mb_2u(sch_1):page76_i2@pure_quanta.q_cap(chips)',
 PATH='I2',
 DRAWING='@S9S_MB_2U_LIB.S9S_MB_2U(SCH_1):PAGE76',
 PHYS_PAGE='76',
 XY='(-3475,4025)',
 ROT='0',
 VER='1',
 PACK_TYPE='C0805',
 CDS_LIB='pure_quanta',
 CDS_PART_NAME='Q_CAP_C0805-47UF,4V,20%,X6S,CHA',
 TOLERANCE='20%',
 MATERIAL='X6S',
 VOLTAGE='4V',
 VALUE='47UF',
 PRIM_FILE='./archive_libs/logical/q_cap/chips/chips.prt';

PART_NAME
 C499 'Q_CAP_C0805-47UF,4V,20%,X6S,CHA':;

SECTION_NUMBER 1
 '@S9S_MB_2U_LIB.S9S_MB_2U(SCH_1):PAGE76_I18@PURE_QUANTA.Q_CAP(CHIPS)':
 C_PATH='@s9s_mb_2u_lib.s9s_mb_2u(sch_1):page76_i18@pure_quanta.q_cap(chips)',
 P_PATH='@s9s_mb_2u_lib.s9s_mb_2u(sch_1):page76_i18@pure_quanta.q_cap(chips)',
 PATH='I18',
 DRAWING='@S9S_MB_2U_LIB.S9S_MB_2U(SCH_1):PAGE76',
 PHYS_PAGE='76',
 XY='(-3925,7950)',
 ROT='0',
 VER='1',
 PACK_TYPE='C0805',
 CDS_LIB='pure_quanta',
 CDS_PART_NAME='Q_CAP_C0805-47UF,4V,20%,X6S,CHA',
 TOLERANCE='20%',
 MATERIAL='X6S',
 VOLTAGE='4V',
 VALUE='47UF',
 PRIM_FILE='./archive_libs/logical/q_cap/chips/chips.prt';

PART_NAME
 C500 'Q_CAP_C0805-47UF,4V,20%,X6S,CHA':;

SECTION_NUMBER 1
 '@S9S_MB_2U_LIB.S9S_MB_2U(SCH_1):PAGE76_I9@PURE_QUANTA.Q_CAP(CHIPS)':
 C_PATH='@s9s_mb_2u_lib.s9s_mb_2u(sch_1):page76_i9@pure_quanta.q_cap(chips)',
 P_PATH='@s9s_mb_2u_lib.s9s_mb_2u(sch_1):page76_i9@pure_quanta.q_cap(chips)',
 PATH='I9',
 DRAWING='@S9S_MB_2U_LIB.S9S_MB_2U(SCH_1):PAGE76',
 PHYS_PAGE='76',
 XY='(-3925,6100)',
 ROT='0',
 VER='1',
 PACK_TYPE='C0805',
 CDS_LIB='pure_quanta',
 CDS_PART_NAME='Q_CAP_C0805-47UF,4V,20%,X6S,CHA',
 TOLERANCE='20%',
 MATERIAL='X6S',
 VOLTAGE='4V',
 VALUE='47UF',
 PRIM_FILE='./archive_libs/logical/q_cap/chips/chips.prt';

PART_NAME
 C501 'Q_CAP_C0805-47UF,4V,20%,X6S,CHA':;

SECTION_NUMBER 1
 '@S9S_MB_2U_LIB.S9S_MB_2U(SCH_1):PAGE75_I4@PURE_QUANTA.Q_CAP(CHIPS)':
 C_PATH='@s9s_mb_2u_lib.s9s_mb_2u(sch_1):page75_i4@pure_quanta.q_cap(chips)',
 P_PATH='@s9s_mb_2u_lib.s9s_mb_2u(sch_1):page75_i4@pure_quanta.q_cap(chips)',
 PATH='I4',
 DRAWING='@S9S_MB_2U_LIB.S9S_MB_2U(SCH_1):PAGE75',
 PHYS_PAGE='75',
 XY='(-3525,-2225)',
 ROT='0',
 VER='1',
 PACK_TYPE='C0805',
 CDS_LIB='pure_quanta',
 CDS_PART_NAME='Q_CAP_C0805-47UF,4V,20%,X6S,CHA',
 TOLERANCE='20%',
 MATERIAL='X6S',
 VOLTAGE='4V',
 VALUE='47UF',
 PRIM_FILE='./archive_libs/logical/q_cap/chips/chips.prt';

PART_NAME
 C502 'Q_CAP_C0805-47UF,4V,20%,X6S,CHA':;

SECTION_NUMBER 1
 '@S9S_MB_2U_LIB.S9S_MB_2U(SCH_1):PAGE76_I3@PURE_QUANTA.Q_CAP(CHIPS)':
 C_PATH='@s9s_mb_2u_lib.s9s_mb_2u(sch_1):page76_i3@pure_quanta.q_cap(chips)',
 P_PATH='@s9s_mb_2u_lib.s9s_mb_2u(sch_1):page76_i3@pure_quanta.q_cap(chips)',
 PATH='I3',
 DRAWING='@S9S_MB_2U_LIB.S9S_MB_2U(SCH_1):PAGE76',
 PHYS_PAGE='76',
 XY='(-3025,4025)',
 ROT='0',
 VER='1',
 PACK_TYPE='C0805',
 CDS_LIB='pure_quanta',
 CDS_PART_NAME='Q_CAP_C0805-47UF,4V,20%,X6S,CHA',
 TOLERANCE='20%',
 MATERIAL='X6S',
 VOLTAGE='4V',
 VALUE='47UF',
 PRIM_FILE='./archive_libs/logical/q_cap/chips/chips.prt';

PART_NAME
 C503 'Q_CAP_C0805-47UF,4V,20%,X6S,CHA':;

SECTION_NUMBER 1
 '@S9S_MB_2U_LIB.S9S_MB_2U(SCH_1):PAGE76_I20@PURE_QUANTA.Q_CAP(CHIPS)':
 C_PATH='@s9s_mb_2u_lib.s9s_mb_2u(sch_1):page76_i20@pure_quanta.q_cap(chips)',
 P_PATH='@s9s_mb_2u_lib.s9s_mb_2u(sch_1):page76_i20@pure_quanta.q_cap(chips)',
 PATH='I20',
 DRAWING='@S9S_MB_2U_LIB.S9S_MB_2U(SCH_1):PAGE76',
 PHYS_PAGE='76',
 XY='(-3475,7950)',
 ROT='0',
 VER='1',
 PACK_TYPE='C0805',
 CDS_LIB='pure_quanta',
 CDS_PART_NAME='Q_CAP_C0805-47UF,4V,20%,X6S,CHA',
 TOLERANCE='20%',
 MATERIAL='X6S',
 VOLTAGE='4V',
 VALUE='47UF',
 PRIM_FILE='./archive_libs/logical/q_cap/chips/chips.prt';

PART_NAME
 C504 'Q_CAP_C0805-47UF,4V,20%,X6S,CHA':;

SECTION_NUMBER 1
 '@S9S_MB_2U_LIB.S9S_MB_2U(SCH_1):PAGE76_I10@PURE_QUANTA.Q_CAP(CHIPS)':
 C_PATH='@s9s_mb_2u_lib.s9s_mb_2u(sch_1):page76_i10@pure_quanta.q_cap(chips)',
 P_PATH='@s9s_mb_2u_lib.s9s_mb_2u(sch_1):page76_i10@pure_quanta.q_cap(chips)',
 PATH='I10',
 DRAWING='@S9S_MB_2U_LIB.S9S_MB_2U(SCH_1):PAGE76',
 PHYS_PAGE='76',
 XY='(-3475,6100)',
 ROT='0',
 VER='1',
 PACK_TYPE='C0805',
 CDS_LIB='pure_quanta',
 CDS_PART_NAME='Q_CAP_C0805-47UF,4V,20%,X6S,CHA',
 TOLERANCE='20%',
 MATERIAL='X6S',
 VOLTAGE='4V',
 VALUE='47UF',
 PRIM_FILE='./archive_libs/logical/q_cap/chips/chips.prt';

PART_NAME
 C505 'Q_CAP_C0805-47UF,4V,20%,X6S,CHA':;

SECTION_NUMBER 1
 '@S9S_MB_2U_LIB.S9S_MB_2U(SCH_1):PAGE75_I6@PURE_QUANTA.Q_CAP(CHIPS)':
 C_PATH='@s9s_mb_2u_lib.s9s_mb_2u(sch_1):page75_i6@pure_quanta.q_cap(chips)',
 P_PATH='@s9s_mb_2u_lib.s9s_mb_2u(sch_1):page75_i6@pure_quanta.q_cap(chips)',
 PATH='I6',
 DRAWING='@S9S_MB_2U_LIB.S9S_MB_2U(SCH_1):PAGE75',
 PHYS_PAGE='75',
 XY='(-3075,-2225)',
 ROT='0',
 VER='1',
 PACK_TYPE='C0805',
 CDS_LIB='pure_quanta',
 CDS_PART_NAME='Q_CAP_C0805-47UF,4V,20%,X6S,CHA',
 TOLERANCE='20%',
 MATERIAL='X6S',
 VOLTAGE='4V',
 VALUE='47UF',
 PRIM_FILE='./archive_libs/logical/q_cap/chips/chips.prt';

PART_NAME
 C506 'Q_CAP_C0805-47UF,4V,20%,X6S,CHA':;

SECTION_NUMBER 1
 '@S9S_MB_2U_LIB.S9S_MB_2U(SCH_1):PAGE76_I26@PURE_QUANTA.Q_CAP(CHIPS)':
 C_PATH='@s9s_mb_2u_lib.s9s_mb_2u(sch_1):page76_i26@pure_quanta.q_cap(chips)',
 P_PATH='@s9s_mb_2u_lib.s9s_mb_2u(sch_1):page76_i26@pure_quanta.q_cap(chips)',
 PATH='I26',
 DRAWING='@S9S_MB_2U_LIB.S9S_MB_2U(SCH_1):PAGE76',
 PHYS_PAGE='76',
 XY='(-2575,4025)',
 ROT='0',
 VER='1',
 PACK_TYPE='C0805',
 CDS_LIB='pure_quanta',
 CDS_PART_NAME='Q_CAP_C0805-47UF,4V,20%,X6S,CHA',
 TOLERANCE='20%',
 MATERIAL='X6S',
 VOLTAGE='4V',
 VALUE='47UF',
 PRIM_FILE='./archive_libs/logical/q_cap/chips/chips.prt';

PART_NAME
 C507 'Q_CAP_C0805-47UF,4V,20%,X6S,CHA':;

SECTION_NUMBER 1
 '@S9S_MB_2U_LIB.S9S_MB_2U(SCH_1):PAGE76_I21@PURE_QUANTA.Q_CAP(CHIPS)':
 C_PATH='@s9s_mb_2u_lib.s9s_mb_2u(sch_1):page76_i21@pure_quanta.q_cap(chips)',
 P_PATH='@s9s_mb_2u_lib.s9s_mb_2u(sch_1):page76_i21@pure_quanta.q_cap(chips)',
 PATH='I21',
 DRAWING='@S9S_MB_2U_LIB.S9S_MB_2U(SCH_1):PAGE76',
 PHYS_PAGE='76',
 XY='(-3025,7950)',
 ROT='0',
 VER='1',
 PACK_TYPE='C0805',
 CDS_LIB='pure_quanta',
 CDS_PART_NAME='Q_CAP_C0805-47UF,4V,20%,X6S,CHA',
 TOLERANCE='20%',
 MATERIAL='X6S',
 VOLTAGE='4V',
 VALUE='47UF',
 PRIM_FILE='./archive_libs/logical/q_cap/chips/chips.prt';

PART_NAME
 C508 'Q_CAP_C0805-47UF,4V,20%,X6S,CHA':;

SECTION_NUMBER 1
 '@S9S_MB_2U_LIB.S9S_MB_2U(SCH_1):PAGE76_I11@PURE_QUANTA.Q_CAP(CHIPS)':
 C_PATH='@s9s_mb_2u_lib.s9s_mb_2u(sch_1):page76_i11@pure_quanta.q_cap(chips)',
 P_PATH='@s9s_mb_2u_lib.s9s_mb_2u(sch_1):page76_i11@pure_quanta.q_cap(chips)',
 PATH='I11',
 DRAWING='@S9S_MB_2U_LIB.S9S_MB_2U(SCH_1):PAGE76',
 PHYS_PAGE='76',
 XY='(-3025,6100)',
 ROT='0',
 VER='1',
 PACK_TYPE='C0805',
 CDS_LIB='pure_quanta',
 CDS_PART_NAME='Q_CAP_C0805-47UF,4V,20%,X6S,CHA',
 TOLERANCE='20%',
 MATERIAL='X6S',
 VOLTAGE='4V',
 VALUE='47UF',
 PRIM_FILE='./archive_libs/logical/q_cap/chips/chips.prt';

PART_NAME
 C509 'Q_CAP_C0603-47UF,2.5V,20%,X6S,A':;

SECTION_NUMBER 1
 '@S9S_MB_2U_LIB.S9S_MB_2U(SCH_1):PAGE75_I8@PURE_QUANTA.Q_CAP(CHIPS)':
 C_PATH='@s9s_mb_2u_lib.s9s_mb_2u(sch_1):page75_i8@pure_quanta.q_cap(chips)',
 P_PATH='@s9s_mb_2u_lib.s9s_mb_2u(sch_1):page75_i8@pure_quanta.q_cap(chips)',
 PATH='I8',
 DRAWING='@S9S_MB_2U_LIB.S9S_MB_2U(SCH_1):PAGE75',
 PHYS_PAGE='75',
 XY='(-2625,-2225)',
 ROT='0',
 VER='1',
 PACK_TYPE='C0603',
 CDS_LIB='pure_quanta',
 CDS_PART_NAME='Q_CAP_C0603-47UF,2.5V,20%,X6S,A',
 TOLERANCE='20%',
 MATERIAL='X6S',
 VOLTAGE='2.5V',
 VALUE='47UF',
 PRIM_FILE='./archive_libs/logical/q_cap/chips/chips.prt';

PART_NAME
 C510 'Q_CAP_C0805-47UF,4V,20%,X6S,CHA':;

SECTION_NUMBER 1
 '@S9S_MB_2U_LIB.S9S_MB_2U(SCH_1):PAGE76_I27@PURE_QUANTA.Q_CAP(CHIPS)':
 C_PATH='@s9s_mb_2u_lib.s9s_mb_2u(sch_1):page76_i27@pure_quanta.q_cap(chips)',
 P_PATH='@s9s_mb_2u_lib.s9s_mb_2u(sch_1):page76_i27@pure_quanta.q_cap(chips)',
 PATH='I27',
 DRAWING='@S9S_MB_2U_LIB.S9S_MB_2U(SCH_1):PAGE76',
 PHYS_PAGE='76',
 XY='(-2125,4025)',
 ROT='0',
 VER='1',
 PACK_TYPE='C0805',
 CDS_LIB='pure_quanta',
 CDS_PART_NAME='Q_CAP_C0805-47UF,4V,20%,X6S,CHA',
 TOLERANCE='20%',
 MATERIAL='X6S',
 VOLTAGE='4V',
 VALUE='47UF',
 PRIM_FILE='./archive_libs/logical/q_cap/chips/chips.prt';

PART_NAME
 C511 'Q_CAP_C0805-47UF,4V,20%,X6S,CHA':;

SECTION_NUMBER 1
 '@S9S_MB_2U_LIB.S9S_MB_2U(SCH_1):PAGE76_I43@PURE_QUANTA.Q_CAP(CHIPS)':
 C_PATH='@s9s_mb_2u_lib.s9s_mb_2u(sch_1):page76_i43@pure_quanta.q_cap(chips)',
 P_PATH='@s9s_mb_2u_lib.s9s_mb_2u(sch_1):page76_i43@pure_quanta.q_cap(chips)',
 PATH='I43',
 DRAWING='@S9S_MB_2U_LIB.S9S_MB_2U(SCH_1):PAGE76',
 PHYS_PAGE='76',
 XY='(-2575,7950)',
 ROT='0',
 VER='1',
 PACK_TYPE='C0805',
 CDS_LIB='pure_quanta',
 CDS_PART_NAME='Q_CAP_C0805-47UF,4V,20%,X6S,CHA',
 TOLERANCE='20%',
 MATERIAL='X6S',
 VOLTAGE='4V',
 VALUE='47UF',
 PRIM_FILE='./archive_libs/logical/q_cap/chips/chips.prt';

PART_NAME
 C512 'Q_CAP_C0805-47UF,4V,20%,X6S,CHA':;

SECTION_NUMBER 1
 '@S9S_MB_2U_LIB.S9S_MB_2U(SCH_1):PAGE76_I32@PURE_QUANTA.Q_CAP(CHIPS)':
 C_PATH='@s9s_mb_2u_lib.s9s_mb_2u(sch_1):page76_i32@pure_quanta.q_cap(chips)',
 P_PATH='@s9s_mb_2u_lib.s9s_mb_2u(sch_1):page76_i32@pure_quanta.q_cap(chips)',
 PATH='I32',
 DRAWING='@S9S_MB_2U_LIB.S9S_MB_2U(SCH_1):PAGE76',
 PHYS_PAGE='76',
 XY='(-2575,6100)',
 ROT='0',
 VER='1',
 PACK_TYPE='C0805',
 CDS_LIB='pure_quanta',
 CDS_PART_NAME='Q_CAP_C0805-47UF,4V,20%,X6S,CHA',
 TOLERANCE='20%',
 MATERIAL='X6S',
 VOLTAGE='4V',
 VALUE='47UF',
 PRIM_FILE='./archive_libs/logical/q_cap/chips/chips.prt';

PART_NAME
 C513 'Q_CAP_C0805-22UF,16V,20%,X6S,CA':;

SECTION_NUMBER 1
 '@S9S_MB_2U_LIB.S9S_MB_2U(SCH_1):PAGE243_I5@PURE_QUANTA.Q_CAP(CHIPS)':
 C_PATH='@s9s_mb_2u_lib.s9s_mb_2u(sch_1):page243_i5@pure_quanta.q_cap(chips)',
 P_PATH='@s9s_mb_2u_lib.s9s_mb_2u(sch_1):page257_i5@pure_quanta.q_cap(chips)',
 PATH='I5',
 DRAWING='@S9S_MB_2U_LIB.S9S_MB_2U(SCH_1):PAGE243',
 PHYS_PAGE='257',
 XY='(-4475,12450)',
 ROT='0',
 VER='1',
 PACK_TYPE='C0805',
 CDS_LIB='pure_quanta',
 CDS_PART_NAME='Q_CAP_C0805-22UF,16V,20%,X6S,CA',
 TOLERANCE='20%',
 MATERIAL='X6S',
 VOLTAGE='16V',
 VALUE='22UF',
 PRIM_FILE='./archive_libs/logical/q_cap/chips/chips.prt';

PART_NAME
 C514 'Q_CAP_C0805-47UF,4V,20%,X6S,CHA':;

SECTION_NUMBER 1
 '@S9S_MB_2U_LIB.S9S_MB_2U(SCH_1):PAGE76_I28@PURE_QUANTA.Q_CAP(CHIPS)':
 C_PATH='@s9s_mb_2u_lib.s9s_mb_2u(sch_1):page76_i28@pure_quanta.q_cap(chips)',
 P_PATH='@s9s_mb_2u_lib.s9s_mb_2u(sch_1):page76_i28@pure_quanta.q_cap(chips)',
 PATH='I28',
 DRAWING='@S9S_MB_2U_LIB.S9S_MB_2U(SCH_1):PAGE76',
 PHYS_PAGE='76',
 XY='(-1675,4025)',
 ROT='0',
 VER='1',
 PACK_TYPE='C0805',
 CDS_LIB='pure_quanta',
 CDS_PART_NAME='Q_CAP_C0805-47UF,4V,20%,X6S,CHA',
 TOLERANCE='20%',
 MATERIAL='X6S',
 VOLTAGE='4V',
 VALUE='47UF',
 PRIM_FILE='./archive_libs/logical/q_cap/chips/chips.prt';

PART_NAME
 C515 'Q_CAP_C0805-47UF,4V,20%,X6S,CHA':;

SECTION_NUMBER 1
 '@S9S_MB_2U_LIB.S9S_MB_2U(SCH_1):PAGE75_I19@PURE_QUANTA.Q_CAP(CHIPS)':
 C_PATH='@s9s_mb_2u_lib.s9s_mb_2u(sch_1):page75_i19@pure_quanta.q_cap(chips)',
 P_PATH='@s9s_mb_2u_lib.s9s_mb_2u(sch_1):page75_i19@pure_quanta.q_cap(chips)',
 PATH='I19',
 DRAWING='@S9S_MB_2U_LIB.S9S_MB_2U(SCH_1):PAGE75',
 PHYS_PAGE='75',
 XY='(-3525,725)',
 ROT='0',
 VER='1',
 PACK_TYPE='C0805',
 CDS_LIB='pure_quanta',
 CDS_PART_NAME='Q_CAP_C0805-47UF,4V,20%,X6S,CHA',
 TOLERANCE='20%',
 MATERIAL='X6S',
 VOLTAGE='4V',
 VALUE='47UF',
 PRIM_FILE='./archive_libs/logical/q_cap/chips/chips.prt';

PART_NAME
 C516 'Q_CAP_C0603-47UF,2.5V,20%,X6S,A':;

SECTION_NUMBER 1
 '@S9S_MB_2U_LIB.S9S_MB_2U(SCH_1):PAGE76_I33@PURE_QUANTA.Q_CAP(CHIPS)':
 C_PATH='@s9s_mb_2u_lib.s9s_mb_2u(sch_1):page76_i33@pure_quanta.q_cap(chips)',
 P_PATH='@s9s_mb_2u_lib.s9s_mb_2u(sch_1):page76_i33@pure_quanta.q_cap(chips)',
 PATH='I33',
 DRAWING='@S9S_MB_2U_LIB.S9S_MB_2U(SCH_1):PAGE76',
 PHYS_PAGE='76',
 XY='(-2125,6100)',
 ROT='0',
 VER='1',
 PACK_TYPE='C0603',
 CDS_LIB='pure_quanta',
 CDS_PART_NAME='Q_CAP_C0603-47UF,2.5V,20%,X6S,A',
 TOLERANCE='20%',
 MATERIAL='X6S',
 VOLTAGE='2.5V',
 VALUE='47UF',
 PRIM_FILE='./archive_libs/logical/q_cap/chips/chips.prt';

PART_NAME
 C517 'Q_CAP_C0805-47UF,4V,20%,X6S,CHA':;

SECTION_NUMBER 1
 '@S9S_MB_2U_LIB.S9S_MB_2U(SCH_1):PAGE76_I29@PURE_QUANTA.Q_CAP(CHIPS)':
 C_PATH='@s9s_mb_2u_lib.s9s_mb_2u(sch_1):page76_i29@pure_quanta.q_cap(chips)',
 P_PATH='@s9s_mb_2u_lib.s9s_mb_2u(sch_1):page76_i29@pure_quanta.q_cap(chips)',
 PATH='I29',
 DRAWING='@S9S_MB_2U_LIB.S9S_MB_2U(SCH_1):PAGE76',
 PHYS_PAGE='76',
 XY='(-1225,4025)',
 ROT='0',
 VER='1',
 PACK_TYPE='C0805',
 CDS_LIB='pure_quanta',
 CDS_PART_NAME='Q_CAP_C0805-47UF,4V,20%,X6S,CHA',
 TOLERANCE='20%',
 MATERIAL='X6S',
 VOLTAGE='4V',
 VALUE='47UF',
 PRIM_FILE='./archive_libs/logical/q_cap/chips/chips.prt';

PART_NAME
 C518 'Q_CAP_C0805-47UF,4V,20%,X6S,CHA':;

SECTION_NUMBER 1
 '@S9S_MB_2U_LIB.S9S_MB_2U(SCH_1):PAGE75_I31@PURE_QUANTA.Q_CAP(CHIPS)':
 C_PATH='@s9s_mb_2u_lib.s9s_mb_2u(sch_1):page75_i31@pure_quanta.q_cap(chips)',
 P_PATH='@s9s_mb_2u_lib.s9s_mb_2u(sch_1):page75_i31@pure_quanta.q_cap(chips)',
 PATH='I31',
 DRAWING='@S9S_MB_2U_LIB.S9S_MB_2U(SCH_1):PAGE75',
 PHYS_PAGE='75',
 XY='(-3075,725)',
 ROT='0',
 VER='1',
 PACK_TYPE='C0805',
 CDS_LIB='pure_quanta',
 CDS_PART_NAME='Q_CAP_C0805-47UF,4V,20%,X6S,CHA',
 TOLERANCE='20%',
 MATERIAL='X6S',
 VOLTAGE='4V',
 VALUE='47UF',
 PRIM_FILE='./archive_libs/logical/q_cap/chips/chips.prt';

PART_NAME
 C519 'Q_CAP_C0603-47UF,2.5V,20%,X6S,A':;

SECTION_NUMBER 1
 '@S9S_MB_2U_LIB.S9S_MB_2U(SCH_1):PAGE76_I35@PURE_QUANTA.Q_CAP(CHIPS)':
 C_PATH='@s9s_mb_2u_lib.s9s_mb_2u(sch_1):page76_i35@pure_quanta.q_cap(chips)',
 P_PATH='@s9s_mb_2u_lib.s9s_mb_2u(sch_1):page76_i35@pure_quanta.q_cap(chips)',
 PATH='I35',
 DRAWING='@S9S_MB_2U_LIB.S9S_MB_2U(SCH_1):PAGE76',
 PHYS_PAGE='76',
 XY='(-1675,6100)',
 ROT='0',
 VER='1',
 PACK_TYPE='C0603',
 CDS_LIB='pure_quanta',
 CDS_PART_NAME='Q_CAP_C0603-47UF,2.5V,20%,X6S,A',
 TOLERANCE='20%',
 MATERIAL='X6S',
 VOLTAGE='2.5V',
 VALUE='47UF',
 PRIM_FILE='./archive_libs/logical/q_cap/chips/chips.prt';

PART_NAME
 C520 'Q_CAP_C0805-47UF,4V,20%,X6S,CHA':;

SECTION_NUMBER 1
 '@S9S_MB_2U_LIB.S9S_MB_2U(SCH_1):PAGE76_I36@PURE_QUANTA.Q_CAP(CHIPS)':
 C_PATH='@s9s_mb_2u_lib.s9s_mb_2u(sch_1):page76_i36@pure_quanta.q_cap(chips)',
 P_PATH='@s9s_mb_2u_lib.s9s_mb_2u(sch_1):page76_i36@pure_quanta.q_cap(chips)',
 PATH='I36',
 DRAWING='@S9S_MB_2U_LIB.S9S_MB_2U(SCH_1):PAGE76',
 PHYS_PAGE='76',
 XY='(-775,4025)',
 ROT='0',
 VER='1',
 PACK_TYPE='C0805',
 CDS_LIB='pure_quanta',
 CDS_PART_NAME='Q_CAP_C0805-47UF,4V,20%,X6S,CHA',
 TOLERANCE='20%',
 MATERIAL='X6S',
 VOLTAGE='4V',
 VALUE='47UF',
 PRIM_FILE='./archive_libs/logical/q_cap/chips/chips.prt';

PART_NAME
 C521 'Q_CAP_C0805-47UF,4V,20%,X6S,CHA':;

SECTION_NUMBER 1
 '@S9S_MB_2U_LIB.S9S_MB_2U(SCH_1):PAGE76_I37@PURE_QUANTA.Q_CAP(CHIPS)':
 C_PATH='@s9s_mb_2u_lib.s9s_mb_2u(sch_1):page76_i37@pure_quanta.q_cap(chips)',
 P_PATH='@s9s_mb_2u_lib.s9s_mb_2u(sch_1):page76_i37@pure_quanta.q_cap(chips)',
 PATH='I37',
 DRAWING='@S9S_MB_2U_LIB.S9S_MB_2U(SCH_1):PAGE76',
 PHYS_PAGE='76',
 XY='(-325,4025)',
 ROT='0',
 VER='1',
 PACK_TYPE='C0805',
 CDS_LIB='pure_quanta',
 CDS_PART_NAME='Q_CAP_C0805-47UF,4V,20%,X6S,CHA',
 TOLERANCE='20%',
 MATERIAL='X6S',
 VOLTAGE='4V',
 VALUE='47UF',
 PRIM_FILE='./archive_libs/logical/q_cap/chips/chips.prt';

PART_NAME
 C522 'Q_CAP_C0805-47UF,4V,20%,X6S,CHA':;

SECTION_NUMBER 1
 '@S9S_MB_2U_LIB.S9S_MB_2U(SCH_1):PAGE75_I9@PURE_QUANTA.Q_CAP(CHIPS)':
 C_PATH='@s9s_mb_2u_lib.s9s_mb_2u(sch_1):page75_i9@pure_quanta.q_cap(chips)',
 P_PATH='@s9s_mb_2u_lib.s9s_mb_2u(sch_1):page75_i9@pure_quanta.q_cap(chips)',
 PATH='I9',
 DRAWING='@S9S_MB_2U_LIB.S9S_MB_2U(SCH_1):PAGE75',
 PHYS_PAGE='75',
 XY='(-4425,-1225)',
 ROT='0',
 VER='1',
 PACK_TYPE='C0805',
 CDS_LIB='pure_quanta',
 CDS_PART_NAME='Q_CAP_C0805-47UF,4V,20%,X6S,CHA',
 TOLERANCE='20%',
 MATERIAL='X6S',
 VOLTAGE='4V',
 VALUE='47UF',
 PRIM_FILE='./archive_libs/logical/q_cap/chips/chips.prt';

PART_NAME
 C523 'Q_CAP_C0805-47UF,4V,20%,X6S,CHA':;

SECTION_NUMBER 1
 '@S9S_MB_2U_LIB.S9S_MB_2U(SCH_1):PAGE76_I38@PURE_QUANTA.Q_CAP(CHIPS)':
 C_PATH='@s9s_mb_2u_lib.s9s_mb_2u(sch_1):page76_i38@pure_quanta.q_cap(chips)',
 P_PATH='@s9s_mb_2u_lib.s9s_mb_2u(sch_1):page76_i38@pure_quanta.q_cap(chips)',
 PATH='I38',
 DRAWING='@S9S_MB_2U_LIB.S9S_MB_2U(SCH_1):PAGE76',
 PHYS_PAGE='76',
 XY='(125,4025)',
 ROT='0',
 VER='1',
 PACK_TYPE='C0805',
 CDS_LIB='pure_quanta',
 CDS_PART_NAME='Q_CAP_C0805-47UF,4V,20%,X6S,CHA',
 TOLERANCE='20%',
 MATERIAL='X6S',
 VOLTAGE='4V',
 VALUE='47UF',
 PRIM_FILE='./archive_libs/logical/q_cap/chips/chips.prt';

PART_NAME
 C525 'Q_CAP_C0805-47UF,4V,20%,X6S,CHA':;

SECTION_NUMBER 1
 '@S9S_MB_2U_LIB.S9S_MB_2U(SCH_1):PAGE76_I5@PURE_QUANTA.Q_CAP(CHIPS)':
 C_PATH='@s9s_mb_2u_lib.s9s_mb_2u(sch_1):page76_i5@pure_quanta.q_cap(chips)',
 P_PATH='@s9s_mb_2u_lib.s9s_mb_2u(sch_1):page76_i5@pure_quanta.q_cap(chips)',
 PATH='I5',
 DRAWING='@S9S_MB_2U_LIB.S9S_MB_2U(SCH_1):PAGE76',
 PHYS_PAGE='76',
 XY='(-3925,5075)',
 ROT='0',
 VER='1',
 PACK_TYPE='C0805',
 CDS_LIB='pure_quanta',
 CDS_PART_NAME='Q_CAP_C0805-47UF,4V,20%,X6S,CHA',
 TOLERANCE='20%',
 MATERIAL='X6S',
 VOLTAGE='4V',
 VALUE='47UF',
 PRIM_FILE='./archive_libs/logical/q_cap/chips/chips.prt';

PART_NAME
 C526 'Q_CAP_C0805-47UF,4V,20%,X6S,CHA':;

SECTION_NUMBER 1
 '@S9S_MB_2U_LIB.S9S_MB_2U(SCH_1):PAGE76_I39@PURE_QUANTA.Q_CAP(CHIPS)':
 C_PATH='@s9s_mb_2u_lib.s9s_mb_2u(sch_1):page76_i39@pure_quanta.q_cap(chips)',
 P_PATH='@s9s_mb_2u_lib.s9s_mb_2u(sch_1):page76_i39@pure_quanta.q_cap(chips)',
 PATH='I39',
 DRAWING='@S9S_MB_2U_LIB.S9S_MB_2U(SCH_1):PAGE76',
 PHYS_PAGE='76',
 XY='(575,4025)',
 ROT='0',
 VER='1',
 PACK_TYPE='C0805',
 CDS_LIB='pure_quanta',
 CDS_PART_NAME='Q_CAP_C0805-47UF,4V,20%,X6S,CHA',
 TOLERANCE='20%',
 MATERIAL='X6S',
 VOLTAGE='4V',
 VALUE='47UF',
 PRIM_FILE='./archive_libs/logical/q_cap/chips/chips.prt';

PART_NAME
 C527 'Q_CAP_C0805-47UF,4V,20%,X6S,CHA':;

SECTION_NUMBER 1
 '@S9S_MB_2U_LIB.S9S_MB_2U(SCH_1):PAGE75_I68@PURE_QUANTA.Q_CAP(CHIPS)':
 C_PATH='@s9s_mb_2u_lib.s9s_mb_2u(sch_1):page75_i68@pure_quanta.q_cap(chips)',
 P_PATH='@s9s_mb_2u_lib.s9s_mb_2u(sch_1):page75_i68@pure_quanta.q_cap(chips)',
 PATH='I68',
 DRAWING='@S9S_MB_2U_LIB.S9S_MB_2U(SCH_1):PAGE75',
 PHYS_PAGE='75',
 XY='(3200,2425)',
 ROT='0',
 VER='1',
 PACK_TYPE='C0805',
 CDS_LIB='pure_quanta',
 CDS_PART_NAME='Q_CAP_C0805-47UF,4V,20%,X6S,CHA',
 TOLERANCE='20%',
 MATERIAL='X6S',
 VOLTAGE='4V',
 VALUE='47UF',
 PRIM_FILE='./archive_libs/logical/q_cap/chips/chips.prt';

PART_NAME
 C528 'Q_CAP_C0805-47UF,4V,20%,X6S,CHA':;

SECTION_NUMBER 1
 '@S9S_MB_2U_LIB.S9S_MB_2U(SCH_1):PAGE76_I6@PURE_QUANTA.Q_CAP(CHIPS)':
 C_PATH='@s9s_mb_2u_lib.s9s_mb_2u(sch_1):page76_i6@pure_quanta.q_cap(chips)',
 P_PATH='@s9s_mb_2u_lib.s9s_mb_2u(sch_1):page76_i6@pure_quanta.q_cap(chips)',
 PATH='I6',
 DRAWING='@S9S_MB_2U_LIB.S9S_MB_2U(SCH_1):PAGE76',
 PHYS_PAGE='76',
 XY='(-3475,5075)',
 ROT='0',
 VER='1',
 PACK_TYPE='C0805',
 CDS_LIB='pure_quanta',
 CDS_PART_NAME='Q_CAP_C0805-47UF,4V,20%,X6S,CHA',
 TOLERANCE='20%',
 MATERIAL='X6S',
 VOLTAGE='4V',
 VALUE='47UF',
 PRIM_FILE='./archive_libs/logical/q_cap/chips/chips.prt';

PART_NAME
 C529 'Q_CAP_C0805-47UF,4V,20%,X6S,CHA':;

SECTION_NUMBER 1
 '@S9S_MB_2U_LIB.S9S_MB_2U(SCH_1):PAGE76_I41@PURE_QUANTA.Q_CAP(CHIPS)':
 C_PATH='@s9s_mb_2u_lib.s9s_mb_2u(sch_1):page76_i41@pure_quanta.q_cap(chips)',
 P_PATH='@s9s_mb_2u_lib.s9s_mb_2u(sch_1):page76_i41@pure_quanta.q_cap(chips)',
 PATH='I41',
 DRAWING='@S9S_MB_2U_LIB.S9S_MB_2U(SCH_1):PAGE76',
 PHYS_PAGE='76',
 XY='(1025,4025)',
 ROT='0',
 VER='1',
 PACK_TYPE='C0805',
 CDS_LIB='pure_quanta',
 CDS_PART_NAME='Q_CAP_C0805-47UF,4V,20%,X6S,CHA',
 TOLERANCE='20%',
 MATERIAL='X6S',
 VOLTAGE='4V',
 VALUE='47UF',
 PRIM_FILE='./archive_libs/logical/q_cap/chips/chips.prt';

PART_NAME
 C530 'Q_CAP_C0805-47UF,4V,20%,X6S,CHA':;

SECTION_NUMBER 1
 '@S9S_MB_2U_LIB.S9S_MB_2U(SCH_1):PAGE76_I7@PURE_QUANTA.Q_CAP(CHIPS)':
 C_PATH='@s9s_mb_2u_lib.s9s_mb_2u(sch_1):page76_i7@pure_quanta.q_cap(chips)',
 P_PATH='@s9s_mb_2u_lib.s9s_mb_2u(sch_1):page76_i7@pure_quanta.q_cap(chips)',
 PATH='I7',
 DRAWING='@S9S_MB_2U_LIB.S9S_MB_2U(SCH_1):PAGE76',
 PHYS_PAGE='76',
 XY='(-3025,5075)',
 ROT='0',
 VER='1',
 PACK_TYPE='C0805',
 CDS_LIB='pure_quanta',
 CDS_PART_NAME='Q_CAP_C0805-47UF,4V,20%,X6S,CHA',
 TOLERANCE='20%',
 MATERIAL='X6S',
 VOLTAGE='4V',
 VALUE='47UF',
 PRIM_FILE='./archive_libs/logical/q_cap/chips/chips.prt';

PART_NAME
 C531 'Q_CAP_C0805-47UF,4V,20%,X6S,CHA':;

SECTION_NUMBER 1
 '@S9S_MB_2U_LIB.S9S_MB_2U(SCH_1):PAGE76_I31@PURE_QUANTA.Q_CAP(CHIPS)':
 C_PATH='@s9s_mb_2u_lib.s9s_mb_2u(sch_1):page76_i31@pure_quanta.q_cap(chips)',
 P_PATH='@s9s_mb_2u_lib.s9s_mb_2u(sch_1):page76_i31@pure_quanta.q_cap(chips)',
 PATH='I31',
 DRAWING='@S9S_MB_2U_LIB.S9S_MB_2U(SCH_1):PAGE76',
 PHYS_PAGE='76',
 XY='(-2575,5075)',
 ROT='0',
 VER='1',
 PACK_TYPE='C0805',
 CDS_LIB='pure_quanta',
 CDS_PART_NAME='Q_CAP_C0805-47UF,4V,20%,X6S,CHA',
 TOLERANCE='20%',
 MATERIAL='X6S',
 VOLTAGE='4V',
 VALUE='47UF',
 PRIM_FILE='./archive_libs/logical/q_cap/chips/chips.prt';

PART_NAME
 C532 'Q_CAP_C0603-47UF,2.5V,20%,X6S,A':;

SECTION_NUMBER 1
 '@S9S_MB_2U_LIB.S9S_MB_2U(SCH_1):PAGE75_I14@PURE_QUANTA.Q_CAP(CHIPS)':
 C_PATH='@s9s_mb_2u_lib.s9s_mb_2u(sch_1):page75_i14@pure_quanta.q_cap(chips)',
 P_PATH='@s9s_mb_2u_lib.s9s_mb_2u(sch_1):page75_i14@pure_quanta.q_cap(chips)',
 PATH='I14',
 DRAWING='@S9S_MB_2U_LIB.S9S_MB_2U(SCH_1):PAGE75',
 PHYS_PAGE='75',
 XY='(-3975,-1225)',
 ROT='0',
 VER='1',
 PACK_TYPE='C0603',
 CDS_LIB='pure_quanta',
 CDS_PART_NAME='Q_CAP_C0603-47UF,2.5V,20%,X6S,A',
 TOLERANCE='20%',
 MATERIAL='X6S',
 VOLTAGE='2.5V',
 VALUE='47UF',
 PRIM_FILE='./archive_libs/logical/q_cap/chips/chips.prt';

PART_NAME
 C533 'Q_CAP_C0603-47UF,2.5V,20%,X6S,A':;

SECTION_NUMBER 1
 '@S9S_MB_2U_LIB.S9S_MB_2U(SCH_1):PAGE75_I17@PURE_QUANTA.Q_CAP(CHIPS)':
 C_PATH='@s9s_mb_2u_lib.s9s_mb_2u(sch_1):page75_i17@pure_quanta.q_cap(chips)',
 P_PATH='@s9s_mb_2u_lib.s9s_mb_2u(sch_1):page75_i17@pure_quanta.q_cap(chips)',
 PATH='I17',
 DRAWING='@S9S_MB_2U_LIB.S9S_MB_2U(SCH_1):PAGE75',
 PHYS_PAGE='75',
 XY='(-3525,-1225)',
 ROT='0',
 VER='1',
 PACK_TYPE='C0603',
 CDS_LIB='pure_quanta',
 CDS_PART_NAME='Q_CAP_C0603-47UF,2.5V,20%,X6S,A',
 TOLERANCE='20%',
 MATERIAL='X6S',
 VOLTAGE='2.5V',
 VALUE='47UF',
 PRIM_FILE='./archive_libs/logical/q_cap/chips/chips.prt';

PART_NAME
 C534 'Q_CAP_C0402-22UF,4V,20%,X6S,CHA':;

SECTION_NUMBER 1
 '@S9S_MB_2U_LIB.S9S_MB_2U(SCH_1):PAGE75_I29@PURE_QUANTA.Q_CAP(CHIPS)':
 C_PATH='@s9s_mb_2u_lib.s9s_mb_2u(sch_1):page75_i29@pure_quanta.q_cap(chips)',
 P_PATH='@s9s_mb_2u_lib.s9s_mb_2u(sch_1):page75_i29@pure_quanta.q_cap(chips)',
 PATH='I29',
 DRAWING='@S9S_MB_2U_LIB.S9S_MB_2U(SCH_1):PAGE75',
 PHYS_PAGE='75',
 XY='(-3075,-1225)',
 ROT='0',
 VER='1',
 PACK_TYPE='C0402',
 CDS_LIB='pure_quanta',
 CDS_PART_NAME='Q_CAP_C0402-22UF,4V,20%,X6S,CHA',
 TOLERANCE='20%',
 MATERIAL='X6S',
 VOLTAGE='4V',
 VALUE='22UF',
 PRIM_FILE='./archive_libs/logical/q_cap/chips/chips.prt';

PART_NAME
 C535 'Q_CAP_C0805-22UF,16V,20%,X6S,CA':;

SECTION_NUMBER 1
 '@S9S_MB_2U_LIB.S9S_MB_2U(SCH_1):PAGE243_I4@PURE_QUANTA.Q_CAP(CHIPS)':
 C_PATH='@s9s_mb_2u_lib.s9s_mb_2u(sch_1):page243_i4@pure_quanta.q_cap(chips)',
 P_PATH='@s9s_mb_2u_lib.s9s_mb_2u(sch_1):page257_i4@pure_quanta.q_cap(chips)',
 PATH='I4',
 DRAWING='@S9S_MB_2U_LIB.S9S_MB_2U(SCH_1):PAGE243',
 PHYS_PAGE='257',
 XY='(-4000,12450)',
 ROT='0',
 VER='1',
 PACK_TYPE='C0805',
 CDS_LIB='pure_quanta',
 CDS_PART_NAME='Q_CAP_C0805-22UF,16V,20%,X6S,CA',
 TOLERANCE='20%',
 MATERIAL='X6S',
 VOLTAGE='16V',
 VALUE='22UF',
 PRIM_FILE='./archive_libs/logical/q_cap/chips/chips.prt';

PART_NAME
 C537 'Q_CAP_0402-0.1UF,25V,10%,X7R,CA':;

SECTION_NUMBER 1
 '@S9S_MB_2U_LIB.S9S_MB_2U(SCH_1):PAGE218_I25@PURE_QUANTA.Q_CAP(CHIPS)':
 C_PATH='@s9s_mb_2u_lib.s9s_mb_2u(sch_1):page218_i25@pure_quanta.q_cap(chips)',
 P_PATH='@s9s_mb_2u_lib.s9s_mb_2u(sch_1):page230_i25@pure_quanta.q_cap(chips)',
 PATH='I25',
 DRAWING='@S9S_MB_2U_LIB.S9S_MB_2U(SCH_1):PAGE218',
 PHYS_PAGE='230',
 XY='(1250,2350)',
 ROT='0',
 VER='1',
 PACK_TYPE='0402',
 CDS_LIB='pure_quanta',
 CDS_PART_NAME='Q_CAP_0402-0.1UF,25V,10%,X7R,CA',
 TOLERANCE='10%',
 MATERIAL='X7R',
 VOLTAGE='25V',
 VALUE='0.1UF',
 PRIM_FILE='./archive_libs/logical/q_cap/chips/chips.prt';

PART_NAME
 C538 'Q_CAP_0402-0.1UF,25V,10%,X7R,CA':;

SECTION_NUMBER 1
 '@S9S_MB_2U_LIB.S9S_MB_2U(SCH_1):PAGE217_I24@PURE_QUANTA.Q_CAP(CHIPS)':
 C_PATH='@s9s_mb_2u_lib.s9s_mb_2u(sch_1):page217_i24@pure_quanta.q_cap(chips)',
 P_PATH='@s9s_mb_2u_lib.s9s_mb_2u(sch_1):page229_i24@pure_quanta.q_cap(chips)',
 PATH='I24',
 DRAWING='@S9S_MB_2U_LIB.S9S_MB_2U(SCH_1):PAGE217',
 PHYS_PAGE='229',
 XY='(-750,2250)',
 ROT='0',
 VER='1',
 PACK_TYPE='0402',
 CDS_LIB='pure_quanta',
 CDS_PART_NAME='Q_CAP_0402-0.1UF,25V,10%,X7R,CA',
 TOLERANCE='10%',
 MATERIAL='X7R',
 VOLTAGE='25V',
 VALUE='0.1UF',
 PRIM_FILE='./archive_libs/logical/q_cap/chips/chips.prt';

PART_NAME
 C539 'Q_CAP_0402-0.1UF,25V,10%,X7R,CA':;

SECTION_NUMBER 1
 '@S9S_MB_2U_LIB.S9S_MB_2U(SCH_1):PAGE135_I70@PURE_QUANTA.Q_CAP(CHIPS)':
 C_PATH='@s9s_mb_2u_lib.s9s_mb_2u(sch_1):page135_i70@pure_quanta.q_cap(chips)',
 P_PATH='@s9s_mb_2u_lib.s9s_mb_2u(sch_1):page133_i70@pure_quanta.q_cap(chips)',
 PATH='I70',
 DRAWING='@S9S_MB_2U_LIB.S9S_MB_2U(SCH_1):PAGE135',
 PHYS_PAGE='133',
 XY='(-1500,3950)',
 ROT='2',
 VER='1',
 PACK_TYPE='0402',
 CDS_LIB='pure_quanta',
 CDS_PART_NAME='Q_CAP_0402-0.1UF,25V,10%,X7R,CA',
 TOLERANCE='10%',
 MATERIAL='X7R',
 VOLTAGE='25V',
 VALUE='0.1UF',
 PRIM_FILE='./archive_libs/logical/q_cap/chips/chips.prt';

PART_NAME
 C540 'Q_CAP_0402-0.1UF,25V,10%,X7R,CA':;

SECTION_NUMBER 1
 '@S9S_MB_2U_LIB.S9S_MB_2U(SCH_1):PAGE135_I81@PURE_QUANTA.Q_CAP(CHIPS)':
 C_PATH='@s9s_mb_2u_lib.s9s_mb_2u(sch_1):page135_i81@pure_quanta.q_cap(chips)',
 P_PATH='@s9s_mb_2u_lib.s9s_mb_2u(sch_1):page133_i81@pure_quanta.q_cap(chips)',
 PATH='I81',
 DRAWING='@S9S_MB_2U_LIB.S9S_MB_2U(SCH_1):PAGE135',
 PHYS_PAGE='133',
 XY='(-1500,2400)',
 ROT='2',
 VER='1',
 PACK_TYPE='0402',
 CDS_LIB='pure_quanta',
 CDS_PART_NAME='Q_CAP_0402-0.1UF,25V,10%,X7R,CA',
 TOLERANCE='10%',
 MATERIAL='X7R',
 VOLTAGE='25V',
 VALUE='0.1UF',
 PRIM_FILE='./archive_libs/logical/q_cap/chips/chips.prt';

PART_NAME
 C541 'Q_CAP_C0402-1UF,25V,10%,X6S,CHA':;

SECTION_NUMBER 1
 '@S9S_MB_2U_LIB.S9S_MB_2U(SCH_1):PAGE135_I61@PURE_QUANTA.Q_CAP(CHIPS)':
 C_PATH='@s9s_mb_2u_lib.s9s_mb_2u(sch_1):page135_i61@pure_quanta.q_cap(chips)',
 P_PATH='@s9s_mb_2u_lib.s9s_mb_2u(sch_1):page133_i61@pure_quanta.q_cap(chips)',
 PATH='I61',
 DRAWING='@S9S_MB_2U_LIB.S9S_MB_2U(SCH_1):PAGE135',
 PHYS_PAGE='133',
 XY='(-1150,3950)',
 ROT='2',
 VER='1',
 PACK_TYPE='C0402',
 CDS_LIB='pure_quanta',
 CDS_PART_NAME='Q_CAP_C0402-1UF,25V,10%,X6S,CHA',
 TOLERANCE='10%',
 MATERIAL='X6S',
 VOLTAGE='25V',
 VALUE='1UF',
 PRIM_FILE='./archive_libs/logical/q_cap/chips/chips.prt';

PART_NAME
 C542 'Q_CAP_C0402-1UF,25V,10%,X6S,CHA':;

SECTION_NUMBER 1
 '@S9S_MB_2U_LIB.S9S_MB_2U(SCH_1):PAGE135_I80@PURE_QUANTA.Q_CAP(CHIPS)':
 C_PATH='@s9s_mb_2u_lib.s9s_mb_2u(sch_1):page135_i80@pure_quanta.q_cap(chips)',
 P_PATH='@s9s_mb_2u_lib.s9s_mb_2u(sch_1):page133_i80@pure_quanta.q_cap(chips)',
 PATH='I80',
 DRAWING='@S9S_MB_2U_LIB.S9S_MB_2U(SCH_1):PAGE135',
 PHYS_PAGE='133',
 XY='(-1150,2400)',
 ROT='2',
 VER='1',
 PACK_TYPE='C0402',
 CDS_LIB='pure_quanta',
 CDS_PART_NAME='Q_CAP_C0402-1UF,25V,10%,X6S,CHA',
 TOLERANCE='10%',
 MATERIAL='X6S',
 VOLTAGE='25V',
 VALUE='1UF',
 PRIM_FILE='./archive_libs/logical/q_cap/chips/chips.prt';

PART_NAME
 C543 'Q_CAP_0402-0.1UF,25V,10%,X7R,CA':;

SECTION_NUMBER 1
 '@S9S_MB_2U_LIB.S9S_MB_2U(SCH_1):PAGE135_I100@PURE_QUANTA.Q_CAP(CHIPS)':
 C_PATH='@s9s_mb_2u_lib.s9s_mb_2u(sch_1):page135_i100@pure_quanta.q_cap(chips)',
 P_PATH='@s9s_mb_2u_lib.s9s_mb_2u(sch_1):page133_i100@pure_quanta.q_cap(chips)',
 PATH='I100',
 DRAWING='@S9S_MB_2U_LIB.S9S_MB_2U(SCH_1):PAGE135',
 PHYS_PAGE='133',
 XY='(750,650)',
 ROT='2',
 VER='1',
 PACK_TYPE='0402',
 CDS_LIB='pure_quanta',
 CDS_PART_NAME='Q_CAP_0402-0.1UF,25V,10%,X7R,CA',
 TOLERANCE='10%',
 MATERIAL='X7R',
 VOLTAGE='25V',
 VALUE='0.1UF',
 PRIM_FILE='./archive_libs/logical/q_cap/chips/chips.prt';

PART_NAME
 C544 'Q_CAP_0402-0.1UF,25V,10%,X7R,CA':;

SECTION_NUMBER 1
 '@S9S_MB_2U_LIB.S9S_MB_2U(SCH_1):PAGE135_I94@PURE_QUANTA.Q_CAP(CHIPS)':
 C_PATH='@s9s_mb_2u_lib.s9s_mb_2u(sch_1):page135_i94@pure_quanta.q_cap(chips)',
 P_PATH='@s9s_mb_2u_lib.s9s_mb_2u(sch_1):page133_i94@pure_quanta.q_cap(chips)',
 PATH='I94',
 DRAWING='@S9S_MB_2U_LIB.S9S_MB_2U(SCH_1):PAGE135',
 PHYS_PAGE='133',
 XY='(2750,650)',
 ROT='2',
 VER='1',
 PACK_TYPE='0402',
 CDS_LIB='pure_quanta',
 CDS_PART_NAME='Q_CAP_0402-0.1UF,25V,10%,X7R,CA',
 TOLERANCE='10%',
 MATERIAL='X7R',
 VOLTAGE='25V',
 VALUE='0.1UF',
 PRIM_FILE='./archive_libs/logical/q_cap/chips/chips.prt';

PART_NAME
 C545 'Q_CAP_C0402-1UF,25V,10%,X6S,CHA':;

SECTION_NUMBER 1
 '@S9S_MB_2U_LIB.S9S_MB_2U(SCH_1):PAGE134_I93@PURE_QUANTA.Q_CAP(CHIPS)':
 C_PATH='@s9s_mb_2u_lib.s9s_mb_2u(sch_1):page134_i93@pure_quanta.q_cap(chips)',
 P_PATH='@s9s_mb_2u_lib.s9s_mb_2u(sch_1):page132_i93@pure_quanta.q_cap(chips)',
 PATH='I93',
 DRAWING='@S9S_MB_2U_LIB.S9S_MB_2U(SCH_1):PAGE134',
 PHYS_PAGE='132',
 XY='(275,4100)',
 ROT='0',
 VER='1',
 PACK_TYPE='C0402',
 CDS_LIB='pure_quanta',
 CDS_PART_NAME='Q_CAP_C0402-1UF,25V,10%,X6S,CHA',
 TOLERANCE='10%',
 MATERIAL='X6S',
 VOLTAGE='25V',
 VALUE='1UF',
 PRIM_FILE='./archive_libs/logical/q_cap/chips/chips.prt';

PART_NAME
 C546 'Q_CAP_C0402-1UF,25V,10%,X6S,CHA':;

SECTION_NUMBER 1
 '@S9S_MB_2U_LIB.S9S_MB_2U(SCH_1):PAGE134_I135@PURE_QUANTA.Q_CAP(CHIPS)':
 C_PATH='@s9s_mb_2u_lib.s9s_mb_2u(sch_1):page134_i135@pure_quanta.q_cap(chips)',
 P_PATH='@s9s_mb_2u_lib.s9s_mb_2u(sch_1):page132_i135@pure_quanta.q_cap(chips)',
 PATH='I135',
 DRAWING='@S9S_MB_2U_LIB.S9S_MB_2U(SCH_1):PAGE134',
 PHYS_PAGE='132',
 XY='(275,2200)',
 ROT='0',
 VER='1',
 PACK_TYPE='C0402',
 CDS_LIB='pure_quanta',
 CDS_PART_NAME='Q_CAP_C0402-1UF,25V,10%,X6S,CHA',
 TOLERANCE='10%',
 MATERIAL='X6S',
 VOLTAGE='25V',
 VALUE='1UF',
 PRIM_FILE='./archive_libs/logical/q_cap/chips/chips.prt';

PART_NAME
 C547 'Q_CAP_C0402-1UF,25V,10%,X6S,CHA':;

SECTION_NUMBER 1
 '@S9S_MB_2U_LIB.S9S_MB_2U(SCH_1):PAGE133_I100@PURE_QUANTA.Q_CAP(CHIPS)':
 C_PATH='@s9s_mb_2u_lib.s9s_mb_2u(sch_1):page133_i100@pure_quanta.q_cap(chips)',
 P_PATH='@s9s_mb_2u_lib.s9s_mb_2u(sch_1):page131_i100@pure_quanta.q_cap(chips)',
 PATH='I100',
 DRAWING='@S9S_MB_2U_LIB.S9S_MB_2U(SCH_1):PAGE133',
 PHYS_PAGE='131',
 XY='(-125,3500)',
 ROT='2',
 VER='1',
 PACK_TYPE='C0402',
 CDS_LIB='pure_quanta',
 CDS_PART_NAME='Q_CAP_C0402-1UF,25V,10%,X6S,CHA',
 TOLERANCE='10%',
 MATERIAL='X6S',
 VOLTAGE='25V',
 VALUE='1UF',
 PRIM_FILE='./archive_libs/logical/q_cap/chips/chips.prt';

PART_NAME
 C548 'Q_CAP_0402-0.1UF,25V,10%,X7R,CA':;

SECTION_NUMBER 1
 '@S9S_MB_2U_LIB.S9S_MB_2U(SCH_1):PAGE133_I130@PURE_QUANTA.Q_CAP(CHIPS)':
 C_PATH='@s9s_mb_2u_lib.s9s_mb_2u(sch_1):page133_i130@pure_quanta.q_cap(chips)',
 P_PATH='@s9s_mb_2u_lib.s9s_mb_2u(sch_1):page131_i130@pure_quanta.q_cap(chips)',
 PATH='I130',
 DRAWING='@S9S_MB_2U_LIB.S9S_MB_2U(SCH_1):PAGE133',
 PHYS_PAGE='131',
 XY='(-125,-1225)',
 ROT='2',
 VER='1',
 PACK_TYPE='0402',
 CDS_LIB='pure_quanta',
 CDS_PART_NAME='Q_CAP_0402-0.1UF,25V,10%,X7R,CA',
 TOLERANCE='10%',
 MATERIAL='X7R',
 VOLTAGE='25V',
 VALUE='0.1UF',
 PRIM_FILE='./archive_libs/logical/q_cap/chips/chips.prt';

PART_NAME
 C549 'Q_CAP_0402-0.1UF,25V,10%,X7R,CA':;

SECTION_NUMBER 1
 '@S9S_MB_2U_LIB.S9S_MB_2U(SCH_1):PAGE133_I129@PURE_QUANTA.Q_CAP(CHIPS)':
 C_PATH='@s9s_mb_2u_lib.s9s_mb_2u(sch_1):page133_i129@pure_quanta.q_cap(chips)',
 P_PATH='@s9s_mb_2u_lib.s9s_mb_2u(sch_1):page131_i129@pure_quanta.q_cap(chips)',
 PATH='I129',
 DRAWING='@S9S_MB_2U_LIB.S9S_MB_2U(SCH_1):PAGE133',
 PHYS_PAGE='131',
 XY='(100,-1225)',
 ROT='0',
 VER='1',
 PACK_TYPE='0402',
 CDS_LIB='pure_quanta',
 CDS_PART_NAME='Q_CAP_0402-0.1UF,25V,10%,X7R,CA',
 TOLERANCE='10%',
 MATERIAL='X7R',
 VOLTAGE='25V',
 VALUE='0.1UF',
 PRIM_FILE='./archive_libs/logical/q_cap/chips/chips.prt';

PART_NAME
 C550 'Q_CAP_C0402-1UF,25V,10%,X6S,CHA':;

SECTION_NUMBER 1
 '@S9S_MB_2U_LIB.S9S_MB_2U(SCH_1):PAGE133_I99@PURE_QUANTA.Q_CAP(CHIPS)':
 C_PATH='@s9s_mb_2u_lib.s9s_mb_2u(sch_1):page133_i99@pure_quanta.q_cap(chips)',
 P_PATH='@s9s_mb_2u_lib.s9s_mb_2u(sch_1):page131_i99@pure_quanta.q_cap(chips)',
 PATH='I99',
 DRAWING='@S9S_MB_2U_LIB.S9S_MB_2U(SCH_1):PAGE133',
 PHYS_PAGE='131',
 XY='(875,3500)',
 ROT='0',
 VER='1',
 PACK_TYPE='C0402',
 CDS_LIB='pure_quanta',
 CDS_PART_NAME='Q_CAP_C0402-1UF,25V,10%,X6S,CHA',
 TOLERANCE='10%',
 MATERIAL='X6S',
 VOLTAGE='25V',
 VALUE='1UF',
 PRIM_FILE='./archive_libs/logical/q_cap/chips/chips.prt';

PART_NAME
 C551 'Q_CAP_C0402-1UF,25V,10%,X6S,CHA':;

SECTION_NUMBER 1
 '@S9S_MB_2U_LIB.S9S_MB_2U(SCH_1):PAGE133_I105@PURE_QUANTA.Q_CAP(CHIPS)':
 C_PATH='@s9s_mb_2u_lib.s9s_mb_2u(sch_1):page133_i105@pure_quanta.q_cap(chips)',
 P_PATH='@s9s_mb_2u_lib.s9s_mb_2u(sch_1):page131_i105@pure_quanta.q_cap(chips)',
 PATH='I105',
 DRAWING='@S9S_MB_2U_LIB.S9S_MB_2U(SCH_1):PAGE133',
 PHYS_PAGE='131',
 XY='(1825,1525)',
 ROT='0',
 VER='1',
 PACK_TYPE='C0402',
 CDS_LIB='pure_quanta',
 CDS_PART_NAME='Q_CAP_C0402-1UF,25V,10%,X6S,CHA',
 TOLERANCE='10%',
 MATERIAL='X6S',
 VOLTAGE='25V',
 VALUE='1UF',
 PRIM_FILE='./archive_libs/logical/q_cap/chips/chips.prt';

PART_NAME
 C552 'Q_CAP_0402-0.1UF,25V,10%,X7R,CA':;

SECTION_NUMBER 1
 '@S9S_MB_2U_LIB.S9S_MB_2U(SCH_1):PAGE133_I96@PURE_QUANTA.Q_CAP(CHIPS)':
 C_PATH='@s9s_mb_2u_lib.s9s_mb_2u(sch_1):page133_i96@pure_quanta.q_cap(chips)',
 P_PATH='@s9s_mb_2u_lib.s9s_mb_2u(sch_1):page131_i96@pure_quanta.q_cap(chips)',
 PATH='I96',
 DRAWING='@S9S_MB_2U_LIB.S9S_MB_2U(SCH_1):PAGE133',
 PHYS_PAGE='131',
 XY='(2225,2050)',
 ROT='0',
 VER='1',
 PACK_TYPE='0402',
 CDS_LIB='pure_quanta',
 CDS_PART_NAME='Q_CAP_0402-0.1UF,25V,10%,X7R,CA',
 TOLERANCE='10%',
 MATERIAL='X7R',
 VOLTAGE='25V',
 VALUE='0.1UF',
 PRIM_FILE='./archive_libs/logical/q_cap/chips/chips.prt';

PART_NAME
 C554 'Q_CAP_0402-0.1UF,25V,10%,X7R,CA':;

SECTION_NUMBER 1
 '@S9S_MB_2U_LIB.S9S_MB_2U(SCH_1):PAGE210_I86@PURE_QUANTA.Q_CAP(CHIPS)':
 C_PATH='@s9s_mb_2u_lib.s9s_mb_2u(sch_1):page210_i86@pure_quanta.q_cap(chips)',
 P_PATH='@s9s_mb_2u_lib.s9s_mb_2u(sch_1):page221_i86@pure_quanta.q_cap(chips)',
 PATH='I86',
 DRAWING='@S9S_MB_2U_LIB.S9S_MB_2U(SCH_1):PAGE210',
 PHYS_PAGE='221',
 XY='(-1200,1400)',
 ROT='2',
 VER='1',
 PACK_TYPE='0402',
 CDS_LIB='pure_quanta',
 CDS_PART_NAME='Q_CAP_0402-0.1UF,25V,10%,X7R,CA',
 TOLERANCE='10%',
 MATERIAL='X7R',
 VOLTAGE='25V',
 VALUE='0.1UF',
 PRIM_FILE='./archive_libs/logical/q_cap/chips/chips.prt';

PART_NAME
 C559 'Q_CAP_0402-0.1UF,25V,10%,X7R,CA':;

SECTION_NUMBER 1
 '@S9S_MB_2U_LIB.S9S_MB_2U(SCH_1):PAGE223_I20@PURE_QUANTA.Q_CAP(CHIPS)':
 C_PATH='@s9s_mb_2u_lib.s9s_mb_2u(sch_1):page223_i20@pure_quanta.q_cap(chips)',
 P_PATH='@s9s_mb_2u_lib.s9s_mb_2u(sch_1):page235_i20@pure_quanta.q_cap(chips)',
 PATH='I20',
 DRAWING='@S9S_MB_2U_LIB.S9S_MB_2U(SCH_1):PAGE223',
 PHYS_PAGE='235',
 XY='(-4350,7600)',
 ROT='2',
 VER='1',
 PACK_TYPE='0402',
 CDS_LIB='pure_quanta',
 CDS_PART_NAME='Q_CAP_0402-0.1UF,25V,10%,X7R,CA',
 TOLERANCE='10%',
 MATERIAL='X7R',
 VOLTAGE='25V',
 VALUE='0.1UF',
 PRIM_FILE='./archive_libs/logical/q_cap/chips/chips.prt';

PART_NAME
 C560 'Q_CAP_0402-0.1UF,25V,10%,X7R,CA':;

SECTION_NUMBER 1
 '@S9S_MB_2U_LIB.S9S_MB_2U(SCH_1):PAGE223_I42@PURE_QUANTA.Q_CAP(CHIPS)':
 C_PATH='@s9s_mb_2u_lib.s9s_mb_2u(sch_1):page223_i42@pure_quanta.q_cap(chips)',
 P_PATH='@s9s_mb_2u_lib.s9s_mb_2u(sch_1):page235_i42@pure_quanta.q_cap(chips)',
 PATH='I42',
 DRAWING='@S9S_MB_2U_LIB.S9S_MB_2U(SCH_1):PAGE223',
 PHYS_PAGE='235',
 XY='(-4350,6000)',
 ROT='2',
 VER='1',
 PACK_TYPE='0402',
 CDS_LIB='pure_quanta',
 CDS_PART_NAME='Q_CAP_0402-0.1UF,25V,10%,X7R,CA',
 TOLERANCE='10%',
 MATERIAL='X7R',
 VOLTAGE='25V',
 VALUE='0.1UF',
 PRIM_FILE='./archive_libs/logical/q_cap/chips/chips.prt';

PART_NAME
 C561 'Q_CAP_0402-0.1UF,25V,10%,X7R,CA':;

SECTION_NUMBER 1
 '@S9S_MB_2U_LIB.S9S_MB_2U(SCH_1):PAGE223_I18@PURE_QUANTA.Q_CAP(CHIPS)':
 C_PATH='@s9s_mb_2u_lib.s9s_mb_2u(sch_1):page223_i18@pure_quanta.q_cap(chips)',
 P_PATH='@s9s_mb_2u_lib.s9s_mb_2u(sch_1):page235_i18@pure_quanta.q_cap(chips)',
 PATH='I18',
 DRAWING='@S9S_MB_2U_LIB.S9S_MB_2U(SCH_1):PAGE223',
 PHYS_PAGE='235',
 XY='(-3000,7600)',
 ROT='0',
 VER='1',
 PACK_TYPE='0402',
 CDS_LIB='pure_quanta',
 CDS_PART_NAME='Q_CAP_0402-0.1UF,25V,10%,X7R,CA',
 TOLERANCE='10%',
 MATERIAL='X7R',
 VOLTAGE='25V',
 VALUE='0.1UF',
 PRIM_FILE='./archive_libs/logical/q_cap/chips/chips.prt';

PART_NAME
 C562 'Q_CAP_0402-0.1UF,25V,10%,X7R,CA':;

SECTION_NUMBER 1
 '@S9S_MB_2U_LIB.S9S_MB_2U(SCH_1):PAGE223_I31@PURE_QUANTA.Q_CAP(CHIPS)':
 C_PATH='@s9s_mb_2u_lib.s9s_mb_2u(sch_1):page223_i31@pure_quanta.q_cap(chips)',
 P_PATH='@s9s_mb_2u_lib.s9s_mb_2u(sch_1):page235_i31@pure_quanta.q_cap(chips)',
 PATH='I31',
 DRAWING='@S9S_MB_2U_LIB.S9S_MB_2U(SCH_1):PAGE223',
 PHYS_PAGE='235',
 XY='(-3000,6000)',
 ROT='0',
 VER='1',
 PACK_TYPE='0402',
 CDS_LIB='pure_quanta',
 CDS_PART_NAME='Q_CAP_0402-0.1UF,25V,10%,X7R,CA',
 TOLERANCE='10%',
 MATERIAL='X7R',
 VOLTAGE='25V',
 VALUE='0.1UF',
 PRIM_FILE='./archive_libs/logical/q_cap/chips/chips.prt';

PART_NAME
 C563 'Q_CAP_C0805-10UF,25V,10%,X6S,CA':;

SECTION_NUMBER 1
 '@S9S_MB_2U_LIB.S9S_MB_2U(SCH_1):PAGE210_I88@PURE_QUANTA.Q_CAP(CHIPS)':
 C_PATH='@s9s_mb_2u_lib.s9s_mb_2u(sch_1):page210_i88@pure_quanta.q_cap(chips)',
 P_PATH='@s9s_mb_2u_lib.s9s_mb_2u(sch_1):page221_i88@pure_quanta.q_cap(chips)',
 PATH='I88',
 DRAWING='@S9S_MB_2U_LIB.S9S_MB_2U(SCH_1):PAGE210',
 PHYS_PAGE='221',
 XY='(-1075,1400)',
 ROT='0',
 VER='1',
 PACK_TYPE='C0805',
 CDS_LIB='pure_quanta',
 CDS_PART_NAME='Q_CAP_C0805-10UF,25V,10%,X6S,CA',
 TOLERANCE='10%',
 MATERIAL='X6S',
 VOLTAGE='25V',
 VALUE='10UF',
 PRIM_FILE='./archive_libs/logical/q_cap/chips/chips.prt';

PART_NAME
 C567 'Q_CAP_0402-0.1UF,25V,10%,X7R,CA':;

SECTION_NUMBER 1
 '@S9S_MB_2U_LIB.S9S_MB_2U(SCH_1):PAGE224_I25@PURE_QUANTA.Q_CAP(CHIPS)':
 C_PATH='@s9s_mb_2u_lib.s9s_mb_2u(sch_1):page224_i25@pure_quanta.q_cap(chips)',
 P_PATH='@s9s_mb_2u_lib.s9s_mb_2u(sch_1):page236_i25@pure_quanta.q_cap(chips)',
 PATH='I25',
 DRAWING='@S9S_MB_2U_LIB.S9S_MB_2U(SCH_1):PAGE224',
 PHYS_PAGE='236',
 XY='(-1825,6225)',
 ROT='2',
 VER='1',
 PACK_TYPE='0402',
 CDS_LIB='pure_quanta',
 CDS_PART_NAME='Q_CAP_0402-0.1UF,25V,10%,X7R,CA',
 TOLERANCE='10%',
 MATERIAL='X7R',
 VOLTAGE='25V',
 VALUE='0.1UF',
 PRIM_FILE='./archive_libs/logical/q_cap/chips/chips.prt';

PART_NAME
 C568 'Q_CAP_0402-0.1UF,25V,10%,X7R,CA':;

SECTION_NUMBER 1
 '@S9S_MB_2U_LIB.S9S_MB_2U(SCH_1):PAGE224_I35@PURE_QUANTA.Q_CAP(CHIPS)':
 C_PATH='@s9s_mb_2u_lib.s9s_mb_2u(sch_1):page224_i35@pure_quanta.q_cap(chips)',
 P_PATH='@s9s_mb_2u_lib.s9s_mb_2u(sch_1):page236_i35@pure_quanta.q_cap(chips)',
 PATH='I35',
 DRAWING='@S9S_MB_2U_LIB.S9S_MB_2U(SCH_1):PAGE224',
 PHYS_PAGE='236',
 XY='(-1825,4425)',
 ROT='2',
 VER='1',
 PACK_TYPE='0402',
 CDS_LIB='pure_quanta',
 CDS_PART_NAME='Q_CAP_0402-0.1UF,25V,10%,X7R,CA',
 TOLERANCE='10%',
 MATERIAL='X7R',
 VOLTAGE='25V',
 VALUE='0.1UF',
 PRIM_FILE='./archive_libs/logical/q_cap/chips/chips.prt';

PART_NAME
 C569 'Q_CAP_0402-0.1UF,25V,10%,X7R,CA':;

SECTION_NUMBER 1
 '@S9S_MB_2U_LIB.S9S_MB_2U(SCH_1):PAGE224_I22@PURE_QUANTA.Q_CAP(CHIPS)':
 C_PATH='@s9s_mb_2u_lib.s9s_mb_2u(sch_1):page224_i22@pure_quanta.q_cap(chips)',
 P_PATH='@s9s_mb_2u_lib.s9s_mb_2u(sch_1):page236_i22@pure_quanta.q_cap(chips)',
 PATH='I22',
 DRAWING='@S9S_MB_2U_LIB.S9S_MB_2U(SCH_1):PAGE224',
 PHYS_PAGE='236',
 XY='(-475,6225)',
 ROT='0',
 VER='1',
 PACK_TYPE='0402',
 CDS_LIB='pure_quanta',
 CDS_PART_NAME='Q_CAP_0402-0.1UF,25V,10%,X7R,CA',
 TOLERANCE='10%',
 MATERIAL='X7R',
 VOLTAGE='25V',
 VALUE='0.1UF',
 PRIM_FILE='./archive_libs/logical/q_cap/chips/chips.prt';

PART_NAME
 C570 'Q_CAP_0402-0.1UF,25V,10%,X7R,CA':;

SECTION_NUMBER 1
 '@S9S_MB_2U_LIB.S9S_MB_2U(SCH_1):PAGE224_I33@PURE_QUANTA.Q_CAP(CHIPS)':
 C_PATH='@s9s_mb_2u_lib.s9s_mb_2u(sch_1):page224_i33@pure_quanta.q_cap(chips)',
 P_PATH='@s9s_mb_2u_lib.s9s_mb_2u(sch_1):page236_i33@pure_quanta.q_cap(chips)',
 PATH='I33',
 DRAWING='@S9S_MB_2U_LIB.S9S_MB_2U(SCH_1):PAGE224',
 PHYS_PAGE='236',
 XY='(-475,4425)',
 ROT='0',
 VER='1',
 PACK_TYPE='0402',
 CDS_LIB='pure_quanta',
 CDS_PART_NAME='Q_CAP_0402-0.1UF,25V,10%,X7R,CA',
 TOLERANCE='10%',
 MATERIAL='X7R',
 VOLTAGE='25V',
 VALUE='0.1UF',
 PRIM_FILE='./archive_libs/logical/q_cap/chips/chips.prt';

PART_NAME
 C578 'Q_CAP_0402-0.1UF,25V,10%,X7R,CA':;

SECTION_NUMBER 1
 '@S9S_MB_2U_LIB.S9S_MB_2U(SCH_1):PAGE154_I169@PURE_QUANTA.Q_CAP(CHIPS)':
 C_PATH='@s9s_mb_2u_lib.s9s_mb_2u(sch_1):page154_i169@pure_quanta.q_cap(chips)',
 P_PATH='@s9s_mb_2u_lib.s9s_mb_2u(sch_1):page158_i169@pure_quanta.q_cap(chips)',
 PATH='I169',
 DRAWING='@S9S_MB_2U_LIB.S9S_MB_2U(SCH_1):PAGE154',
 PHYS_PAGE='158',
 XY='(-2350,5500)',
 ROT='0',
 VER='1',
 PACK_TYPE='0402',
 CDS_LIB='pure_quanta',
 CDS_PART_NAME='Q_CAP_0402-0.1UF,25V,10%,X7R,CA',
 TOLERANCE='10%',
 MATERIAL='X7R',
 VOLTAGE='25V',
 VALUE='0.1UF',
 PRIM_FILE='./archive_libs/logical/q_cap/chips/chips.prt';

PART_NAME
 C579 'Q_CAP_0402-0.1UF,25V,10%,X7R,CA':;

SECTION_NUMBER 1
 '@S9S_MB_2U_LIB.S9S_MB_2U(SCH_1):PAGE154_I192@PURE_QUANTA.Q_CAP(CHIPS)':
 C_PATH='@s9s_mb_2u_lib.s9s_mb_2u(sch_1):page154_i192@pure_quanta.q_cap(chips)',
 P_PATH='@s9s_mb_2u_lib.s9s_mb_2u(sch_1):page158_i192@pure_quanta.q_cap(chips)',
 PATH='I192',
 DRAWING='@S9S_MB_2U_LIB.S9S_MB_2U(SCH_1):PAGE154',
 PHYS_PAGE='158',
 XY='(-2475,9900)',
 ROT='0',
 VER='1',
 PACK_TYPE='0402',
 CDS_LIB='pure_quanta',
 CDS_PART_NAME='Q_CAP_0402-0.1UF,25V,10%,X7R,CA',
 TOLERANCE='10%',
 MATERIAL='X7R',
 VOLTAGE='25V',
 VALUE='0.1UF',
 PRIM_FILE='./archive_libs/logical/q_cap/chips/chips.prt';

PART_NAME
 C580 'Q_CAP_0402-0.1UF,25V,10%,X7R,CA':;

SECTION_NUMBER 1
 '@S9S_MB_2U_LIB.S9S_MB_2U(SCH_1):PAGE154_I229@PURE_QUANTA.Q_CAP(CHIPS)':
 C_PATH='@s9s_mb_2u_lib.s9s_mb_2u(sch_1):page154_i229@pure_quanta.q_cap(chips)',
 P_PATH='@s9s_mb_2u_lib.s9s_mb_2u(sch_1):page158_i229@pure_quanta.q_cap(chips)',
 PATH='I229',
 DRAWING='@S9S_MB_2U_LIB.S9S_MB_2U(SCH_1):PAGE154',
 PHYS_PAGE='158',
 XY='(-4175,7150)',
 ROT='2',
 VER='1',
 PACK_TYPE='0402',
 LOCATION='C580',
 CDS_LIB='pure_quanta',
 CDS_PART_NAME='Q_CAP_0402-0.1UF,25V,10%,X7R,CA',
 TOLERANCE='10%',
 MATERIAL='X7R',
 VOLTAGE='25V',
 VALUE='0.1UF',
 PRIM_FILE='./archive_libs/logical/q_cap/chips/chips.prt';

PART_NAME
 C581 'Q_CAP_0402-0.1UF,25V,10%,X7R,CA':;

SECTION_NUMBER 1
 '@S9S_MB_2U_LIB.S9S_MB_2U(SCH_1):PAGE154_I148@PURE_QUANTA.Q_CAP(CHIPS)':
 C_PATH='@s9s_mb_2u_lib.s9s_mb_2u(sch_1):page154_i148@pure_quanta.q_cap(chips)',
 P_PATH='@s9s_mb_2u_lib.s9s_mb_2u(sch_1):page158_i148@pure_quanta.q_cap(chips)',
 PATH='I148',
 DRAWING='@S9S_MB_2U_LIB.S9S_MB_2U(SCH_1):PAGE154',
 PHYS_PAGE='158',
 XY='(3175,7250)',
 ROT='0',
 VER='1',
 PACK_TYPE='0402',
 CDS_LIB='pure_quanta',
 CDS_PART_NAME='Q_CAP_0402-0.1UF,25V,10%,X7R,CA',
 TOLERANCE='10%',
 MATERIAL='X7R',
 VOLTAGE='25V',
 VALUE='0.1UF',
 PRIM_FILE='./archive_libs/logical/q_cap/chips/chips.prt';

PART_NAME
 C590 'Q_CAP_C0402-22UF,4V,20%,X6S,CHA':;

SECTION_NUMBER 1
 '@S9S_MB_2U_LIB.S9S_MB_2U(SCH_1):PAGE74_I102@PURE_QUANTA.Q_CAP(CHIPS)':
 C_PATH='@s9s_mb_2u_lib.s9s_mb_2u(sch_1):page74_i102@pure_quanta.q_cap(chips)',
 P_PATH='@s9s_mb_2u_lib.s9s_mb_2u(sch_1):page74_i102@pure_quanta.q_cap(chips)',
 PATH='I102',
 DRAWING='@S9S_MB_2U_LIB.S9S_MB_2U(SCH_1):PAGE74',
 PHYS_PAGE='74',
 XY='(1025,-150)',
 ROT='0',
 VER='1',
 PACK_TYPE='C0402',
 CDS_LIB='pure_quanta',
 CDS_PART_NAME='Q_CAP_C0402-22UF,4V,20%,X6S,CHA',
 TOLERANCE='20%',
 MATERIAL='X6S',
 VOLTAGE='4V',
 VALUE='22UF',
 PRIM_FILE='./archive_libs/logical/q_cap/chips/chips.prt';

PART_NAME
 C592 'Q_CAP_0402-0.1UF,25V,10%,X7R,CA':;

SECTION_NUMBER 1
 '@S9S_MB_2U_LIB.S9S_MB_2U(SCH_1):PAGE153_I30@PURE_QUANTA.Q_CAP(CHIPS)':
 C_PATH='@s9s_mb_2u_lib.s9s_mb_2u(sch_1):page153_i30@pure_quanta.q_cap(chips)',
 P_PATH='@s9s_mb_2u_lib.s9s_mb_2u(sch_1):page156_i30@pure_quanta.q_cap(chips)',
 PATH='I30',
 DRAWING='@S9S_MB_2U_LIB.S9S_MB_2U(SCH_1):PAGE153',
 PHYS_PAGE='156',
 XY='(5850,9250)',
 ROT='0',
 VER='1',
 PACK_TYPE='0402',
 CDS_LIB='pure_quanta',
 CDS_PART_NAME='Q_CAP_0402-0.1UF,25V,10%,X7R,CA',
 TOLERANCE='10%',
 MATERIAL='X7R',
 VOLTAGE='25V',
 VALUE='0.1UF',
 PRIM_FILE='./archive_libs/logical/q_cap/chips/chips.prt';

PART_NAME
 C593 'Q_CAP_0402-0.1UF,25V,10%,X7R,CA':;

SECTION_NUMBER 1
 '@S9S_MB_2U_LIB.S9S_MB_2U(SCH_1):PAGE153_I27@PURE_QUANTA.Q_CAP(CHIPS)':
 C_PATH='@s9s_mb_2u_lib.s9s_mb_2u(sch_1):page153_i27@pure_quanta.q_cap(chips)',
 P_PATH='@s9s_mb_2u_lib.s9s_mb_2u(sch_1):page156_i27@pure_quanta.q_cap(chips)',
 PATH='I27',
 DRAWING='@S9S_MB_2U_LIB.S9S_MB_2U(SCH_1):PAGE153',
 PHYS_PAGE='156',
 XY='(5850,8350)',
 ROT='0',
 VER='1',
 PACK_TYPE='0402',
 CDS_LIB='pure_quanta',
 CDS_PART_NAME='Q_CAP_0402-0.1UF,25V,10%,X7R,CA',
 TOLERANCE='10%',
 MATERIAL='X7R',
 VOLTAGE='25V',
 VALUE='0.1UF',
 PRIM_FILE='./archive_libs/logical/q_cap/chips/chips.prt';

PART_NAME
 C605 'Q_CAP_C0402-1UF,25V,10%,X6S,CHA':;

SECTION_NUMBER 1
 '@S9S_MB_2U_LIB.S9S_MB_2U(SCH_1):PAGE190_I37@PURE_QUANTA.Q_CAP(CHIPS)':
 C_PATH='@s9s_mb_2u_lib.s9s_mb_2u(sch_1):page190_i37@pure_quanta.q_cap(chips)',
 P_PATH='@s9s_mb_2u_lib.s9s_mb_2u(sch_1):page202_i37@pure_quanta.q_cap(chips)',
 PATH='I37',
 DRAWING='@S9S_MB_2U_LIB.S9S_MB_2U(SCH_1):PAGE190',
 PHYS_PAGE='202',
 XY='(1525,4350)',
 ROT='0',
 VER='1',
 PACK_TYPE='C0402',
 CDS_LIB='pure_quanta',
 CDS_PART_NAME='Q_CAP_C0402-1UF,25V,10%,X6S,CHA',
 TOLERANCE='10%',
 MATERIAL='X6S',
 VOLTAGE='25V',
 VALUE='1UF',
 PRIM_FILE='./archive_libs/logical/q_cap/chips/chips.prt';

PART_NAME
 C606 'Q_CAP_C0402-1UF,25V,10%,X6S,CHA':;

SECTION_NUMBER 1
 '@S9S_MB_2U_LIB.S9S_MB_2U(SCH_1):PAGE190_I45@PURE_QUANTA.Q_CAP(CHIPS)':
 C_PATH='@s9s_mb_2u_lib.s9s_mb_2u(sch_1):page190_i45@pure_quanta.q_cap(chips)',
 P_PATH='@s9s_mb_2u_lib.s9s_mb_2u(sch_1):page202_i45@pure_quanta.q_cap(chips)',
 PATH='I45',
 DRAWING='@S9S_MB_2U_LIB.S9S_MB_2U(SCH_1):PAGE190',
 PHYS_PAGE='202',
 XY='(1525,3175)',
 ROT='0',
 VER='1',
 PACK_TYPE='C0402',
 CDS_LIB='pure_quanta',
 CDS_PART_NAME='Q_CAP_C0402-1UF,25V,10%,X6S,CHA',
 TOLERANCE='10%',
 MATERIAL='X6S',
 VOLTAGE='25V',
 VALUE='1UF',
 PRIM_FILE='./archive_libs/logical/q_cap/chips/chips.prt';

PART_NAME
 C607 'Q_CAP_0402-0.1UF,25V,10%,X7R,CA':;

SECTION_NUMBER 1
 '@S9S_MB_2U_LIB.S9S_MB_2U(SCH_1):PAGE190_I36@PURE_QUANTA.Q_CAP(CHIPS)':
 C_PATH='@s9s_mb_2u_lib.s9s_mb_2u(sch_1):page190_i36@pure_quanta.q_cap(chips)',
 P_PATH='@s9s_mb_2u_lib.s9s_mb_2u(sch_1):page202_i36@pure_quanta.q_cap(chips)',
 PATH='I36',
 DRAWING='@S9S_MB_2U_LIB.S9S_MB_2U(SCH_1):PAGE190',
 PHYS_PAGE='202',
 XY='(1875,4350)',
 ROT='0',
 VER='1',
 PACK_TYPE='0402',
 CDS_LIB='pure_quanta',
 CDS_PART_NAME='Q_CAP_0402-0.1UF,25V,10%,X7R,CA',
 TOLERANCE='10%',
 MATERIAL='X7R',
 VOLTAGE='25V',
 VALUE='0.1UF',
 PRIM_FILE='./archive_libs/logical/q_cap/chips/chips.prt';

PART_NAME
 C608 'Q_CAP_0402-0.1UF,25V,10%,X7R,CA':;

SECTION_NUMBER 1
 '@S9S_MB_2U_LIB.S9S_MB_2U(SCH_1):PAGE190_I43@PURE_QUANTA.Q_CAP(CHIPS)':
 C_PATH='@s9s_mb_2u_lib.s9s_mb_2u(sch_1):page190_i43@pure_quanta.q_cap(chips)',
 P_PATH='@s9s_mb_2u_lib.s9s_mb_2u(sch_1):page202_i43@pure_quanta.q_cap(chips)',
 PATH='I43',
 DRAWING='@S9S_MB_2U_LIB.S9S_MB_2U(SCH_1):PAGE190',
 PHYS_PAGE='202',
 XY='(1875,3175)',
 ROT='0',
 VER='1',
 PACK_TYPE='0402',
 CDS_LIB='pure_quanta',
 CDS_PART_NAME='Q_CAP_0402-0.1UF,25V,10%,X7R,CA',
 TOLERANCE='10%',
 MATERIAL='X7R',
 VOLTAGE='25V',
 VALUE='0.1UF',
 PRIM_FILE='./archive_libs/logical/q_cap/chips/chips.prt';

PART_NAME
 C609 'Q_CAP_0402-0.1UF,25V,10%,X7R,CA':;

SECTION_NUMBER 1
 '@S9S_MB_2U_LIB.S9S_MB_2U(SCH_1):PAGE171_I89@PURE_QUANTA.Q_CAP(CHIPS)':
 C_PATH='@s9s_mb_2u_lib.s9s_mb_2u(sch_1):page171_i89@pure_quanta.q_cap(chips)',
 P_PATH='@s9s_mb_2u_lib.s9s_mb_2u(sch_1):page179_i89@pure_quanta.q_cap(chips)',
 PATH='I89',
 DRAWING='@S9S_MB_2U_LIB.S9S_MB_2U(SCH_1):PAGE171',
 PHYS_PAGE='179',
 XY='(-800,2950)',
 ROT='2',
 VER='1',
 PACK_TYPE='0402',
 CDS_LIB='pure_quanta',
 CDS_PART_NAME='Q_CAP_0402-0.1UF,25V,10%,X7R,CA',
 TOLERANCE='10%',
 MATERIAL='X7R',
 VOLTAGE='25V',
 VALUE='0.1UF',
 PRIM_FILE='./archive_libs/logical/q_cap/chips/chips.prt';

PART_NAME
 C610 'Q_CAP_C0402-1UF,25V,10%,X6S,CHA':;

SECTION_NUMBER 1
 '@S9S_MB_2U_LIB.S9S_MB_2U(SCH_1):PAGE177_I68@PURE_QUANTA.Q_CAP(CHIPS)':
 C_PATH='@s9s_mb_2u_lib.s9s_mb_2u(sch_1):page177_i68@pure_quanta.q_cap(chips)',
 P_PATH='@s9s_mb_2u_lib.s9s_mb_2u(sch_1):page185_i68@pure_quanta.q_cap(chips)',
 PATH='I68',
 DRAWING='@S9S_MB_2U_LIB.S9S_MB_2U(SCH_1):PAGE177',
 PHYS_PAGE='185',
 XY='(-1400,675)',
 ROT='0',
 VER='1',
 PACK_TYPE='C0402',
 CDS_LIB='pure_quanta',
 CDS_PART_NAME='Q_CAP_C0402-1UF,25V,10%,X6S,CHA',
 TOLERANCE='10%',
 MATERIAL='X6S',
 VOLTAGE='25V',
 VALUE='1UF',
 PRIM_FILE='./archive_libs/logical/q_cap/chips/chips.prt';

PART_NAME
 C611 'Q_CAP_C0402-1UF,25V,10%,X6S,CHA':;

SECTION_NUMBER 1
 '@S9S_MB_2U_LIB.S9S_MB_2U(SCH_1):PAGE177_I65@PURE_QUANTA.Q_CAP(CHIPS)':
 C_PATH='@s9s_mb_2u_lib.s9s_mb_2u(sch_1):page177_i65@pure_quanta.q_cap(chips)',
 P_PATH='@s9s_mb_2u_lib.s9s_mb_2u(sch_1):page185_i65@pure_quanta.q_cap(chips)',
 PATH='I65',
 DRAWING='@S9S_MB_2U_LIB.S9S_MB_2U(SCH_1):PAGE177',
 PHYS_PAGE='185',
 XY='(5125,150)',
 ROT='0',
 VER='1',
 PACK_TYPE='C0402',
 CDS_LIB='pure_quanta',
 CDS_PART_NAME='Q_CAP_C0402-1UF,25V,10%,X6S,CHA',
 TOLERANCE='10%',
 MATERIAL='X6S',
 VOLTAGE='25V',
 VALUE='1UF',
 PRIM_FILE='./archive_libs/logical/q_cap/chips/chips.prt';

PART_NAME
 C613 'Q_CAP_C0402-1UF,25V,10%,EMPTY,A':;

SECTION_NUMBER 1
 '@S9S_MB_2U_LIB.S9S_MB_2U(SCH_1):PAGE130_I68@PURE_QUANTA.Q_CAP(CHIPS)':
 C_PATH='@s9s_mb_2u_lib.s9s_mb_2u(sch_1):page130_i68@pure_quanta.q_cap(chips)',
 P_PATH='@s9s_mb_2u_lib.s9s_mb_2u(sch_1):page130_i68@pure_quanta.q_cap(chips)',
 PATH='I68',
 DRAWING='@S9S_MB_2U_LIB.S9S_MB_2U(SCH_1):PAGE130',
 PHYS_PAGE='130',
 XY='(-7750,-650)',
 ROT='2',
 VER='1',
 PACK_TYPE='C0402',
 CDS_LIB='pure_quanta',
 CDS_PART_NAME='Q_CAP_C0402-1UF,25V,10%,EMPTY,A',
 TOLERANCE='10%',
 MATERIAL='EMPTY',
 VOLTAGE='25V',
 VALUE='1UF',
 PRIM_FILE='./archive_libs/logical/q_cap/chips/chips.prt';

PART_NAME
 C614 'Q_CAP_C0402-1UF,25V,10%,EMPTY,A':;

SECTION_NUMBER 1
 '@S9S_MB_2U_LIB.S9S_MB_2U(SCH_1):PAGE130_I65@PURE_QUANTA.Q_CAP(CHIPS)':
 C_PATH='@s9s_mb_2u_lib.s9s_mb_2u(sch_1):page130_i65@pure_quanta.q_cap(chips)',
 P_PATH='@s9s_mb_2u_lib.s9s_mb_2u(sch_1):page130_i65@pure_quanta.q_cap(chips)',
 PATH='I65',
 DRAWING='@S9S_MB_2U_LIB.S9S_MB_2U(SCH_1):PAGE130',
 PHYS_PAGE='130',
 XY='(-7725,3900)',
 ROT='2',
 VER='1',
 PACK_TYPE='C0402',
 CDS_LIB='pure_quanta',
 CDS_PART_NAME='Q_CAP_C0402-1UF,25V,10%,EMPTY,A',
 TOLERANCE='10%',
 MATERIAL='EMPTY',
 VOLTAGE='25V',
 VALUE='1UF',
 PRIM_FILE='./archive_libs/logical/q_cap/chips/chips.prt';

PART_NAME
 C615 'Q_CAP_C0402-1UF,25V,10%,EMPTY,A':;

SECTION_NUMBER 1
 '@S9S_MB_2U_LIB.S9S_MB_2U(SCH_1):PAGE130_I62@PURE_QUANTA.Q_CAP(CHIPS)':
 C_PATH='@s9s_mb_2u_lib.s9s_mb_2u(sch_1):page130_i62@pure_quanta.q_cap(chips)',
 P_PATH='@s9s_mb_2u_lib.s9s_mb_2u(sch_1):page130_i62@pure_quanta.q_cap(chips)',
 PATH='I62',
 DRAWING='@S9S_MB_2U_LIB.S9S_MB_2U(SCH_1):PAGE130',
 PHYS_PAGE='130',
 XY='(-7725,2375)',
 ROT='2',
 VER='1',
 PACK_TYPE='C0402',
 CDS_LIB='pure_quanta',
 CDS_PART_NAME='Q_CAP_C0402-1UF,25V,10%,EMPTY,A',
 TOLERANCE='10%',
 MATERIAL='EMPTY',
 VOLTAGE='25V',
 VALUE='1UF',
 PRIM_FILE='./archive_libs/logical/q_cap/chips/chips.prt';

PART_NAME
 C616 'Q_CAP_C0402-1UF,25V,10%,EMPTY,A':;

SECTION_NUMBER 1
 '@S9S_MB_2U_LIB.S9S_MB_2U(SCH_1):PAGE130_I59@PURE_QUANTA.Q_CAP(CHIPS)':
 C_PATH='@s9s_mb_2u_lib.s9s_mb_2u(sch_1):page130_i59@pure_quanta.q_cap(chips)',
 P_PATH='@s9s_mb_2u_lib.s9s_mb_2u(sch_1):page130_i59@pure_quanta.q_cap(chips)',
 PATH='I59',
 DRAWING='@S9S_MB_2U_LIB.S9S_MB_2U(SCH_1):PAGE130',
 PHYS_PAGE='130',
 XY='(-7725,875)',
 ROT='2',
 VER='1',
 PACK_TYPE='C0402',
 CDS_LIB='pure_quanta',
 CDS_PART_NAME='Q_CAP_C0402-1UF,25V,10%,EMPTY,A',
 TOLERANCE='10%',
 MATERIAL='EMPTY',
 VOLTAGE='25V',
 VALUE='1UF',
 PRIM_FILE='./archive_libs/logical/q_cap/chips/chips.prt';

PART_NAME
 C621 'Q_CAP_C0402-1UF,25V,10%,EMPTY,A':;

SECTION_NUMBER 1
 '@S9S_MB_2U_LIB.S9S_MB_2U(SCH_1):PAGE129_I102@PURE_QUANTA.Q_CAP(CHIPS)':
 C_PATH='@s9s_mb_2u_lib.s9s_mb_2u(sch_1):page129_i102@pure_quanta.q_cap(chips)',
 P_PATH='@s9s_mb_2u_lib.s9s_mb_2u(sch_1):page129_i102@pure_quanta.q_cap(chips)',
 PATH='I102',
 DRAWING='@S9S_MB_2U_LIB.S9S_MB_2U(SCH_1):PAGE129',
 PHYS_PAGE='129',
 XY='(-7475,600)',
 ROT='2',
 VER='1',
 PACK_TYPE='C0402',
 CDS_LIB='pure_quanta',
 CDS_PART_NAME='Q_CAP_C0402-1UF,25V,10%,EMPTY,A',
 TOLERANCE='10%',
 MATERIAL='EMPTY',
 VOLTAGE='25V',
 VALUE='1UF',
 PRIM_FILE='./archive_libs/logical/q_cap/chips/chips.prt';

PART_NAME
 C622 'Q_CAP_C0402-1UF,25V,10%,EMPTY,A':;

SECTION_NUMBER 1
 '@S9S_MB_2U_LIB.S9S_MB_2U(SCH_1):PAGE129_I91@PURE_QUANTA.Q_CAP(CHIPS)':
 C_PATH='@s9s_mb_2u_lib.s9s_mb_2u(sch_1):page129_i91@pure_quanta.q_cap(chips)',
 P_PATH='@s9s_mb_2u_lib.s9s_mb_2u(sch_1):page129_i91@pure_quanta.q_cap(chips)',
 PATH='I91',
 DRAWING='@S9S_MB_2U_LIB.S9S_MB_2U(SCH_1):PAGE129',
 PHYS_PAGE='129',
 XY='(-7475,5150)',
 ROT='2',
 VER='1',
 PACK_TYPE='C0402',
 CDS_LIB='pure_quanta',
 CDS_PART_NAME='Q_CAP_C0402-1UF,25V,10%,EMPTY,A',
 TOLERANCE='10%',
 MATERIAL='EMPTY',
 VOLTAGE='25V',
 VALUE='1UF',
 PRIM_FILE='./archive_libs/logical/q_cap/chips/chips.prt';

PART_NAME
 C623 'Q_CAP_C0402-1UF,25V,10%,EMPTY,A':;

SECTION_NUMBER 1
 '@S9S_MB_2U_LIB.S9S_MB_2U(SCH_1):PAGE129_I94@PURE_QUANTA.Q_CAP(CHIPS)':
 C_PATH='@s9s_mb_2u_lib.s9s_mb_2u(sch_1):page129_i94@pure_quanta.q_cap(chips)',
 P_PATH='@s9s_mb_2u_lib.s9s_mb_2u(sch_1):page129_i94@pure_quanta.q_cap(chips)',
 PATH='I94',
 DRAWING='@S9S_MB_2U_LIB.S9S_MB_2U(SCH_1):PAGE129',
 PHYS_PAGE='129',
 XY='(-7475,3625)',
 ROT='2',
 VER='1',
 PACK_TYPE='C0402',
 CDS_LIB='pure_quanta',
 CDS_PART_NAME='Q_CAP_C0402-1UF,25V,10%,EMPTY,A',
 TOLERANCE='10%',
 MATERIAL='EMPTY',
 VOLTAGE='25V',
 VALUE='1UF',
 PRIM_FILE='./archive_libs/logical/q_cap/chips/chips.prt';

PART_NAME
 C624 'Q_CAP_C0402-1UF,25V,10%,EMPTY,A':;

SECTION_NUMBER 1
 '@S9S_MB_2U_LIB.S9S_MB_2U(SCH_1):PAGE129_I99@PURE_QUANTA.Q_CAP(CHIPS)':
 C_PATH='@s9s_mb_2u_lib.s9s_mb_2u(sch_1):page129_i99@pure_quanta.q_cap(chips)',
 P_PATH='@s9s_mb_2u_lib.s9s_mb_2u(sch_1):page129_i99@pure_quanta.q_cap(chips)',
 PATH='I99',
 DRAWING='@S9S_MB_2U_LIB.S9S_MB_2U(SCH_1):PAGE129',
 PHYS_PAGE='129',
 XY='(-7475,2125)',
 ROT='2',
 VER='1',
 PACK_TYPE='C0402',
 CDS_LIB='pure_quanta',
 CDS_PART_NAME='Q_CAP_C0402-1UF,25V,10%,EMPTY,A',
 TOLERANCE='10%',
 MATERIAL='EMPTY',
 VOLTAGE='25V',
 VALUE='1UF',
 PRIM_FILE='./archive_libs/logical/q_cap/chips/chips.prt';

PART_NAME
 C626 'Q_CAP_0402-1000PF,50V,5%,EMPTYA':;

SECTION_NUMBER 1
 '@S9S_MB_2U_LIB.S9S_MB_2U(SCH_1):PAGE264_I47@PURE_QUANTA.Q_CAP(CHIPS)':
 C_PATH='@s9s_mb_2u_lib.s9s_mb_2u(sch_1):page264_i47@pure_quanta.q_cap(chips)',
 P_PATH='@s9s_mb_2u_lib.s9s_mb_2u(sch_1):page278_i47@pure_quanta.q_cap(chips)',
 PATH='I47',
 DRAWING='@S9S_MB_2U_LIB.S9S_MB_2U(SCH_1):PAGE264',
 PHYS_PAGE='278',
 XY='(-9000,9100)',
 ROT='0',
 VER='2',
 PACK_TYPE='0402',
 LOCATION='C626',
 CDS_LIB='pure_quanta',
 CDS_PART_NAME='Q_CAP_0402-1000PF,50V,5%,EMPTYA',
 TOLERANCE='5%',
 MATERIAL='EMPTY',
 VOLTAGE='50V',
 VALUE='1000PF',
 PRIM_FILE='./archive_libs/logical/q_cap/chips/chips.prt';

PART_NAME
 C629 'Q_CAP_0402-0.1UF,25V,10%,X7R,CA':;

SECTION_NUMBER 1
 '@S9S_MB_2U_LIB.S9S_MB_2U(SCH_1):PAGE231_I55@PURE_QUANTA.Q_CAP(CHIPS)':
 C_PATH='@s9s_mb_2u_lib.s9s_mb_2u(sch_1):page231_i55@pure_quanta.q_cap(chips)',
 P_PATH='@s9s_mb_2u_lib.s9s_mb_2u(sch_1):page243_i55@pure_quanta.q_cap(chips)',
 PATH='I55',
 DRAWING='@S9S_MB_2U_LIB.S9S_MB_2U(SCH_1):PAGE231',
 PHYS_PAGE='243',
 XY='(-425,2575)',
 ROT='2',
 VER='1',
 PACK_TYPE='0402',
 CDS_LIB='pure_quanta',
 CDS_PART_NAME='Q_CAP_0402-0.1UF,25V,10%,X7R,CA',
 TOLERANCE='10%',
 MATERIAL='X7R',
 VOLTAGE='25V',
 VALUE='0.1UF',
 PRIM_FILE='./archive_libs/logical/q_cap/chips/chips.prt';

PART_NAME
 C639 'Q_CAP_0402-0.1UF,25V,10%,X7R,CA':;

SECTION_NUMBER 1
 '@S9S_MB_2U_LIB.S9S_MB_2U(SCH_1):PAGE151_I22@PURE_QUANTA.Q_CAP(CHIPS)':
 C_PATH='@s9s_mb_2u_lib.s9s_mb_2u(sch_1):page151_i22@pure_quanta.q_cap(chips)',
 P_PATH='@s9s_mb_2u_lib.s9s_mb_2u(sch_1):page154_i22@pure_quanta.q_cap(chips)',
 PATH='I22',
 DRAWING='@S9S_MB_2U_LIB.S9S_MB_2U(SCH_1):PAGE151',
 PHYS_PAGE='154',
 XY='(-3475,4150)',
 ROT='2',
 VER='1',
 PACK_TYPE='0402',
 CDS_LIB='pure_quanta',
 CDS_PART_NAME='Q_CAP_0402-0.1UF,25V,10%,X7R,CA',
 TOLERANCE='10%',
 MATERIAL='X7R',
 VOLTAGE='25V',
 VALUE='0.1UF',
 PRIM_FILE='./archive_libs/logical/q_cap/chips/chips.prt';

PART_NAME
 C640 'Q_CAP_0402-0.1UF,25V,10%,X7R,CA':;

SECTION_NUMBER 1
 '@S9S_MB_2U_LIB.S9S_MB_2U(SCH_1):PAGE151_I40@PURE_QUANTA.Q_CAP(CHIPS)':
 C_PATH='@s9s_mb_2u_lib.s9s_mb_2u(sch_1):page151_i40@pure_quanta.q_cap(chips)',
 P_PATH='@s9s_mb_2u_lib.s9s_mb_2u(sch_1):page154_i40@pure_quanta.q_cap(chips)',
 PATH='I40',
 DRAWING='@S9S_MB_2U_LIB.S9S_MB_2U(SCH_1):PAGE151',
 PHYS_PAGE='154',
 XY='(-2375,6950)',
 ROT='2',
 VER='1',
 PACK_TYPE='0402',
 CDS_LIB='pure_quanta',
 CDS_PART_NAME='Q_CAP_0402-0.1UF,25V,10%,X7R,CA',
 TOLERANCE='10%',
 MATERIAL='X7R',
 VOLTAGE='25V',
 VALUE='0.1UF',
 PRIM_FILE='./archive_libs/logical/q_cap/chips/chips.prt';

PART_NAME
 C641 'Q_CAP_0402-0.1UF,25V,10%,X7R,CA':;

SECTION_NUMBER 1
 '@S9S_MB_2U_LIB.S9S_MB_2U(SCH_1):PAGE151_I32@PURE_QUANTA.Q_CAP(CHIPS)':
 C_PATH='@s9s_mb_2u_lib.s9s_mb_2u(sch_1):page151_i32@pure_quanta.q_cap(chips)',
 P_PATH='@s9s_mb_2u_lib.s9s_mb_2u(sch_1):page154_i32@pure_quanta.q_cap(chips)',
 PATH='I32',
 DRAWING='@S9S_MB_2U_LIB.S9S_MB_2U(SCH_1):PAGE151',
 PHYS_PAGE='154',
 XY='(-2375,5525)',
 ROT='2',
 VER='1',
 PACK_TYPE='0402',
 CDS_LIB='pure_quanta',
 CDS_PART_NAME='Q_CAP_0402-0.1UF,25V,10%,X7R,CA',
 TOLERANCE='10%',
 MATERIAL='X7R',
 VOLTAGE='25V',
 VALUE='0.1UF',
 PRIM_FILE='./archive_libs/logical/q_cap/chips/chips.prt';

PART_NAME
 C678 'Q_CAP_DIFFBUS_C0201-DIFF BUS_0A':;

SECTION_NUMBER 1
 '@S9S_MB_2U_LIB.S9S_MB_2U(SCH_1):PAGE168_I172@PURE_QUANTA.Q_CAP_DIFFBUS(CHIPS)':
 C_PATH='@s9s_mb_2u_lib.s9s_mb_2u(sch_1):page168_i172@pure_quanta.q_cap_diffbus(~
chips)',
 P_PATH='@s9s_mb_2u_lib.s9s_mb_2u(sch_1):page177_i172@pure_quanta.q_cap_diffbus(~
chips)',
 PATH='I172',
 DRAWING='@S9S_MB_2U_LIB.S9S_MB_2U(SCH_1):PAGE168',
 PIN_NAMES_ROTATE='TRUE',
 PHYS_PAGE='177',
 XY='(3150,3550)',
 ROT='2',
 VER='2',
 PACK_TYPE='C0201',
 CDS_LIB='pure_quanta',
 CDS_PART_NAME='Q_CAP_DIFFBUS_C0201-DIFF BUS_0A',
 TOLERANCE='20%',
 MATERIAL='X6S',
 VOLTAGE='6.3V',
 VALUE='DIFF BUS_0.22UF',
 PRIM_FILE='./archive_libs/logical/q_cap_diffbus/chips/chips.prt';

PART_NAME
 C679 'Q_CAP_DIFFBUS_C0201-DIFF BUS_0A':;

SECTION_NUMBER 1
 '@S9S_MB_2U_LIB.S9S_MB_2U(SCH_1):PAGE168_I169@PURE_QUANTA.Q_CAP_DIFFBUS(CHIPS)':
 C_PATH='@s9s_mb_2u_lib.s9s_mb_2u(sch_1):page168_i169@pure_quanta.q_cap_diffbus(~
chips)',
 P_PATH='@s9s_mb_2u_lib.s9s_mb_2u(sch_1):page177_i169@pure_quanta.q_cap_diffbus(~
chips)',
 PATH='I169',
 DRAWING='@S9S_MB_2U_LIB.S9S_MB_2U(SCH_1):PAGE168',
 PIN_NAMES_ROTATE='TRUE',
 PHYS_PAGE='177',
 XY='(3150,3500)',
 ROT='2',
 VER='2',
 PACK_TYPE='C0201',
 CDS_LIB='pure_quanta',
 CDS_PART_NAME='Q_CAP_DIFFBUS_C0201-DIFF BUS_0A',
 TOLERANCE='20%',
 MATERIAL='X6S',
 VOLTAGE='6.3V',
 VALUE='DIFF BUS_0.22UF',
 PRIM_FILE='./archive_libs/logical/q_cap_diffbus/chips/chips.prt';

PART_NAME
 C680 'Q_CAP_DIFFBUS_C0201-DIFF BUS_0A':;

SECTION_NUMBER 1
 '@S9S_MB_2U_LIB.S9S_MB_2U(SCH_1):PAGE168_I170@PURE_QUANTA.Q_CAP_DIFFBUS(CHIPS)':
 C_PATH='@s9s_mb_2u_lib.s9s_mb_2u(sch_1):page168_i170@pure_quanta.q_cap_diffbus(~
chips)',
 P_PATH='@s9s_mb_2u_lib.s9s_mb_2u(sch_1):page177_i170@pure_quanta.q_cap_diffbus(~
chips)',
 PATH='I170',
 DRAWING='@S9S_MB_2U_LIB.S9S_MB_2U(SCH_1):PAGE168',
 PIN_NAMES_ROTATE='TRUE',
 PHYS_PAGE='177',
 XY='(3150,3350)',
 ROT='2',
 VER='2',
 PACK_TYPE='C0201',
 CDS_LIB='pure_quanta',
 CDS_PART_NAME='Q_CAP_DIFFBUS_C0201-DIFF BUS_0A',
 TOLERANCE='20%',
 MATERIAL='X6S',
 VOLTAGE='6.3V',
 VALUE='DIFF BUS_0.22UF',
 PRIM_FILE='./archive_libs/logical/q_cap_diffbus/chips/chips.prt';

PART_NAME
 C681 'Q_CAP_DIFFBUS_C0201-DIFF BUS_0A':;

SECTION_NUMBER 1
 '@S9S_MB_2U_LIB.S9S_MB_2U(SCH_1):PAGE168_I171@PURE_QUANTA.Q_CAP_DIFFBUS(CHIPS)':
 C_PATH='@s9s_mb_2u_lib.s9s_mb_2u(sch_1):page168_i171@pure_quanta.q_cap_diffbus(~
chips)',
 P_PATH='@s9s_mb_2u_lib.s9s_mb_2u(sch_1):page177_i171@pure_quanta.q_cap_diffbus(~
chips)',
 PATH='I171',
 DRAWING='@S9S_MB_2U_LIB.S9S_MB_2U(SCH_1):PAGE168',
 PIN_NAMES_ROTATE='TRUE',
 PHYS_PAGE='177',
 XY='(3150,3300)',
 ROT='2',
 VER='2',
 PACK_TYPE='C0201',
 CDS_LIB='pure_quanta',
 CDS_PART_NAME='Q_CAP_DIFFBUS_C0201-DIFF BUS_0A',
 TOLERANCE='20%',
 MATERIAL='X6S',
 VOLTAGE='6.3V',
 VALUE='DIFF BUS_0.22UF',
 PRIM_FILE='./archive_libs/logical/q_cap_diffbus/chips/chips.prt';

PART_NAME
 C682 'Q_CAP_DIFFBUS_C0201-DIFF BUS_0A':;

SECTION_NUMBER 1
 '@S9S_MB_2U_LIB.S9S_MB_2U(SCH_1):PAGE168_I167@PURE_QUANTA.Q_CAP_DIFFBUS(CHIPS)':
 C_PATH='@s9s_mb_2u_lib.s9s_mb_2u(sch_1):page168_i167@pure_quanta.q_cap_diffbus(~
chips)',
 P_PATH='@s9s_mb_2u_lib.s9s_mb_2u(sch_1):page177_i167@pure_quanta.q_cap_diffbus(~
chips)',
 PATH='I167',
 DRAWING='@S9S_MB_2U_LIB.S9S_MB_2U(SCH_1):PAGE168',
 PIN_NAMES_ROTATE='TRUE',
 PHYS_PAGE='177',
 XY='(3150,3150)',
 ROT='2',
 VER='2',
 PACK_TYPE='C0201',
 CDS_LIB='pure_quanta',
 CDS_PART_NAME='Q_CAP_DIFFBUS_C0201-DIFF BUS_0A',
 TOLERANCE='20%',
 MATERIAL='X6S',
 VOLTAGE='6.3V',
 VALUE='DIFF BUS_0.22UF',
 PRIM_FILE='./archive_libs/logical/q_cap_diffbus/chips/chips.prt';

PART_NAME
 C683 'Q_CAP_DIFFBUS_C0201-DIFF BUS_0A':;

SECTION_NUMBER 1
 '@S9S_MB_2U_LIB.S9S_MB_2U(SCH_1):PAGE168_I168@PURE_QUANTA.Q_CAP_DIFFBUS(CHIPS)':
 C_PATH='@s9s_mb_2u_lib.s9s_mb_2u(sch_1):page168_i168@pure_quanta.q_cap_diffbus(~
chips)',
 P_PATH='@s9s_mb_2u_lib.s9s_mb_2u(sch_1):page177_i168@pure_quanta.q_cap_diffbus(~
chips)',
 PATH='I168',
 DRAWING='@S9S_MB_2U_LIB.S9S_MB_2U(SCH_1):PAGE168',
 PIN_NAMES_ROTATE='TRUE',
 PHYS_PAGE='177',
 XY='(3150,3100)',
 ROT='2',
 VER='2',
 PACK_TYPE='C0201',
 CDS_LIB='pure_quanta',
 CDS_PART_NAME='Q_CAP_DIFFBUS_C0201-DIFF BUS_0A',
 TOLERANCE='20%',
 MATERIAL='X6S',
 VOLTAGE='6.3V',
 VALUE='DIFF BUS_0.22UF',
 PRIM_FILE='./archive_libs/logical/q_cap_diffbus/chips/chips.prt';

PART_NAME
 C684 'Q_CAP_DIFFBUS_C0201-DIFF BUS_0A':;

SECTION_NUMBER 1
 '@S9S_MB_2U_LIB.S9S_MB_2U(SCH_1):PAGE168_I166@PURE_QUANTA.Q_CAP_DIFFBUS(CHIPS)':
 C_PATH='@s9s_mb_2u_lib.s9s_mb_2u(sch_1):page168_i166@pure_quanta.q_cap_diffbus(~
chips)',
 P_PATH='@s9s_mb_2u_lib.s9s_mb_2u(sch_1):page177_i166@pure_quanta.q_cap_diffbus(~
chips)',
 PATH='I166',
 DRAWING='@S9S_MB_2U_LIB.S9S_MB_2U(SCH_1):PAGE168',
 PIN_NAMES_ROTATE='TRUE',
 PHYS_PAGE='177',
 XY='(3150,2950)',
 ROT='2',
 VER='2',
 PACK_TYPE='C0201',
 CDS_LIB='pure_quanta',
 CDS_PART_NAME='Q_CAP_DIFFBUS_C0201-DIFF BUS_0A',
 TOLERANCE='20%',
 MATERIAL='X6S',
 VOLTAGE='6.3V',
 VALUE='DIFF BUS_0.22UF',
 PRIM_FILE='./archive_libs/logical/q_cap_diffbus/chips/chips.prt';

PART_NAME
 C685 'Q_CAP_DIFFBUS_C0201-DIFF BUS_0A':;

SECTION_NUMBER 1
 '@S9S_MB_2U_LIB.S9S_MB_2U(SCH_1):PAGE168_I165@PURE_QUANTA.Q_CAP_DIFFBUS(CHIPS)':
 C_PATH='@s9s_mb_2u_lib.s9s_mb_2u(sch_1):page168_i165@pure_quanta.q_cap_diffbus(~
chips)',
 P_PATH='@s9s_mb_2u_lib.s9s_mb_2u(sch_1):page177_i165@pure_quanta.q_cap_diffbus(~
chips)',
 PATH='I165',
 DRAWING='@S9S_MB_2U_LIB.S9S_MB_2U(SCH_1):PAGE168',
 PIN_NAMES_ROTATE='TRUE',
 PHYS_PAGE='177',
 XY='(3150,2900)',
 ROT='2',
 VER='2',
 PACK_TYPE='C0201',
 CDS_LIB='pure_quanta',
 CDS_PART_NAME='Q_CAP_DIFFBUS_C0201-DIFF BUS_0A',
 TOLERANCE='20%',
 MATERIAL='X6S',
 VOLTAGE='6.3V',
 VALUE='DIFF BUS_0.22UF',
 PRIM_FILE='./archive_libs/logical/q_cap_diffbus/chips/chips.prt';

PART_NAME
 C686 'Q_CAP_DIFFBUS_C0201-DIFF BUS_0A':;

SECTION_NUMBER 1
 '@S9S_MB_2U_LIB.S9S_MB_2U(SCH_1):PAGE168_I164@PURE_QUANTA.Q_CAP_DIFFBUS(CHIPS)':
 C_PATH='@s9s_mb_2u_lib.s9s_mb_2u(sch_1):page168_i164@pure_quanta.q_cap_diffbus(~
chips)',
 P_PATH='@s9s_mb_2u_lib.s9s_mb_2u(sch_1):page177_i164@pure_quanta.q_cap_diffbus(~
chips)',
 PATH='I164',
 DRAWING='@S9S_MB_2U_LIB.S9S_MB_2U(SCH_1):PAGE168',
 PIN_NAMES_ROTATE='TRUE',
 PHYS_PAGE='177',
 XY='(3150,2750)',
 ROT='2',
 VER='2',
 PACK_TYPE='C0201',
 CDS_LIB='pure_quanta',
 CDS_PART_NAME='Q_CAP_DIFFBUS_C0201-DIFF BUS_0A',
 TOLERANCE='20%',
 MATERIAL='X6S',
 VOLTAGE='6.3V',
 VALUE='DIFF BUS_0.22UF',
 PRIM_FILE='./archive_libs/logical/q_cap_diffbus/chips/chips.prt';

PART_NAME
 C687 'Q_CAP_DIFFBUS_C0201-DIFF BUS_0A':;

SECTION_NUMBER 1
 '@S9S_MB_2U_LIB.S9S_MB_2U(SCH_1):PAGE168_I161@PURE_QUANTA.Q_CAP_DIFFBUS(CHIPS)':
 C_PATH='@s9s_mb_2u_lib.s9s_mb_2u(sch_1):page168_i161@pure_quanta.q_cap_diffbus(~
chips)',
 P_PATH='@s9s_mb_2u_lib.s9s_mb_2u(sch_1):page177_i161@pure_quanta.q_cap_diffbus(~
chips)',
 PATH='I161',
 DRAWING='@S9S_MB_2U_LIB.S9S_MB_2U(SCH_1):PAGE168',
 PIN_NAMES_ROTATE='TRUE',
 PHYS_PAGE='177',
 XY='(3150,2700)',
 ROT='2',
 VER='2',
 PACK_TYPE='C0201',
 CDS_LIB='pure_quanta',
 CDS_PART_NAME='Q_CAP_DIFFBUS_C0201-DIFF BUS_0A',
 TOLERANCE='20%',
 MATERIAL='X6S',
 VOLTAGE='6.3V',
 VALUE='DIFF BUS_0.22UF',
 PRIM_FILE='./archive_libs/logical/q_cap_diffbus/chips/chips.prt';

PART_NAME
 C688 'Q_CAP_DIFFBUS_C0201-DIFF BUS_0A':;

SECTION_NUMBER 1
 '@S9S_MB_2U_LIB.S9S_MB_2U(SCH_1):PAGE168_I162@PURE_QUANTA.Q_CAP_DIFFBUS(CHIPS)':
 C_PATH='@s9s_mb_2u_lib.s9s_mb_2u(sch_1):page168_i162@pure_quanta.q_cap_diffbus(~
chips)',
 P_PATH='@s9s_mb_2u_lib.s9s_mb_2u(sch_1):page177_i162@pure_quanta.q_cap_diffbus(~
chips)',
 PATH='I162',
 DRAWING='@S9S_MB_2U_LIB.S9S_MB_2U(SCH_1):PAGE168',
 PIN_NAMES_ROTATE='TRUE',
 PHYS_PAGE='177',
 XY='(3150,2550)',
 ROT='2',
 VER='2',
 PACK_TYPE='C0201',
 CDS_LIB='pure_quanta',
 CDS_PART_NAME='Q_CAP_DIFFBUS_C0201-DIFF BUS_0A',
 TOLERANCE='20%',
 MATERIAL='X6S',
 VOLTAGE='6.3V',
 VALUE='DIFF BUS_0.22UF',
 PRIM_FILE='./archive_libs/logical/q_cap_diffbus/chips/chips.prt';

PART_NAME
 C689 'Q_CAP_DIFFBUS_C0201-DIFF BUS_0A':;

SECTION_NUMBER 1
 '@S9S_MB_2U_LIB.S9S_MB_2U(SCH_1):PAGE168_I163@PURE_QUANTA.Q_CAP_DIFFBUS(CHIPS)':
 C_PATH='@s9s_mb_2u_lib.s9s_mb_2u(sch_1):page168_i163@pure_quanta.q_cap_diffbus(~
chips)',
 P_PATH='@s9s_mb_2u_lib.s9s_mb_2u(sch_1):page177_i163@pure_quanta.q_cap_diffbus(~
chips)',
 PATH='I163',
 DRAWING='@S9S_MB_2U_LIB.S9S_MB_2U(SCH_1):PAGE168',
 PIN_NAMES_ROTATE='TRUE',
 PHYS_PAGE='177',
 XY='(3150,2500)',
 ROT='2',
 VER='2',
 PACK_TYPE='C0201',
 CDS_LIB='pure_quanta',
 CDS_PART_NAME='Q_CAP_DIFFBUS_C0201-DIFF BUS_0A',
 TOLERANCE='20%',
 MATERIAL='X6S',
 VOLTAGE='6.3V',
 VALUE='DIFF BUS_0.22UF',
 PRIM_FILE='./archive_libs/logical/q_cap_diffbus/chips/chips.prt';

PART_NAME
 C690 'Q_CAP_DIFFBUS_C0201-DIFF BUS_0A':;

SECTION_NUMBER 1
 '@S9S_MB_2U_LIB.S9S_MB_2U(SCH_1):PAGE168_I159@PURE_QUANTA.Q_CAP_DIFFBUS(CHIPS)':
 C_PATH='@s9s_mb_2u_lib.s9s_mb_2u(sch_1):page168_i159@pure_quanta.q_cap_diffbus(~
chips)',
 P_PATH='@s9s_mb_2u_lib.s9s_mb_2u(sch_1):page177_i159@pure_quanta.q_cap_diffbus(~
chips)',
 PATH='I159',
 DRAWING='@S9S_MB_2U_LIB.S9S_MB_2U(SCH_1):PAGE168',
 PIN_NAMES_ROTATE='TRUE',
 PHYS_PAGE='177',
 XY='(3150,2350)',
 ROT='2',
 VER='2',
 PACK_TYPE='C0201',
 CDS_LIB='pure_quanta',
 CDS_PART_NAME='Q_CAP_DIFFBUS_C0201-DIFF BUS_0A',
 TOLERANCE='20%',
 MATERIAL='X6S',
 VOLTAGE='6.3V',
 VALUE='DIFF BUS_0.22UF',
 PRIM_FILE='./archive_libs/logical/q_cap_diffbus/chips/chips.prt';

PART_NAME
 C691 'Q_CAP_DIFFBUS_C0201-DIFF BUS_0A':;

SECTION_NUMBER 1
 '@S9S_MB_2U_LIB.S9S_MB_2U(SCH_1):PAGE168_I160@PURE_QUANTA.Q_CAP_DIFFBUS(CHIPS)':
 C_PATH='@s9s_mb_2u_lib.s9s_mb_2u(sch_1):page168_i160@pure_quanta.q_cap_diffbus(~
chips)',
 P_PATH='@s9s_mb_2u_lib.s9s_mb_2u(sch_1):page177_i160@pure_quanta.q_cap_diffbus(~
chips)',
 PATH='I160',
 DRAWING='@S9S_MB_2U_LIB.S9S_MB_2U(SCH_1):PAGE168',
 PIN_NAMES_ROTATE='TRUE',
 PHYS_PAGE='177',
 XY='(3150,2300)',
 ROT='2',
 VER='2',
 PACK_TYPE='C0201',
 CDS_LIB='pure_quanta',
 CDS_PART_NAME='Q_CAP_DIFFBUS_C0201-DIFF BUS_0A',
 TOLERANCE='20%',
 MATERIAL='X6S',
 VOLTAGE='6.3V',
 VALUE='DIFF BUS_0.22UF',
 PRIM_FILE='./archive_libs/logical/q_cap_diffbus/chips/chips.prt';

PART_NAME
 C692 'Q_CAP_DIFFBUS_C0201-DIFF BUS_0A':;

SECTION_NUMBER 1
 '@S9S_MB_2U_LIB.S9S_MB_2U(SCH_1):PAGE168_I158@PURE_QUANTA.Q_CAP_DIFFBUS(CHIPS)':
 C_PATH='@s9s_mb_2u_lib.s9s_mb_2u(sch_1):page168_i158@pure_quanta.q_cap_diffbus(~
chips)',
 P_PATH='@s9s_mb_2u_lib.s9s_mb_2u(sch_1):page177_i158@pure_quanta.q_cap_diffbus(~
chips)',
 PATH='I158',
 DRAWING='@S9S_MB_2U_LIB.S9S_MB_2U(SCH_1):PAGE168',
 PIN_NAMES_ROTATE='TRUE',
 PHYS_PAGE='177',
 XY='(3150,2150)',
 ROT='2',
 VER='2',
 PACK_TYPE='C0201',
 CDS_LIB='pure_quanta',
 CDS_PART_NAME='Q_CAP_DIFFBUS_C0201-DIFF BUS_0A',
 TOLERANCE='20%',
 MATERIAL='X6S',
 VOLTAGE='6.3V',
 VALUE='DIFF BUS_0.22UF',
 PRIM_FILE='./archive_libs/logical/q_cap_diffbus/chips/chips.prt';

PART_NAME
 C693 'Q_CAP_DIFFBUS_C0201-DIFF BUS_0A':;

SECTION_NUMBER 1
 '@S9S_MB_2U_LIB.S9S_MB_2U(SCH_1):PAGE168_I157@PURE_QUANTA.Q_CAP_DIFFBUS(CHIPS)':
 C_PATH='@s9s_mb_2u_lib.s9s_mb_2u(sch_1):page168_i157@pure_quanta.q_cap_diffbus(~
chips)',
 P_PATH='@s9s_mb_2u_lib.s9s_mb_2u(sch_1):page177_i157@pure_quanta.q_cap_diffbus(~
chips)',
 PATH='I157',
 DRAWING='@S9S_MB_2U_LIB.S9S_MB_2U(SCH_1):PAGE168',
 PIN_NAMES_ROTATE='TRUE',
 PHYS_PAGE='177',
 XY='(3150,2100)',
 ROT='2',
 VER='2',
 PACK_TYPE='C0201',
 CDS_LIB='pure_quanta',
 CDS_PART_NAME='Q_CAP_DIFFBUS_C0201-DIFF BUS_0A',
 TOLERANCE='20%',
 MATERIAL='X6S',
 VOLTAGE='6.3V',
 VALUE='DIFF BUS_0.22UF',
 PRIM_FILE='./archive_libs/logical/q_cap_diffbus/chips/chips.prt';

PART_NAME
 C694 'Q_CAP_DIFFBUS_C0201-DIFF BUS_0A':;

SECTION_NUMBER 1
 '@S9S_MB_2U_LIB.S9S_MB_2U(SCH_1):PAGE168_I140@PURE_QUANTA.Q_CAP_DIFFBUS(CHIPS)':
 C_PATH='@s9s_mb_2u_lib.s9s_mb_2u(sch_1):page168_i140@pure_quanta.q_cap_diffbus(~
chips)',
 P_PATH='@s9s_mb_2u_lib.s9s_mb_2u(sch_1):page177_i140@pure_quanta.q_cap_diffbus(~
chips)',
 PATH='I140',
 DRAWING='@S9S_MB_2U_LIB.S9S_MB_2U(SCH_1):PAGE168',
 PIN_NAMES_ROTATE='TRUE',
 PHYS_PAGE='177',
 XY='(3150,1575)',
 ROT='2',
 VER='2',
 PACK_TYPE='C0201',
 CDS_LIB='pure_quanta',
 CDS_PART_NAME='Q_CAP_DIFFBUS_C0201-DIFF BUS_0A',
 TOLERANCE='20%',
 MATERIAL='X6S',
 VOLTAGE='6.3V',
 VALUE='DIFF BUS_0.22UF',
 PRIM_FILE='./archive_libs/logical/q_cap_diffbus/chips/chips.prt';

PART_NAME
 C695 'Q_CAP_DIFFBUS_C0201-DIFF BUS_0A':;

SECTION_NUMBER 1
 '@S9S_MB_2U_LIB.S9S_MB_2U(SCH_1):PAGE168_I139@PURE_QUANTA.Q_CAP_DIFFBUS(CHIPS)':
 C_PATH='@s9s_mb_2u_lib.s9s_mb_2u(sch_1):page168_i139@pure_quanta.q_cap_diffbus(~
chips)',
 P_PATH='@s9s_mb_2u_lib.s9s_mb_2u(sch_1):page177_i139@pure_quanta.q_cap_diffbus(~
chips)',
 PATH='I139',
 DRAWING='@S9S_MB_2U_LIB.S9S_MB_2U(SCH_1):PAGE168',
 PIN_NAMES_ROTATE='TRUE',
 PHYS_PAGE='177',
 XY='(3150,1525)',
 ROT='2',
 VER='2',
 PACK_TYPE='C0201',
 CDS_LIB='pure_quanta',
 CDS_PART_NAME='Q_CAP_DIFFBUS_C0201-DIFF BUS_0A',
 TOLERANCE='20%',
 MATERIAL='X6S',
 VOLTAGE='6.3V',
 VALUE='DIFF BUS_0.22UF',
 PRIM_FILE='./archive_libs/logical/q_cap_diffbus/chips/chips.prt';

PART_NAME
 C696 'Q_CAP_DIFFBUS_C0201-DIFF BUS_0A':;

SECTION_NUMBER 1
 '@S9S_MB_2U_LIB.S9S_MB_2U(SCH_1):PAGE168_I137@PURE_QUANTA.Q_CAP_DIFFBUS(CHIPS)':
 C_PATH='@s9s_mb_2u_lib.s9s_mb_2u(sch_1):page168_i137@pure_quanta.q_cap_diffbus(~
chips)',
 P_PATH='@s9s_mb_2u_lib.s9s_mb_2u(sch_1):page177_i137@pure_quanta.q_cap_diffbus(~
chips)',
 PATH='I137',
 DRAWING='@S9S_MB_2U_LIB.S9S_MB_2U(SCH_1):PAGE168',
 PIN_NAMES_ROTATE='TRUE',
 PHYS_PAGE='177',
 XY='(3150,1375)',
 ROT='2',
 VER='2',
 PACK_TYPE='C0201',
 CDS_LIB='pure_quanta',
 CDS_PART_NAME='Q_CAP_DIFFBUS_C0201-DIFF BUS_0A',
 TOLERANCE='20%',
 MATERIAL='X6S',
 VOLTAGE='6.3V',
 VALUE='DIFF BUS_0.22UF',
 PRIM_FILE='./archive_libs/logical/q_cap_diffbus/chips/chips.prt';

PART_NAME
 C697 'Q_CAP_DIFFBUS_C0201-DIFF BUS_0A':;

SECTION_NUMBER 1
 '@S9S_MB_2U_LIB.S9S_MB_2U(SCH_1):PAGE168_I138@PURE_QUANTA.Q_CAP_DIFFBUS(CHIPS)':
 C_PATH='@s9s_mb_2u_lib.s9s_mb_2u(sch_1):page168_i138@pure_quanta.q_cap_diffbus(~
chips)',
 P_PATH='@s9s_mb_2u_lib.s9s_mb_2u(sch_1):page177_i138@pure_quanta.q_cap_diffbus(~
chips)',
 PATH='I138',
 DRAWING='@S9S_MB_2U_LIB.S9S_MB_2U(SCH_1):PAGE168',
 PIN_NAMES_ROTATE='TRUE',
 PHYS_PAGE='177',
 XY='(3150,1325)',
 ROT='2',
 VER='2',
 PACK_TYPE='C0201',
 CDS_LIB='pure_quanta',
 CDS_PART_NAME='Q_CAP_DIFFBUS_C0201-DIFF BUS_0A',
 TOLERANCE='20%',
 MATERIAL='X6S',
 VOLTAGE='6.3V',
 VALUE='DIFF BUS_0.22UF',
 PRIM_FILE='./archive_libs/logical/q_cap_diffbus/chips/chips.prt';

PART_NAME
 C698 'Q_CAP_DIFFBUS_C0201-DIFF BUS_0A':;

SECTION_NUMBER 1
 '@S9S_MB_2U_LIB.S9S_MB_2U(SCH_1):PAGE168_I135@PURE_QUANTA.Q_CAP_DIFFBUS(CHIPS)':
 C_PATH='@s9s_mb_2u_lib.s9s_mb_2u(sch_1):page168_i135@pure_quanta.q_cap_diffbus(~
chips)',
 P_PATH='@s9s_mb_2u_lib.s9s_mb_2u(sch_1):page177_i135@pure_quanta.q_cap_diffbus(~
chips)',
 PATH='I135',
 DRAWING='@S9S_MB_2U_LIB.S9S_MB_2U(SCH_1):PAGE168',
 PIN_NAMES_ROTATE='TRUE',
 PHYS_PAGE='177',
 XY='(3150,1175)',
 ROT='2',
 VER='2',
 PACK_TYPE='C0201',
 CDS_LIB='pure_quanta',
 CDS_PART_NAME='Q_CAP_DIFFBUS_C0201-DIFF BUS_0A',
 TOLERANCE='20%',
 MATERIAL='X6S',
 VOLTAGE='6.3V',
 VALUE='DIFF BUS_0.22UF',
 PRIM_FILE='./archive_libs/logical/q_cap_diffbus/chips/chips.prt';

PART_NAME
 C699 'Q_CAP_DIFFBUS_C0201-DIFF BUS_0A':;

SECTION_NUMBER 1
 '@S9S_MB_2U_LIB.S9S_MB_2U(SCH_1):PAGE168_I136@PURE_QUANTA.Q_CAP_DIFFBUS(CHIPS)':
 C_PATH='@s9s_mb_2u_lib.s9s_mb_2u(sch_1):page168_i136@pure_quanta.q_cap_diffbus(~
chips)',
 P_PATH='@s9s_mb_2u_lib.s9s_mb_2u(sch_1):page177_i136@pure_quanta.q_cap_diffbus(~
chips)',
 PATH='I136',
 DRAWING='@S9S_MB_2U_LIB.S9S_MB_2U(SCH_1):PAGE168',
 PIN_NAMES_ROTATE='TRUE',
 PHYS_PAGE='177',
 XY='(3150,1125)',
 ROT='2',
 VER='2',
 PACK_TYPE='C0201',
 CDS_LIB='pure_quanta',
 CDS_PART_NAME='Q_CAP_DIFFBUS_C0201-DIFF BUS_0A',
 TOLERANCE='20%',
 MATERIAL='X6S',
 VOLTAGE='6.3V',
 VALUE='DIFF BUS_0.22UF',
 PRIM_FILE='./archive_libs/logical/q_cap_diffbus/chips/chips.prt';

PART_NAME
 C700 'Q_CAP_DIFFBUS_C0201-DIFF BUS_0A':;

SECTION_NUMBER 1
 '@S9S_MB_2U_LIB.S9S_MB_2U(SCH_1):PAGE168_I134@PURE_QUANTA.Q_CAP_DIFFBUS(CHIPS)':
 C_PATH='@s9s_mb_2u_lib.s9s_mb_2u(sch_1):page168_i134@pure_quanta.q_cap_diffbus(~
chips)',
 P_PATH='@s9s_mb_2u_lib.s9s_mb_2u(sch_1):page177_i134@pure_quanta.q_cap_diffbus(~
chips)',
 PATH='I134',
 DRAWING='@S9S_MB_2U_LIB.S9S_MB_2U(SCH_1):PAGE168',
 PIN_NAMES_ROTATE='TRUE',
 PHYS_PAGE='177',
 XY='(3150,975)',
 ROT='2',
 VER='2',
 PACK_TYPE='C0201',
 CDS_LIB='pure_quanta',
 CDS_PART_NAME='Q_CAP_DIFFBUS_C0201-DIFF BUS_0A',
 TOLERANCE='20%',
 MATERIAL='X6S',
 VOLTAGE='6.3V',
 VALUE='DIFF BUS_0.22UF',
 PRIM_FILE='./archive_libs/logical/q_cap_diffbus/chips/chips.prt';

PART_NAME
 C701 'Q_CAP_DIFFBUS_C0201-DIFF BUS_0A':;

SECTION_NUMBER 1
 '@S9S_MB_2U_LIB.S9S_MB_2U(SCH_1):PAGE168_I131@PURE_QUANTA.Q_CAP_DIFFBUS(CHIPS)':
 C_PATH='@s9s_mb_2u_lib.s9s_mb_2u(sch_1):page168_i131@pure_quanta.q_cap_diffbus(~
chips)',
 P_PATH='@s9s_mb_2u_lib.s9s_mb_2u(sch_1):page177_i131@pure_quanta.q_cap_diffbus(~
chips)',
 PATH='I131',
 DRAWING='@S9S_MB_2U_LIB.S9S_MB_2U(SCH_1):PAGE168',
 PIN_NAMES_ROTATE='TRUE',
 PHYS_PAGE='177',
 XY='(3150,925)',
 ROT='2',
 VER='2',
 PACK_TYPE='C0201',
 CDS_LIB='pure_quanta',
 CDS_PART_NAME='Q_CAP_DIFFBUS_C0201-DIFF BUS_0A',
 TOLERANCE='20%',
 MATERIAL='X6S',
 VOLTAGE='6.3V',
 VALUE='DIFF BUS_0.22UF',
 PRIM_FILE='./archive_libs/logical/q_cap_diffbus/chips/chips.prt';

PART_NAME
 C702 'Q_CAP_DIFFBUS_C0201-DIFF BUS_0A':;

SECTION_NUMBER 1
 '@S9S_MB_2U_LIB.S9S_MB_2U(SCH_1):PAGE168_I132@PURE_QUANTA.Q_CAP_DIFFBUS(CHIPS)':
 C_PATH='@s9s_mb_2u_lib.s9s_mb_2u(sch_1):page168_i132@pure_quanta.q_cap_diffbus(~
chips)',
 P_PATH='@s9s_mb_2u_lib.s9s_mb_2u(sch_1):page177_i132@pure_quanta.q_cap_diffbus(~
chips)',
 PATH='I132',
 DRAWING='@S9S_MB_2U_LIB.S9S_MB_2U(SCH_1):PAGE168',
 PIN_NAMES_ROTATE='TRUE',
 PHYS_PAGE='177',
 XY='(3150,775)',
 ROT='2',
 VER='2',
 PACK_TYPE='C0201',
 CDS_LIB='pure_quanta',
 CDS_PART_NAME='Q_CAP_DIFFBUS_C0201-DIFF BUS_0A',
 TOLERANCE='20%',
 MATERIAL='X6S',
 VOLTAGE='6.3V',
 VALUE='DIFF BUS_0.22UF',
 PRIM_FILE='./archive_libs/logical/q_cap_diffbus/chips/chips.prt';

PART_NAME
 C703 'Q_CAP_DIFFBUS_C0201-DIFF BUS_0A':;

SECTION_NUMBER 1
 '@S9S_MB_2U_LIB.S9S_MB_2U(SCH_1):PAGE168_I133@PURE_QUANTA.Q_CAP_DIFFBUS(CHIPS)':
 C_PATH='@s9s_mb_2u_lib.s9s_mb_2u(sch_1):page168_i133@pure_quanta.q_cap_diffbus(~
chips)',
 P_PATH='@s9s_mb_2u_lib.s9s_mb_2u(sch_1):page177_i133@pure_quanta.q_cap_diffbus(~
chips)',
 PATH='I133',
 DRAWING='@S9S_MB_2U_LIB.S9S_MB_2U(SCH_1):PAGE168',
 PIN_NAMES_ROTATE='TRUE',
 PHYS_PAGE='177',
 XY='(3150,725)',
 ROT='2',
 VER='2',
 PACK_TYPE='C0201',
 CDS_LIB='pure_quanta',
 CDS_PART_NAME='Q_CAP_DIFFBUS_C0201-DIFF BUS_0A',
 TOLERANCE='20%',
 MATERIAL='X6S',
 VOLTAGE='6.3V',
 VALUE='DIFF BUS_0.22UF',
 PRIM_FILE='./archive_libs/logical/q_cap_diffbus/chips/chips.prt';

PART_NAME
 C704 'Q_CAP_DIFFBUS_C0201-DIFF BUS_0A':;

SECTION_NUMBER 1
 '@S9S_MB_2U_LIB.S9S_MB_2U(SCH_1):PAGE168_I129@PURE_QUANTA.Q_CAP_DIFFBUS(CHIPS)':
 C_PATH='@s9s_mb_2u_lib.s9s_mb_2u(sch_1):page168_i129@pure_quanta.q_cap_diffbus(~
chips)',
 P_PATH='@s9s_mb_2u_lib.s9s_mb_2u(sch_1):page177_i129@pure_quanta.q_cap_diffbus(~
chips)',
 PATH='I129',
 DRAWING='@S9S_MB_2U_LIB.S9S_MB_2U(SCH_1):PAGE168',
 PIN_NAMES_ROTATE='TRUE',
 PHYS_PAGE='177',
 XY='(3150,575)',
 ROT='2',
 VER='2',
 PACK_TYPE='C0201',
 CDS_LIB='pure_quanta',
 CDS_PART_NAME='Q_CAP_DIFFBUS_C0201-DIFF BUS_0A',
 TOLERANCE='20%',
 MATERIAL='X6S',
 VOLTAGE='6.3V',
 VALUE='DIFF BUS_0.22UF',
 PRIM_FILE='./archive_libs/logical/q_cap_diffbus/chips/chips.prt';

PART_NAME
 C705 'Q_CAP_DIFFBUS_C0201-DIFF BUS_0A':;

SECTION_NUMBER 1
 '@S9S_MB_2U_LIB.S9S_MB_2U(SCH_1):PAGE168_I130@PURE_QUANTA.Q_CAP_DIFFBUS(CHIPS)':
 C_PATH='@s9s_mb_2u_lib.s9s_mb_2u(sch_1):page168_i130@pure_quanta.q_cap_diffbus(~
chips)',
 P_PATH='@s9s_mb_2u_lib.s9s_mb_2u(sch_1):page177_i130@pure_quanta.q_cap_diffbus(~
chips)',
 PATH='I130',
 DRAWING='@S9S_MB_2U_LIB.S9S_MB_2U(SCH_1):PAGE168',
 PIN_NAMES_ROTATE='TRUE',
 PHYS_PAGE='177',
 XY='(3150,525)',
 ROT='2',
 VER='2',
 PACK_TYPE='C0201',
 CDS_LIB='pure_quanta',
 CDS_PART_NAME='Q_CAP_DIFFBUS_C0201-DIFF BUS_0A',
 TOLERANCE='20%',
 MATERIAL='X6S',
 VOLTAGE='6.3V',
 VALUE='DIFF BUS_0.22UF',
 PRIM_FILE='./archive_libs/logical/q_cap_diffbus/chips/chips.prt';

PART_NAME
 C706 'Q_CAP_DIFFBUS_C0201-DIFF BUS_0A':;

SECTION_NUMBER 1
 '@S9S_MB_2U_LIB.S9S_MB_2U(SCH_1):PAGE168_I127@PURE_QUANTA.Q_CAP_DIFFBUS(CHIPS)':
 C_PATH='@s9s_mb_2u_lib.s9s_mb_2u(sch_1):page168_i127@pure_quanta.q_cap_diffbus(~
chips)',
 P_PATH='@s9s_mb_2u_lib.s9s_mb_2u(sch_1):page177_i127@pure_quanta.q_cap_diffbus(~
chips)',
 PATH='I127',
 DRAWING='@S9S_MB_2U_LIB.S9S_MB_2U(SCH_1):PAGE168',
 PIN_NAMES_ROTATE='TRUE',
 PHYS_PAGE='177',
 XY='(3150,375)',
 ROT='2',
 VER='2',
 PACK_TYPE='C0201',
 CDS_LIB='pure_quanta',
 CDS_PART_NAME='Q_CAP_DIFFBUS_C0201-DIFF BUS_0A',
 TOLERANCE='20%',
 MATERIAL='X6S',
 VOLTAGE='6.3V',
 VALUE='DIFF BUS_0.22UF',
 PRIM_FILE='./archive_libs/logical/q_cap_diffbus/chips/chips.prt';

PART_NAME
 C707 'Q_CAP_DIFFBUS_C0201-DIFF BUS_0A':;

SECTION_NUMBER 1
 '@S9S_MB_2U_LIB.S9S_MB_2U(SCH_1):PAGE168_I128@PURE_QUANTA.Q_CAP_DIFFBUS(CHIPS)':
 C_PATH='@s9s_mb_2u_lib.s9s_mb_2u(sch_1):page168_i128@pure_quanta.q_cap_diffbus(~
chips)',
 P_PATH='@s9s_mb_2u_lib.s9s_mb_2u(sch_1):page177_i128@pure_quanta.q_cap_diffbus(~
chips)',
 PATH='I128',
 DRAWING='@S9S_MB_2U_LIB.S9S_MB_2U(SCH_1):PAGE168',
 PIN_NAMES_ROTATE='TRUE',
 PHYS_PAGE='177',
 XY='(3150,325)',
 ROT='2',
 VER='2',
 PACK_TYPE='C0201',
 CDS_LIB='pure_quanta',
 CDS_PART_NAME='Q_CAP_DIFFBUS_C0201-DIFF BUS_0A',
 TOLERANCE='20%',
 MATERIAL='X6S',
 VOLTAGE='6.3V',
 VALUE='DIFF BUS_0.22UF',
 PRIM_FILE='./archive_libs/logical/q_cap_diffbus/chips/chips.prt';

PART_NAME
 C708 'Q_CAP_DIFFBUS_C0201-DIFF BUS_0A':;

SECTION_NUMBER 1
 '@S9S_MB_2U_LIB.S9S_MB_2U(SCH_1):PAGE168_I125@PURE_QUANTA.Q_CAP_DIFFBUS(CHIPS)':
 C_PATH='@s9s_mb_2u_lib.s9s_mb_2u(sch_1):page168_i125@pure_quanta.q_cap_diffbus(~
chips)',
 P_PATH='@s9s_mb_2u_lib.s9s_mb_2u(sch_1):page177_i125@pure_quanta.q_cap_diffbus(~
chips)',
 PATH='I125',
 DRAWING='@S9S_MB_2U_LIB.S9S_MB_2U(SCH_1):PAGE168',
 PIN_NAMES_ROTATE='TRUE',
 PHYS_PAGE='177',
 XY='(3150,175)',
 ROT='2',
 VER='2',
 PACK_TYPE='C0201',
 CDS_LIB='pure_quanta',
 CDS_PART_NAME='Q_CAP_DIFFBUS_C0201-DIFF BUS_0A',
 TOLERANCE='20%',
 MATERIAL='X6S',
 VOLTAGE='6.3V',
 VALUE='DIFF BUS_0.22UF',
 PRIM_FILE='./archive_libs/logical/q_cap_diffbus/chips/chips.prt';

PART_NAME
 C709 'Q_CAP_DIFFBUS_C0201-DIFF BUS_0A':;

SECTION_NUMBER 1
 '@S9S_MB_2U_LIB.S9S_MB_2U(SCH_1):PAGE168_I126@PURE_QUANTA.Q_CAP_DIFFBUS(CHIPS)':
 C_PATH='@s9s_mb_2u_lib.s9s_mb_2u(sch_1):page168_i126@pure_quanta.q_cap_diffbus(~
chips)',
 P_PATH='@s9s_mb_2u_lib.s9s_mb_2u(sch_1):page177_i126@pure_quanta.q_cap_diffbus(~
chips)',
 PATH='I126',
 DRAWING='@S9S_MB_2U_LIB.S9S_MB_2U(SCH_1):PAGE168',
 PIN_NAMES_ROTATE='TRUE',
 PHYS_PAGE='177',
 XY='(3150,125)',
 ROT='2',
 VER='2',
 PACK_TYPE='C0201',
 CDS_LIB='pure_quanta',
 CDS_PART_NAME='Q_CAP_DIFFBUS_C0201-DIFF BUS_0A',
 TOLERANCE='20%',
 MATERIAL='X6S',
 VOLTAGE='6.3V',
 VALUE='DIFF BUS_0.22UF',
 PRIM_FILE='./archive_libs/logical/q_cap_diffbus/chips/chips.prt';

PART_NAME
 C710 'Q_CAP_DIFFBUS_C0201-DIFF BUS_0A':;

SECTION_NUMBER 1
 '@S9S_MB_2U_LIB.S9S_MB_2U(SCH_1):PAGE167_I299@PURE_QUANTA.Q_CAP_DIFFBUS(CHIPS)':
 C_PATH='@s9s_mb_2u_lib.s9s_mb_2u(sch_1):page167_i299@pure_quanta.q_cap_diffbus(~
chips)',
 P_PATH='@s9s_mb_2u_lib.s9s_mb_2u(sch_1):page176_i299@pure_quanta.q_cap_diffbus(~
chips)',
 PATH='I299',
 DRAWING='@S9S_MB_2U_LIB.S9S_MB_2U(SCH_1):PAGE167',
 PIN_NAMES_ROTATE='TRUE',
 PHYS_PAGE='176',
 XY='(-950,3600)',
 ROT='2',
 VER='2',
 PACK_TYPE='C0201',
 CDS_LIB='pure_quanta',
 CDS_PART_NAME='Q_CAP_DIFFBUS_C0201-DIFF BUS_0A',
 TOLERANCE='20%',
 MATERIAL='X6S',
 VOLTAGE='6.3V',
 VALUE='DIFF BUS_0.22UF',
 PRIM_FILE='./archive_libs/logical/q_cap_diffbus/chips/chips.prt';

PART_NAME
 C711 'Q_CAP_DIFFBUS_C0201-DIFF BUS_0A':;

SECTION_NUMBER 1
 '@S9S_MB_2U_LIB.S9S_MB_2U(SCH_1):PAGE167_I298@PURE_QUANTA.Q_CAP_DIFFBUS(CHIPS)':
 C_PATH='@s9s_mb_2u_lib.s9s_mb_2u(sch_1):page167_i298@pure_quanta.q_cap_diffbus(~
chips)',
 P_PATH='@s9s_mb_2u_lib.s9s_mb_2u(sch_1):page176_i298@pure_quanta.q_cap_diffbus(~
chips)',
 PATH='I298',
 DRAWING='@S9S_MB_2U_LIB.S9S_MB_2U(SCH_1):PAGE167',
 PIN_NAMES_ROTATE='TRUE',
 PHYS_PAGE='176',
 XY='(-950,3550)',
 ROT='2',
 VER='2',
 PACK_TYPE='C0201',
 CDS_LIB='pure_quanta',
 CDS_PART_NAME='Q_CAP_DIFFBUS_C0201-DIFF BUS_0A',
 TOLERANCE='20%',
 MATERIAL='X6S',
 VOLTAGE='6.3V',
 VALUE='DIFF BUS_0.22UF',
 PRIM_FILE='./archive_libs/logical/q_cap_diffbus/chips/chips.prt';

PART_NAME
 C712 'Q_CAP_DIFFBUS_C0201-DIFF BUS_0A':;

SECTION_NUMBER 1
 '@S9S_MB_2U_LIB.S9S_MB_2U(SCH_1):PAGE167_I296@PURE_QUANTA.Q_CAP_DIFFBUS(CHIPS)':
 C_PATH='@s9s_mb_2u_lib.s9s_mb_2u(sch_1):page167_i296@pure_quanta.q_cap_diffbus(~
chips)',
 P_PATH='@s9s_mb_2u_lib.s9s_mb_2u(sch_1):page176_i296@pure_quanta.q_cap_diffbus(~
chips)',
 PATH='I296',
 DRAWING='@S9S_MB_2U_LIB.S9S_MB_2U(SCH_1):PAGE167',
 PIN_NAMES_ROTATE='TRUE',
 PHYS_PAGE='176',
 XY='(-950,3400)',
 ROT='2',
 VER='2',
 PACK_TYPE='C0201',
 CDS_LIB='pure_quanta',
 CDS_PART_NAME='Q_CAP_DIFFBUS_C0201-DIFF BUS_0A',
 TOLERANCE='20%',
 MATERIAL='X6S',
 VOLTAGE='6.3V',
 VALUE='DIFF BUS_0.22UF',
 PRIM_FILE='./archive_libs/logical/q_cap_diffbus/chips/chips.prt';

PART_NAME
 C713 'Q_CAP_DIFFBUS_C0201-DIFF BUS_0A':;

SECTION_NUMBER 1
 '@S9S_MB_2U_LIB.S9S_MB_2U(SCH_1):PAGE167_I297@PURE_QUANTA.Q_CAP_DIFFBUS(CHIPS)':
 C_PATH='@s9s_mb_2u_lib.s9s_mb_2u(sch_1):page167_i297@pure_quanta.q_cap_diffbus(~
chips)',
 P_PATH='@s9s_mb_2u_lib.s9s_mb_2u(sch_1):page176_i297@pure_quanta.q_cap_diffbus(~
chips)',
 PATH='I297',
 DRAWING='@S9S_MB_2U_LIB.S9S_MB_2U(SCH_1):PAGE167',
 PIN_NAMES_ROTATE='TRUE',
 PHYS_PAGE='176',
 XY='(-950,3350)',
 ROT='2',
 VER='2',
 PACK_TYPE='C0201',
 CDS_LIB='pure_quanta',
 CDS_PART_NAME='Q_CAP_DIFFBUS_C0201-DIFF BUS_0A',
 TOLERANCE='20%',
 MATERIAL='X6S',
 VOLTAGE='6.3V',
 VALUE='DIFF BUS_0.22UF',
 PRIM_FILE='./archive_libs/logical/q_cap_diffbus/chips/chips.prt';

PART_NAME
 C714 'Q_CAP_DIFFBUS_C0201-DIFF BUS_0A':;

SECTION_NUMBER 1
 '@S9S_MB_2U_LIB.S9S_MB_2U(SCH_1):PAGE167_I295@PURE_QUANTA.Q_CAP_DIFFBUS(CHIPS)':
 C_PATH='@s9s_mb_2u_lib.s9s_mb_2u(sch_1):page167_i295@pure_quanta.q_cap_diffbus(~
chips)',
 P_PATH='@s9s_mb_2u_lib.s9s_mb_2u(sch_1):page176_i295@pure_quanta.q_cap_diffbus(~
chips)',
 PATH='I295',
 DRAWING='@S9S_MB_2U_LIB.S9S_MB_2U(SCH_1):PAGE167',
 PIN_NAMES_ROTATE='TRUE',
 PHYS_PAGE='176',
 XY='(-950,3200)',
 ROT='2',
 VER='2',
 PACK_TYPE='C0201',
 CDS_LIB='pure_quanta',
 CDS_PART_NAME='Q_CAP_DIFFBUS_C0201-DIFF BUS_0A',
 TOLERANCE='20%',
 MATERIAL='X6S',
 VOLTAGE='6.3V',
 VALUE='DIFF BUS_0.22UF',
 PRIM_FILE='./archive_libs/logical/q_cap_diffbus/chips/chips.prt';

PART_NAME
 C715 'Q_CAP_DIFFBUS_C0201-DIFF BUS_0A':;

SECTION_NUMBER 1
 '@S9S_MB_2U_LIB.S9S_MB_2U(SCH_1):PAGE167_I294@PURE_QUANTA.Q_CAP_DIFFBUS(CHIPS)':
 C_PATH='@s9s_mb_2u_lib.s9s_mb_2u(sch_1):page167_i294@pure_quanta.q_cap_diffbus(~
chips)',
 P_PATH='@s9s_mb_2u_lib.s9s_mb_2u(sch_1):page176_i294@pure_quanta.q_cap_diffbus(~
chips)',
 PATH='I294',
 DRAWING='@S9S_MB_2U_LIB.S9S_MB_2U(SCH_1):PAGE167',
 PIN_NAMES_ROTATE='TRUE',
 PHYS_PAGE='176',
 XY='(-950,3150)',
 ROT='2',
 VER='2',
 PACK_TYPE='C0201',
 CDS_LIB='pure_quanta',
 CDS_PART_NAME='Q_CAP_DIFFBUS_C0201-DIFF BUS_0A',
 TOLERANCE='20%',
 MATERIAL='X6S',
 VOLTAGE='6.3V',
 VALUE='DIFF BUS_0.22UF',
 PRIM_FILE='./archive_libs/logical/q_cap_diffbus/chips/chips.prt';

PART_NAME
 C716 'Q_CAP_DIFFBUS_C0201-DIFF BUS_0A':;

SECTION_NUMBER 1
 '@S9S_MB_2U_LIB.S9S_MB_2U(SCH_1):PAGE167_I283@PURE_QUANTA.Q_CAP_DIFFBUS(CHIPS)':
 C_PATH='@s9s_mb_2u_lib.s9s_mb_2u(sch_1):page167_i283@pure_quanta.q_cap_diffbus(~
chips)',
 P_PATH='@s9s_mb_2u_lib.s9s_mb_2u(sch_1):page176_i283@pure_quanta.q_cap_diffbus(~
chips)',
 PATH='I283',
 DRAWING='@S9S_MB_2U_LIB.S9S_MB_2U(SCH_1):PAGE167',
 PIN_NAMES_ROTATE='TRUE',
 PHYS_PAGE='176',
 XY='(-950,3000)',
 ROT='2',
 VER='2',
 PACK_TYPE='C0201',
 CDS_LIB='pure_quanta',
 CDS_PART_NAME='Q_CAP_DIFFBUS_C0201-DIFF BUS_0A',
 TOLERANCE='20%',
 MATERIAL='X6S',
 VOLTAGE='6.3V',
 VALUE='DIFF BUS_0.22UF',
 PRIM_FILE='./archive_libs/logical/q_cap_diffbus/chips/chips.prt';

PART_NAME
 C717 'Q_CAP_DIFFBUS_C0201-DIFF BUS_0A':;

SECTION_NUMBER 1
 '@S9S_MB_2U_LIB.S9S_MB_2U(SCH_1):PAGE167_I282@PURE_QUANTA.Q_CAP_DIFFBUS(CHIPS)':
 C_PATH='@s9s_mb_2u_lib.s9s_mb_2u(sch_1):page167_i282@pure_quanta.q_cap_diffbus(~
chips)',
 P_PATH='@s9s_mb_2u_lib.s9s_mb_2u(sch_1):page176_i282@pure_quanta.q_cap_diffbus(~
chips)',
 PATH='I282',
 DRAWING='@S9S_MB_2U_LIB.S9S_MB_2U(SCH_1):PAGE167',
 PIN_NAMES_ROTATE='TRUE',
 PHYS_PAGE='176',
 XY='(-950,2950)',
 ROT='2',
 VER='2',
 PACK_TYPE='C0201',
 CDS_LIB='pure_quanta',
 CDS_PART_NAME='Q_CAP_DIFFBUS_C0201-DIFF BUS_0A',
 TOLERANCE='20%',
 MATERIAL='X6S',
 VOLTAGE='6.3V',
 VALUE='DIFF BUS_0.22UF',
 PRIM_FILE='./archive_libs/logical/q_cap_diffbus/chips/chips.prt';

PART_NAME
 C718 'Q_CAP_DIFFBUS_C0201-DIFF BUS_0A':;

SECTION_NUMBER 1
 '@S9S_MB_2U_LIB.S9S_MB_2U(SCH_1):PAGE167_I281@PURE_QUANTA.Q_CAP_DIFFBUS(CHIPS)':
 C_PATH='@s9s_mb_2u_lib.s9s_mb_2u(sch_1):page167_i281@pure_quanta.q_cap_diffbus(~
chips)',
 P_PATH='@s9s_mb_2u_lib.s9s_mb_2u(sch_1):page176_i281@pure_quanta.q_cap_diffbus(~
chips)',
 PATH='I281',
 DRAWING='@S9S_MB_2U_LIB.S9S_MB_2U(SCH_1):PAGE167',
 PIN_NAMES_ROTATE='TRUE',
 PHYS_PAGE='176',
 XY='(-950,2800)',
 ROT='2',
 VER='2',
 PACK_TYPE='C0201',
 CDS_LIB='pure_quanta',
 CDS_PART_NAME='Q_CAP_DIFFBUS_C0201-DIFF BUS_0A',
 TOLERANCE='20%',
 MATERIAL='X6S',
 VOLTAGE='6.3V',
 VALUE='DIFF BUS_0.22UF',
 PRIM_FILE='./archive_libs/logical/q_cap_diffbus/chips/chips.prt';

PART_NAME
 C719 'Q_CAP_DIFFBUS_C0201-DIFF BUS_0A':;

SECTION_NUMBER 1
 '@S9S_MB_2U_LIB.S9S_MB_2U(SCH_1):PAGE167_I280@PURE_QUANTA.Q_CAP_DIFFBUS(CHIPS)':
 C_PATH='@s9s_mb_2u_lib.s9s_mb_2u(sch_1):page167_i280@pure_quanta.q_cap_diffbus(~
chips)',
 P_PATH='@s9s_mb_2u_lib.s9s_mb_2u(sch_1):page176_i280@pure_quanta.q_cap_diffbus(~
chips)',
 PATH='I280',
 DRAWING='@S9S_MB_2U_LIB.S9S_MB_2U(SCH_1):PAGE167',
 PIN_NAMES_ROTATE='TRUE',
 PHYS_PAGE='176',
 XY='(-950,2750)',
 ROT='2',
 VER='2',
 PACK_TYPE='C0201',
 CDS_LIB='pure_quanta',
 CDS_PART_NAME='Q_CAP_DIFFBUS_C0201-DIFF BUS_0A',
 TOLERANCE='20%',
 MATERIAL='X6S',
 VOLTAGE='6.3V',
 VALUE='DIFF BUS_0.22UF',
 PRIM_FILE='./archive_libs/logical/q_cap_diffbus/chips/chips.prt';

PART_NAME
 C720 'Q_CAP_DIFFBUS_C0201-DIFF BUS_0A':;

SECTION_NUMBER 1
 '@S9S_MB_2U_LIB.S9S_MB_2U(SCH_1):PAGE167_I279@PURE_QUANTA.Q_CAP_DIFFBUS(CHIPS)':
 C_PATH='@s9s_mb_2u_lib.s9s_mb_2u(sch_1):page167_i279@pure_quanta.q_cap_diffbus(~
chips)',
 P_PATH='@s9s_mb_2u_lib.s9s_mb_2u(sch_1):page176_i279@pure_quanta.q_cap_diffbus(~
chips)',
 PATH='I279',
 DRAWING='@S9S_MB_2U_LIB.S9S_MB_2U(SCH_1):PAGE167',
 PIN_NAMES_ROTATE='TRUE',
 PHYS_PAGE='176',
 XY='(-950,2600)',
 ROT='2',
 VER='2',
 PACK_TYPE='C0201',
 CDS_LIB='pure_quanta',
 CDS_PART_NAME='Q_CAP_DIFFBUS_C0201-DIFF BUS_0A',
 TOLERANCE='20%',
 MATERIAL='X6S',
 VOLTAGE='6.3V',
 VALUE='DIFF BUS_0.22UF',
 PRIM_FILE='./archive_libs/logical/q_cap_diffbus/chips/chips.prt';

PART_NAME
 C721 'Q_CAP_DIFFBUS_C0201-DIFF BUS_0A':;

SECTION_NUMBER 1
 '@S9S_MB_2U_LIB.S9S_MB_2U(SCH_1):PAGE167_I278@PURE_QUANTA.Q_CAP_DIFFBUS(CHIPS)':
 C_PATH='@s9s_mb_2u_lib.s9s_mb_2u(sch_1):page167_i278@pure_quanta.q_cap_diffbus(~
chips)',
 P_PATH='@s9s_mb_2u_lib.s9s_mb_2u(sch_1):page176_i278@pure_quanta.q_cap_diffbus(~
chips)',
 PATH='I278',
 DRAWING='@S9S_MB_2U_LIB.S9S_MB_2U(SCH_1):PAGE167',
 PIN_NAMES_ROTATE='TRUE',
 PHYS_PAGE='176',
 XY='(-950,2550)',
 ROT='2',
 VER='2',
 PACK_TYPE='C0201',
 CDS_LIB='pure_quanta',
 CDS_PART_NAME='Q_CAP_DIFFBUS_C0201-DIFF BUS_0A',
 TOLERANCE='20%',
 MATERIAL='X6S',
 VOLTAGE='6.3V',
 VALUE='DIFF BUS_0.22UF',
 PRIM_FILE='./archive_libs/logical/q_cap_diffbus/chips/chips.prt';

PART_NAME
 C722 'Q_CAP_DIFFBUS_C0201-DIFF BUS_0A':;

SECTION_NUMBER 1
 '@S9S_MB_2U_LIB.S9S_MB_2U(SCH_1):PAGE167_I276@PURE_QUANTA.Q_CAP_DIFFBUS(CHIPS)':
 C_PATH='@s9s_mb_2u_lib.s9s_mb_2u(sch_1):page167_i276@pure_quanta.q_cap_diffbus(~
chips)',
 P_PATH='@s9s_mb_2u_lib.s9s_mb_2u(sch_1):page176_i276@pure_quanta.q_cap_diffbus(~
chips)',
 PATH='I276',
 DRAWING='@S9S_MB_2U_LIB.S9S_MB_2U(SCH_1):PAGE167',
 PIN_NAMES_ROTATE='TRUE',
 PHYS_PAGE='176',
 XY='(-950,2400)',
 ROT='2',
 VER='2',
 PACK_TYPE='C0201',
 CDS_LIB='pure_quanta',
 CDS_PART_NAME='Q_CAP_DIFFBUS_C0201-DIFF BUS_0A',
 TOLERANCE='20%',
 MATERIAL='X6S',
 VOLTAGE='6.3V',
 VALUE='DIFF BUS_0.22UF',
 PRIM_FILE='./archive_libs/logical/q_cap_diffbus/chips/chips.prt';

PART_NAME
 C723 'Q_CAP_DIFFBUS_C0201-DIFF BUS_0A':;

SECTION_NUMBER 1
 '@S9S_MB_2U_LIB.S9S_MB_2U(SCH_1):PAGE167_I277@PURE_QUANTA.Q_CAP_DIFFBUS(CHIPS)':
 C_PATH='@s9s_mb_2u_lib.s9s_mb_2u(sch_1):page167_i277@pure_quanta.q_cap_diffbus(~
chips)',
 P_PATH='@s9s_mb_2u_lib.s9s_mb_2u(sch_1):page176_i277@pure_quanta.q_cap_diffbus(~
chips)',
 PATH='I277',
 DRAWING='@S9S_MB_2U_LIB.S9S_MB_2U(SCH_1):PAGE167',
 PIN_NAMES_ROTATE='TRUE',
 PHYS_PAGE='176',
 XY='(-950,2350)',
 ROT='2',
 VER='2',
 PACK_TYPE='C0201',
 CDS_LIB='pure_quanta',
 CDS_PART_NAME='Q_CAP_DIFFBUS_C0201-DIFF BUS_0A',
 TOLERANCE='20%',
 MATERIAL='X6S',
 VOLTAGE='6.3V',
 VALUE='DIFF BUS_0.22UF',
 PRIM_FILE='./archive_libs/logical/q_cap_diffbus/chips/chips.prt';

PART_NAME
 C724 'Q_CAP_DIFFBUS_C0201-DIFF BUS_0A':;

SECTION_NUMBER 1
 '@S9S_MB_2U_LIB.S9S_MB_2U(SCH_1):PAGE167_I275@PURE_QUANTA.Q_CAP_DIFFBUS(CHIPS)':
 C_PATH='@s9s_mb_2u_lib.s9s_mb_2u(sch_1):page167_i275@pure_quanta.q_cap_diffbus(~
chips)',
 P_PATH='@s9s_mb_2u_lib.s9s_mb_2u(sch_1):page176_i275@pure_quanta.q_cap_diffbus(~
chips)',
 PATH='I275',
 DRAWING='@S9S_MB_2U_LIB.S9S_MB_2U(SCH_1):PAGE167',
 PIN_NAMES_ROTATE='TRUE',
 PHYS_PAGE='176',
 XY='(-950,2200)',
 ROT='2',
 VER='2',
 PACK_TYPE='C0201',
 CDS_LIB='pure_quanta',
 CDS_PART_NAME='Q_CAP_DIFFBUS_C0201-DIFF BUS_0A',
 TOLERANCE='20%',
 MATERIAL='X6S',
 VOLTAGE='6.3V',
 VALUE='DIFF BUS_0.22UF',
 PRIM_FILE='./archive_libs/logical/q_cap_diffbus/chips/chips.prt';

PART_NAME
 C725 'Q_CAP_DIFFBUS_C0201-DIFF BUS_0A':;

SECTION_NUMBER 1
 '@S9S_MB_2U_LIB.S9S_MB_2U(SCH_1):PAGE167_I274@PURE_QUANTA.Q_CAP_DIFFBUS(CHIPS)':
 C_PATH='@s9s_mb_2u_lib.s9s_mb_2u(sch_1):page167_i274@pure_quanta.q_cap_diffbus(~
chips)',
 P_PATH='@s9s_mb_2u_lib.s9s_mb_2u(sch_1):page176_i274@pure_quanta.q_cap_diffbus(~
chips)',
 PATH='I274',
 DRAWING='@S9S_MB_2U_LIB.S9S_MB_2U(SCH_1):PAGE167',
 PIN_NAMES_ROTATE='TRUE',
 PHYS_PAGE='176',
 XY='(-950,2150)',
 ROT='2',
 VER='2',
 PACK_TYPE='C0201',
 CDS_LIB='pure_quanta',
 CDS_PART_NAME='Q_CAP_DIFFBUS_C0201-DIFF BUS_0A',
 TOLERANCE='20%',
 MATERIAL='X6S',
 VOLTAGE='6.3V',
 VALUE='DIFF BUS_0.22UF',
 PRIM_FILE='./archive_libs/logical/q_cap_diffbus/chips/chips.prt';

PART_NAME
 C726 'Q_CAP_DIFFBUS_C0201-DIFF BUS_0A':;

SECTION_NUMBER 1
 '@S9S_MB_2U_LIB.S9S_MB_2U(SCH_1):PAGE167_I312@PURE_QUANTA.Q_CAP_DIFFBUS(CHIPS)':
 C_PATH='@s9s_mb_2u_lib.s9s_mb_2u(sch_1):page167_i312@pure_quanta.q_cap_diffbus(~
chips)',
 P_PATH='@s9s_mb_2u_lib.s9s_mb_2u(sch_1):page176_i312@pure_quanta.q_cap_diffbus(~
chips)',
 PATH='I312',
 DRAWING='@S9S_MB_2U_LIB.S9S_MB_2U(SCH_1):PAGE167',
 PIN_NAMES_ROTATE='TRUE',
 PHYS_PAGE='176',
 XY='(-950,1625)',
 ROT='2',
 VER='2',
 PACK_TYPE='C0201',
 CDS_LIB='pure_quanta',
 CDS_PART_NAME='Q_CAP_DIFFBUS_C0201-DIFF BUS_0A',
 TOLERANCE='20%',
 MATERIAL='X6S',
 VOLTAGE='6.3V',
 VALUE='DIFF BUS_0.22UF',
 PRIM_FILE='./archive_libs/logical/q_cap_diffbus/chips/chips.prt';

PART_NAME
 C727 'Q_CAP_DIFFBUS_C0201-DIFF BUS_0A':;

SECTION_NUMBER 1
 '@S9S_MB_2U_LIB.S9S_MB_2U(SCH_1):PAGE167_I251@PURE_QUANTA.Q_CAP_DIFFBUS(CHIPS)':
 C_PATH='@s9s_mb_2u_lib.s9s_mb_2u(sch_1):page167_i251@pure_quanta.q_cap_diffbus(~
chips)',
 P_PATH='@s9s_mb_2u_lib.s9s_mb_2u(sch_1):page176_i251@pure_quanta.q_cap_diffbus(~
chips)',
 PATH='I251',
 DRAWING='@S9S_MB_2U_LIB.S9S_MB_2U(SCH_1):PAGE167',
 PIN_NAMES_ROTATE='TRUE',
 PHYS_PAGE='176',
 XY='(-950,1575)',
 ROT='2',
 VER='2',
 PACK_TYPE='C0201',
 CDS_LIB='pure_quanta',
 CDS_PART_NAME='Q_CAP_DIFFBUS_C0201-DIFF BUS_0A',
 TOLERANCE='20%',
 MATERIAL='X6S',
 VOLTAGE='6.3V',
 VALUE='DIFF BUS_0.22UF',
 PRIM_FILE='./archive_libs/logical/q_cap_diffbus/chips/chips.prt';

PART_NAME
 C728 'Q_CAP_DIFFBUS_C0201-DIFF BUS_0A':;

SECTION_NUMBER 1
 '@S9S_MB_2U_LIB.S9S_MB_2U(SCH_1):PAGE167_I250@PURE_QUANTA.Q_CAP_DIFFBUS(CHIPS)':
 C_PATH='@s9s_mb_2u_lib.s9s_mb_2u(sch_1):page167_i250@pure_quanta.q_cap_diffbus(~
chips)',
 P_PATH='@s9s_mb_2u_lib.s9s_mb_2u(sch_1):page176_i250@pure_quanta.q_cap_diffbus(~
chips)',
 PATH='I250',
 DRAWING='@S9S_MB_2U_LIB.S9S_MB_2U(SCH_1):PAGE167',
 PIN_NAMES_ROTATE='TRUE',
 PHYS_PAGE='176',
 XY='(-950,1425)',
 ROT='2',
 VER='2',
 PACK_TYPE='C0201',
 CDS_LIB='pure_quanta',
 CDS_PART_NAME='Q_CAP_DIFFBUS_C0201-DIFF BUS_0A',
 TOLERANCE='20%',
 MATERIAL='X6S',
 VOLTAGE='6.3V',
 VALUE='DIFF BUS_0.22UF',
 PRIM_FILE='./archive_libs/logical/q_cap_diffbus/chips/chips.prt';

PART_NAME
 C729 'Q_CAP_DIFFBUS_C0201-DIFF BUS_0A':;

SECTION_NUMBER 1
 '@S9S_MB_2U_LIB.S9S_MB_2U(SCH_1):PAGE167_I249@PURE_QUANTA.Q_CAP_DIFFBUS(CHIPS)':
 C_PATH='@s9s_mb_2u_lib.s9s_mb_2u(sch_1):page167_i249@pure_quanta.q_cap_diffbus(~
chips)',
 P_PATH='@s9s_mb_2u_lib.s9s_mb_2u(sch_1):page176_i249@pure_quanta.q_cap_diffbus(~
chips)',
 PATH='I249',
 DRAWING='@S9S_MB_2U_LIB.S9S_MB_2U(SCH_1):PAGE167',
 PIN_NAMES_ROTATE='TRUE',
 PHYS_PAGE='176',
 XY='(-950,1375)',
 ROT='2',
 VER='2',
 PACK_TYPE='C0201',
 CDS_LIB='pure_quanta',
 CDS_PART_NAME='Q_CAP_DIFFBUS_C0201-DIFF BUS_0A',
 TOLERANCE='20%',
 MATERIAL='X6S',
 VOLTAGE='6.3V',
 VALUE='DIFF BUS_0.22UF',
 PRIM_FILE='./archive_libs/logical/q_cap_diffbus/chips/chips.prt';

PART_NAME
 C730 'Q_CAP_DIFFBUS_C0201-DIFF BUS_0A':;

SECTION_NUMBER 1
 '@S9S_MB_2U_LIB.S9S_MB_2U(SCH_1):PAGE167_I248@PURE_QUANTA.Q_CAP_DIFFBUS(CHIPS)':
 C_PATH='@s9s_mb_2u_lib.s9s_mb_2u(sch_1):page167_i248@pure_quanta.q_cap_diffbus(~
chips)',
 P_PATH='@s9s_mb_2u_lib.s9s_mb_2u(sch_1):page176_i248@pure_quanta.q_cap_diffbus(~
chips)',
 PATH='I248',
 DRAWING='@S9S_MB_2U_LIB.S9S_MB_2U(SCH_1):PAGE167',
 PIN_NAMES_ROTATE='TRUE',
 PHYS_PAGE='176',
 XY='(-950,1225)',
 ROT='2',
 VER='2',
 PACK_TYPE='C0201',
 CDS_LIB='pure_quanta',
 CDS_PART_NAME='Q_CAP_DIFFBUS_C0201-DIFF BUS_0A',
 TOLERANCE='20%',
 MATERIAL='X6S',
 VOLTAGE='6.3V',
 VALUE='DIFF BUS_0.22UF',
 PRIM_FILE='./archive_libs/logical/q_cap_diffbus/chips/chips.prt';

PART_NAME
 C731 'Q_CAP_DIFFBUS_C0201-DIFF BUS_0A':;

SECTION_NUMBER 1
 '@S9S_MB_2U_LIB.S9S_MB_2U(SCH_1):PAGE167_I247@PURE_QUANTA.Q_CAP_DIFFBUS(CHIPS)':
 C_PATH='@s9s_mb_2u_lib.s9s_mb_2u(sch_1):page167_i247@pure_quanta.q_cap_diffbus(~
chips)',
 P_PATH='@s9s_mb_2u_lib.s9s_mb_2u(sch_1):page176_i247@pure_quanta.q_cap_diffbus(~
chips)',
 PATH='I247',
 DRAWING='@S9S_MB_2U_LIB.S9S_MB_2U(SCH_1):PAGE167',
 PIN_NAMES_ROTATE='TRUE',
 PHYS_PAGE='176',
 XY='(-950,1175)',
 ROT='2',
 VER='2',
 PACK_TYPE='C0201',
 CDS_LIB='pure_quanta',
 CDS_PART_NAME='Q_CAP_DIFFBUS_C0201-DIFF BUS_0A',
 TOLERANCE='20%',
 MATERIAL='X6S',
 VOLTAGE='6.3V',
 VALUE='DIFF BUS_0.22UF',
 PRIM_FILE='./archive_libs/logical/q_cap_diffbus/chips/chips.prt';

PART_NAME
 C732 'Q_CAP_DIFFBUS_C0201-DIFF BUS_0A':;

SECTION_NUMBER 1
 '@S9S_MB_2U_LIB.S9S_MB_2U(SCH_1):PAGE167_I246@PURE_QUANTA.Q_CAP_DIFFBUS(CHIPS)':
 C_PATH='@s9s_mb_2u_lib.s9s_mb_2u(sch_1):page167_i246@pure_quanta.q_cap_diffbus(~
chips)',
 P_PATH='@s9s_mb_2u_lib.s9s_mb_2u(sch_1):page176_i246@pure_quanta.q_cap_diffbus(~
chips)',
 PATH='I246',
 DRAWING='@S9S_MB_2U_LIB.S9S_MB_2U(SCH_1):PAGE167',
 PIN_NAMES_ROTATE='TRUE',
 PHYS_PAGE='176',
 XY='(-950,1025)',
 ROT='2',
 VER='2',
 PACK_TYPE='C0201',
 CDS_LIB='pure_quanta',
 CDS_PART_NAME='Q_CAP_DIFFBUS_C0201-DIFF BUS_0A',
 TOLERANCE='20%',
 MATERIAL='X6S',
 VOLTAGE='6.3V',
 VALUE='DIFF BUS_0.22UF',
 PRIM_FILE='./archive_libs/logical/q_cap_diffbus/chips/chips.prt';

PART_NAME
 C733 'Q_CAP_DIFFBUS_C0201-DIFF BUS_0A':;

SECTION_NUMBER 1
 '@S9S_MB_2U_LIB.S9S_MB_2U(SCH_1):PAGE167_I237@PURE_QUANTA.Q_CAP_DIFFBUS(CHIPS)':
 C_PATH='@s9s_mb_2u_lib.s9s_mb_2u(sch_1):page167_i237@pure_quanta.q_cap_diffbus(~
chips)',
 P_PATH='@s9s_mb_2u_lib.s9s_mb_2u(sch_1):page176_i237@pure_quanta.q_cap_diffbus(~
chips)',
 PATH='I237',
 DRAWING='@S9S_MB_2U_LIB.S9S_MB_2U(SCH_1):PAGE167',
 PIN_NAMES_ROTATE='TRUE',
 PHYS_PAGE='176',
 XY='(-950,975)',
 ROT='2',
 VER='2',
 PACK_TYPE='C0201',
 CDS_LIB='pure_quanta',
 CDS_PART_NAME='Q_CAP_DIFFBUS_C0201-DIFF BUS_0A',
 TOLERANCE='20%',
 MATERIAL='X6S',
 VOLTAGE='6.3V',
 VALUE='DIFF BUS_0.22UF',
 PRIM_FILE='./archive_libs/logical/q_cap_diffbus/chips/chips.prt';

PART_NAME
 C734 'Q_CAP_DIFFBUS_C0201-DIFF BUS_0A':;

SECTION_NUMBER 1
 '@S9S_MB_2U_LIB.S9S_MB_2U(SCH_1):PAGE167_I235@PURE_QUANTA.Q_CAP_DIFFBUS(CHIPS)':
 C_PATH='@s9s_mb_2u_lib.s9s_mb_2u(sch_1):page167_i235@pure_quanta.q_cap_diffbus(~
chips)',
 P_PATH='@s9s_mb_2u_lib.s9s_mb_2u(sch_1):page176_i235@pure_quanta.q_cap_diffbus(~
chips)',
 PATH='I235',
 DRAWING='@S9S_MB_2U_LIB.S9S_MB_2U(SCH_1):PAGE167',
 PIN_NAMES_ROTATE='TRUE',
 PHYS_PAGE='176',
 XY='(-950,825)',
 ROT='2',
 VER='2',
 PACK_TYPE='C0201',
 CDS_LIB='pure_quanta',
 CDS_PART_NAME='Q_CAP_DIFFBUS_C0201-DIFF BUS_0A',
 TOLERANCE='20%',
 MATERIAL='X6S',
 VOLTAGE='6.3V',
 VALUE='DIFF BUS_0.22UF',
 PRIM_FILE='./archive_libs/logical/q_cap_diffbus/chips/chips.prt';

PART_NAME
 C735 'Q_CAP_DIFFBUS_C0201-DIFF BUS_0A':;

SECTION_NUMBER 1
 '@S9S_MB_2U_LIB.S9S_MB_2U(SCH_1):PAGE167_I236@PURE_QUANTA.Q_CAP_DIFFBUS(CHIPS)':
 C_PATH='@s9s_mb_2u_lib.s9s_mb_2u(sch_1):page167_i236@pure_quanta.q_cap_diffbus(~
chips)',
 P_PATH='@s9s_mb_2u_lib.s9s_mb_2u(sch_1):page176_i236@pure_quanta.q_cap_diffbus(~
chips)',
 PATH='I236',
 DRAWING='@S9S_MB_2U_LIB.S9S_MB_2U(SCH_1):PAGE167',
 PIN_NAMES_ROTATE='TRUE',
 PHYS_PAGE='176',
 XY='(-950,775)',
 ROT='2',
 VER='2',
 PACK_TYPE='C0201',
 CDS_LIB='pure_quanta',
 CDS_PART_NAME='Q_CAP_DIFFBUS_C0201-DIFF BUS_0A',
 TOLERANCE='20%',
 MATERIAL='X6S',
 VOLTAGE='6.3V',
 VALUE='DIFF BUS_0.22UF',
 PRIM_FILE='./archive_libs/logical/q_cap_diffbus/chips/chips.prt';

PART_NAME
 C736 'Q_CAP_DIFFBUS_C0201-DIFF BUS_0A':;

SECTION_NUMBER 1
 '@S9S_MB_2U_LIB.S9S_MB_2U(SCH_1):PAGE167_I234@PURE_QUANTA.Q_CAP_DIFFBUS(CHIPS)':
 C_PATH='@s9s_mb_2u_lib.s9s_mb_2u(sch_1):page167_i234@pure_quanta.q_cap_diffbus(~
chips)',
 P_PATH='@s9s_mb_2u_lib.s9s_mb_2u(sch_1):page176_i234@pure_quanta.q_cap_diffbus(~
chips)',
 PATH='I234',
 DRAWING='@S9S_MB_2U_LIB.S9S_MB_2U(SCH_1):PAGE167',
 PIN_NAMES_ROTATE='TRUE',
 PHYS_PAGE='176',
 XY='(-950,625)',
 ROT='2',
 VER='2',
 PACK_TYPE='C0201',
 CDS_LIB='pure_quanta',
 CDS_PART_NAME='Q_CAP_DIFFBUS_C0201-DIFF BUS_0A',
 TOLERANCE='20%',
 MATERIAL='X6S',
 VOLTAGE='6.3V',
 VALUE='DIFF BUS_0.22UF',
 PRIM_FILE='./archive_libs/logical/q_cap_diffbus/chips/chips.prt';

PART_NAME
 C737 'Q_CAP_DIFFBUS_C0201-DIFF BUS_0A':;

SECTION_NUMBER 1
 '@S9S_MB_2U_LIB.S9S_MB_2U(SCH_1):PAGE167_I233@PURE_QUANTA.Q_CAP_DIFFBUS(CHIPS)':
 C_PATH='@s9s_mb_2u_lib.s9s_mb_2u(sch_1):page167_i233@pure_quanta.q_cap_diffbus(~
chips)',
 P_PATH='@s9s_mb_2u_lib.s9s_mb_2u(sch_1):page176_i233@pure_quanta.q_cap_diffbus(~
chips)',
 PATH='I233',
 DRAWING='@S9S_MB_2U_LIB.S9S_MB_2U(SCH_1):PAGE167',
 PIN_NAMES_ROTATE='TRUE',
 PHYS_PAGE='176',
 XY='(-950,575)',
 ROT='2',
 VER='2',
 PACK_TYPE='C0201',
 CDS_LIB='pure_quanta',
 CDS_PART_NAME='Q_CAP_DIFFBUS_C0201-DIFF BUS_0A',
 TOLERANCE='20%',
 MATERIAL='X6S',
 VOLTAGE='6.3V',
 VALUE='DIFF BUS_0.22UF',
 PRIM_FILE='./archive_libs/logical/q_cap_diffbus/chips/chips.prt';

PART_NAME
 C738 'Q_CAP_DIFFBUS_C0201-DIFF BUS_0A':;

SECTION_NUMBER 1
 '@S9S_MB_2U_LIB.S9S_MB_2U(SCH_1):PAGE167_I232@PURE_QUANTA.Q_CAP_DIFFBUS(CHIPS)':
 C_PATH='@s9s_mb_2u_lib.s9s_mb_2u(sch_1):page167_i232@pure_quanta.q_cap_diffbus(~
chips)',
 P_PATH='@s9s_mb_2u_lib.s9s_mb_2u(sch_1):page176_i232@pure_quanta.q_cap_diffbus(~
chips)',
 PATH='I232',
 DRAWING='@S9S_MB_2U_LIB.S9S_MB_2U(SCH_1):PAGE167',
 PIN_NAMES_ROTATE='TRUE',
 PHYS_PAGE='176',
 XY='(-950,425)',
 ROT='2',
 VER='2',
 PACK_TYPE='C0201',
 CDS_LIB='pure_quanta',
 CDS_PART_NAME='Q_CAP_DIFFBUS_C0201-DIFF BUS_0A',
 TOLERANCE='20%',
 MATERIAL='X6S',
 VOLTAGE='6.3V',
 VALUE='DIFF BUS_0.22UF',
 PRIM_FILE='./archive_libs/logical/q_cap_diffbus/chips/chips.prt';

PART_NAME
 C739 'Q_CAP_DIFFBUS_C0201-DIFF BUS_0A':;

SECTION_NUMBER 1
 '@S9S_MB_2U_LIB.S9S_MB_2U(SCH_1):PAGE167_I231@PURE_QUANTA.Q_CAP_DIFFBUS(CHIPS)':
 C_PATH='@s9s_mb_2u_lib.s9s_mb_2u(sch_1):page167_i231@pure_quanta.q_cap_diffbus(~
chips)',
 P_PATH='@s9s_mb_2u_lib.s9s_mb_2u(sch_1):page176_i231@pure_quanta.q_cap_diffbus(~
chips)',
 PATH='I231',
 DRAWING='@S9S_MB_2U_LIB.S9S_MB_2U(SCH_1):PAGE167',
 PIN_NAMES_ROTATE='TRUE',
 PHYS_PAGE='176',
 XY='(-950,375)',
 ROT='2',
 VER='2',
 PACK_TYPE='C0201',
 CDS_LIB='pure_quanta',
 CDS_PART_NAME='Q_CAP_DIFFBUS_C0201-DIFF BUS_0A',
 TOLERANCE='20%',
 MATERIAL='X6S',
 VOLTAGE='6.3V',
 VALUE='DIFF BUS_0.22UF',
 PRIM_FILE='./archive_libs/logical/q_cap_diffbus/chips/chips.prt';

PART_NAME
 C740 'Q_CAP_DIFFBUS_C0201-DIFF BUS_0A':;

SECTION_NUMBER 1
 '@S9S_MB_2U_LIB.S9S_MB_2U(SCH_1):PAGE167_I229@PURE_QUANTA.Q_CAP_DIFFBUS(CHIPS)':
 C_PATH='@s9s_mb_2u_lib.s9s_mb_2u(sch_1):page167_i229@pure_quanta.q_cap_diffbus(~
chips)',
 P_PATH='@s9s_mb_2u_lib.s9s_mb_2u(sch_1):page176_i229@pure_quanta.q_cap_diffbus(~
chips)',
 PATH='I229',
 DRAWING='@S9S_MB_2U_LIB.S9S_MB_2U(SCH_1):PAGE167',
 PIN_NAMES_ROTATE='TRUE',
 PHYS_PAGE='176',
 XY='(-950,225)',
 ROT='2',
 VER='2',
 PACK_TYPE='C0201',
 CDS_LIB='pure_quanta',
 CDS_PART_NAME='Q_CAP_DIFFBUS_C0201-DIFF BUS_0A',
 TOLERANCE='20%',
 MATERIAL='X6S',
 VOLTAGE='6.3V',
 VALUE='DIFF BUS_0.22UF',
 PRIM_FILE='./archive_libs/logical/q_cap_diffbus/chips/chips.prt';

PART_NAME
 C741 'Q_CAP_DIFFBUS_C0201-DIFF BUS_0A':;

SECTION_NUMBER 1
 '@S9S_MB_2U_LIB.S9S_MB_2U(SCH_1):PAGE167_I230@PURE_QUANTA.Q_CAP_DIFFBUS(CHIPS)':
 C_PATH='@s9s_mb_2u_lib.s9s_mb_2u(sch_1):page167_i230@pure_quanta.q_cap_diffbus(~
chips)',
 P_PATH='@s9s_mb_2u_lib.s9s_mb_2u(sch_1):page176_i230@pure_quanta.q_cap_diffbus(~
chips)',
 PATH='I230',
 DRAWING='@S9S_MB_2U_LIB.S9S_MB_2U(SCH_1):PAGE167',
 PIN_NAMES_ROTATE='TRUE',
 PHYS_PAGE='176',
 XY='(-950,175)',
 ROT='2',
 VER='2',
 PACK_TYPE='C0201',
 CDS_LIB='pure_quanta',
 CDS_PART_NAME='Q_CAP_DIFFBUS_C0201-DIFF BUS_0A',
 TOLERANCE='20%',
 MATERIAL='X6S',
 VOLTAGE='6.3V',
 VALUE='DIFF BUS_0.22UF',
 PRIM_FILE='./archive_libs/logical/q_cap_diffbus/chips/chips.prt';

PART_NAME
 C742 'Q_CAP_DIFFBUS_C0201-DIFF BUS_0A':;

SECTION_NUMBER 1
 '@S9S_MB_2U_LIB.S9S_MB_2U(SCH_1):PAGE167_I172@PURE_QUANTA.Q_CAP_DIFFBUS(CHIPS)':
 C_PATH='@s9s_mb_2u_lib.s9s_mb_2u(sch_1):page167_i172@pure_quanta.q_cap_diffbus(~
chips)',
 P_PATH='@s9s_mb_2u_lib.s9s_mb_2u(sch_1):page176_i172@pure_quanta.q_cap_diffbus(~
chips)',
 PATH='I172',
 DRAWING='@S9S_MB_2U_LIB.S9S_MB_2U(SCH_1):PAGE167',
 PIN_NAMES_ROTATE='TRUE',
 PHYS_PAGE='176',
 XY='(3625,3625)',
 ROT='2',
 VER='2',
 PACK_TYPE='C0201',
 CDS_LIB='pure_quanta',
 CDS_PART_NAME='Q_CAP_DIFFBUS_C0201-DIFF BUS_0A',
 TOLERANCE='20%',
 MATERIAL='X6S',
 VOLTAGE='6.3V',
 VALUE='DIFF BUS_0.22UF',
 PRIM_FILE='./archive_libs/logical/q_cap_diffbus/chips/chips.prt';

PART_NAME
 C743 'Q_CAP_DIFFBUS_C0201-DIFF BUS_0A':;

SECTION_NUMBER 1
 '@S9S_MB_2U_LIB.S9S_MB_2U(SCH_1):PAGE167_I171@PURE_QUANTA.Q_CAP_DIFFBUS(CHIPS)':
 C_PATH='@s9s_mb_2u_lib.s9s_mb_2u(sch_1):page167_i171@pure_quanta.q_cap_diffbus(~
chips)',
 P_PATH='@s9s_mb_2u_lib.s9s_mb_2u(sch_1):page176_i171@pure_quanta.q_cap_diffbus(~
chips)',
 PATH='I171',
 DRAWING='@S9S_MB_2U_LIB.S9S_MB_2U(SCH_1):PAGE167',
 PIN_NAMES_ROTATE='TRUE',
 PHYS_PAGE='176',
 XY='(3625,3575)',
 ROT='2',
 VER='2',
 PACK_TYPE='C0201',
 CDS_LIB='pure_quanta',
 CDS_PART_NAME='Q_CAP_DIFFBUS_C0201-DIFF BUS_0A',
 TOLERANCE='20%',
 MATERIAL='X6S',
 VOLTAGE='6.3V',
 VALUE='DIFF BUS_0.22UF',
 PRIM_FILE='./archive_libs/logical/q_cap_diffbus/chips/chips.prt';

PART_NAME
 C744 'Q_CAP_DIFFBUS_C0201-DIFF BUS_0A':;

SECTION_NUMBER 1
 '@S9S_MB_2U_LIB.S9S_MB_2U(SCH_1):PAGE167_I170@PURE_QUANTA.Q_CAP_DIFFBUS(CHIPS)':
 C_PATH='@s9s_mb_2u_lib.s9s_mb_2u(sch_1):page167_i170@pure_quanta.q_cap_diffbus(~
chips)',
 P_PATH='@s9s_mb_2u_lib.s9s_mb_2u(sch_1):page176_i170@pure_quanta.q_cap_diffbus(~
chips)',
 PATH='I170',
 DRAWING='@S9S_MB_2U_LIB.S9S_MB_2U(SCH_1):PAGE167',
 PIN_NAMES_ROTATE='TRUE',
 PHYS_PAGE='176',
 XY='(3625,3425)',
 ROT='2',
 VER='2',
 PACK_TYPE='C0201',
 CDS_LIB='pure_quanta',
 CDS_PART_NAME='Q_CAP_DIFFBUS_C0201-DIFF BUS_0A',
 TOLERANCE='20%',
 MATERIAL='X6S',
 VOLTAGE='6.3V',
 VALUE='DIFF BUS_0.22UF',
 PRIM_FILE='./archive_libs/logical/q_cap_diffbus/chips/chips.prt';

PART_NAME
 C745 'Q_CAP_DIFFBUS_C0201-DIFF BUS_0A':;

SECTION_NUMBER 1
 '@S9S_MB_2U_LIB.S9S_MB_2U(SCH_1):PAGE167_I169@PURE_QUANTA.Q_CAP_DIFFBUS(CHIPS)':
 C_PATH='@s9s_mb_2u_lib.s9s_mb_2u(sch_1):page167_i169@pure_quanta.q_cap_diffbus(~
chips)',
 P_PATH='@s9s_mb_2u_lib.s9s_mb_2u(sch_1):page176_i169@pure_quanta.q_cap_diffbus(~
chips)',
 PATH='I169',
 DRAWING='@S9S_MB_2U_LIB.S9S_MB_2U(SCH_1):PAGE167',
 PIN_NAMES_ROTATE='TRUE',
 PHYS_PAGE='176',
 XY='(3625,3375)',
 ROT='2',
 VER='2',
 PACK_TYPE='C0201',
 CDS_LIB='pure_quanta',
 CDS_PART_NAME='Q_CAP_DIFFBUS_C0201-DIFF BUS_0A',
 TOLERANCE='20%',
 MATERIAL='X6S',
 VOLTAGE='6.3V',
 VALUE='DIFF BUS_0.22UF',
 PRIM_FILE='./archive_libs/logical/q_cap_diffbus/chips/chips.prt';

PART_NAME
 C746 'Q_CAP_DIFFBUS_C0201-DIFF BUS_0A':;

SECTION_NUMBER 1
 '@S9S_MB_2U_LIB.S9S_MB_2U(SCH_1):PAGE167_I168@PURE_QUANTA.Q_CAP_DIFFBUS(CHIPS)':
 C_PATH='@s9s_mb_2u_lib.s9s_mb_2u(sch_1):page167_i168@pure_quanta.q_cap_diffbus(~
chips)',
 P_PATH='@s9s_mb_2u_lib.s9s_mb_2u(sch_1):page176_i168@pure_quanta.q_cap_diffbus(~
chips)',
 PATH='I168',
 DRAWING='@S9S_MB_2U_LIB.S9S_MB_2U(SCH_1):PAGE167',
 PIN_NAMES_ROTATE='TRUE',
 PHYS_PAGE='176',
 XY='(3625,3225)',
 ROT='2',
 VER='2',
 PACK_TYPE='C0201',
 CDS_LIB='pure_quanta',
 CDS_PART_NAME='Q_CAP_DIFFBUS_C0201-DIFF BUS_0A',
 TOLERANCE='20%',
 MATERIAL='X6S',
 VOLTAGE='6.3V',
 VALUE='DIFF BUS_0.22UF',
 PRIM_FILE='./archive_libs/logical/q_cap_diffbus/chips/chips.prt';

PART_NAME
 C747 'Q_CAP_DIFFBUS_C0201-DIFF BUS_0A':;

SECTION_NUMBER 1
 '@S9S_MB_2U_LIB.S9S_MB_2U(SCH_1):PAGE167_I167@PURE_QUANTA.Q_CAP_DIFFBUS(CHIPS)':
 C_PATH='@s9s_mb_2u_lib.s9s_mb_2u(sch_1):page167_i167@pure_quanta.q_cap_diffbus(~
chips)',
 P_PATH='@s9s_mb_2u_lib.s9s_mb_2u(sch_1):page176_i167@pure_quanta.q_cap_diffbus(~
chips)',
 PATH='I167',
 DRAWING='@S9S_MB_2U_LIB.S9S_MB_2U(SCH_1):PAGE167',
 PIN_NAMES_ROTATE='TRUE',
 PHYS_PAGE='176',
 XY='(3625,3175)',
 ROT='2',
 VER='2',
 PACK_TYPE='C0201',
 CDS_LIB='pure_quanta',
 CDS_PART_NAME='Q_CAP_DIFFBUS_C0201-DIFF BUS_0A',
 TOLERANCE='20%',
 MATERIAL='X6S',
 VOLTAGE='6.3V',
 VALUE='DIFF BUS_0.22UF',
 PRIM_FILE='./archive_libs/logical/q_cap_diffbus/chips/chips.prt';

PART_NAME
 C748 'Q_CAP_DIFFBUS_C0201-DIFF BUS_0A':;

SECTION_NUMBER 1
 '@S9S_MB_2U_LIB.S9S_MB_2U(SCH_1):PAGE167_I163@PURE_QUANTA.Q_CAP_DIFFBUS(CHIPS)':
 C_PATH='@s9s_mb_2u_lib.s9s_mb_2u(sch_1):page167_i163@pure_quanta.q_cap_diffbus(~
chips)',
 P_PATH='@s9s_mb_2u_lib.s9s_mb_2u(sch_1):page176_i163@pure_quanta.q_cap_diffbus(~
chips)',
 PATH='I163',
 DRAWING='@S9S_MB_2U_LIB.S9S_MB_2U(SCH_1):PAGE167',
 PIN_NAMES_ROTATE='TRUE',
 PHYS_PAGE='176',
 XY='(3625,3025)',
 ROT='2',
 VER='2',
 PACK_TYPE='C0201',
 CDS_LIB='pure_quanta',
 CDS_PART_NAME='Q_CAP_DIFFBUS_C0201-DIFF BUS_0A',
 TOLERANCE='20%',
 MATERIAL='X6S',
 VOLTAGE='6.3V',
 VALUE='DIFF BUS_0.22UF',
 PRIM_FILE='./archive_libs/logical/q_cap_diffbus/chips/chips.prt';

PART_NAME
 C749 'Q_CAP_DIFFBUS_C0201-DIFF BUS_0A':;

SECTION_NUMBER 1
 '@S9S_MB_2U_LIB.S9S_MB_2U(SCH_1):PAGE167_I162@PURE_QUANTA.Q_CAP_DIFFBUS(CHIPS)':
 C_PATH='@s9s_mb_2u_lib.s9s_mb_2u(sch_1):page167_i162@pure_quanta.q_cap_diffbus(~
chips)',
 P_PATH='@s9s_mb_2u_lib.s9s_mb_2u(sch_1):page176_i162@pure_quanta.q_cap_diffbus(~
chips)',
 PATH='I162',
 DRAWING='@S9S_MB_2U_LIB.S9S_MB_2U(SCH_1):PAGE167',
 PIN_NAMES_ROTATE='TRUE',
 PHYS_PAGE='176',
 XY='(3625,2975)',
 ROT='2',
 VER='2',
 PACK_TYPE='C0201',
 CDS_LIB='pure_quanta',
 CDS_PART_NAME='Q_CAP_DIFFBUS_C0201-DIFF BUS_0A',
 TOLERANCE='20%',
 MATERIAL='X6S',
 VOLTAGE='6.3V',
 VALUE='DIFF BUS_0.22UF',
 PRIM_FILE='./archive_libs/logical/q_cap_diffbus/chips/chips.prt';

PART_NAME
 C750 'Q_CAP_DIFFBUS_C0201-DIFF BUS_0A':;

SECTION_NUMBER 1
 '@S9S_MB_2U_LIB.S9S_MB_2U(SCH_1):PAGE167_I160@PURE_QUANTA.Q_CAP_DIFFBUS(CHIPS)':
 C_PATH='@s9s_mb_2u_lib.s9s_mb_2u(sch_1):page167_i160@pure_quanta.q_cap_diffbus(~
chips)',
 P_PATH='@s9s_mb_2u_lib.s9s_mb_2u(sch_1):page176_i160@pure_quanta.q_cap_diffbus(~
chips)',
 PATH='I160',
 DRAWING='@S9S_MB_2U_LIB.S9S_MB_2U(SCH_1):PAGE167',
 PIN_NAMES_ROTATE='TRUE',
 PHYS_PAGE='176',
 XY='(3625,2825)',
 ROT='2',
 VER='2',
 PACK_TYPE='C0201',
 CDS_LIB='pure_quanta',
 CDS_PART_NAME='Q_CAP_DIFFBUS_C0201-DIFF BUS_0A',
 TOLERANCE='20%',
 MATERIAL='X6S',
 VOLTAGE='6.3V',
 VALUE='DIFF BUS_0.22UF',
 PRIM_FILE='./archive_libs/logical/q_cap_diffbus/chips/chips.prt';

PART_NAME
 C751 'Q_CAP_DIFFBUS_C0201-DIFF BUS_0A':;

SECTION_NUMBER 1
 '@S9S_MB_2U_LIB.S9S_MB_2U(SCH_1):PAGE167_I161@PURE_QUANTA.Q_CAP_DIFFBUS(CHIPS)':
 C_PATH='@s9s_mb_2u_lib.s9s_mb_2u(sch_1):page167_i161@pure_quanta.q_cap_diffbus(~
chips)',
 P_PATH='@s9s_mb_2u_lib.s9s_mb_2u(sch_1):page176_i161@pure_quanta.q_cap_diffbus(~
chips)',
 PATH='I161',
 DRAWING='@S9S_MB_2U_LIB.S9S_MB_2U(SCH_1):PAGE167',
 PIN_NAMES_ROTATE='TRUE',
 PHYS_PAGE='176',
 XY='(3625,2775)',
 ROT='2',
 VER='2',
 PACK_TYPE='C0201',
 CDS_LIB='pure_quanta',
 CDS_PART_NAME='Q_CAP_DIFFBUS_C0201-DIFF BUS_0A',
 TOLERANCE='20%',
 MATERIAL='X6S',
 VOLTAGE='6.3V',
 VALUE='DIFF BUS_0.22UF',
 PRIM_FILE='./archive_libs/logical/q_cap_diffbus/chips/chips.prt';

PART_NAME
 C752 'Q_CAP_DIFFBUS_C0201-DIFF BUS_0A':;

SECTION_NUMBER 1
 '@S9S_MB_2U_LIB.S9S_MB_2U(SCH_1):PAGE167_I159@PURE_QUANTA.Q_CAP_DIFFBUS(CHIPS)':
 C_PATH='@s9s_mb_2u_lib.s9s_mb_2u(sch_1):page167_i159@pure_quanta.q_cap_diffbus(~
chips)',
 P_PATH='@s9s_mb_2u_lib.s9s_mb_2u(sch_1):page176_i159@pure_quanta.q_cap_diffbus(~
chips)',
 PATH='I159',
 DRAWING='@S9S_MB_2U_LIB.S9S_MB_2U(SCH_1):PAGE167',
 PIN_NAMES_ROTATE='TRUE',
 PHYS_PAGE='176',
 XY='(3625,2625)',
 ROT='2',
 VER='2',
 PACK_TYPE='C0201',
 CDS_LIB='pure_quanta',
 CDS_PART_NAME='Q_CAP_DIFFBUS_C0201-DIFF BUS_0A',
 TOLERANCE='20%',
 MATERIAL='X6S',
 VOLTAGE='6.3V',
 VALUE='DIFF BUS_0.22UF',
 PRIM_FILE='./archive_libs/logical/q_cap_diffbus/chips/chips.prt';

PART_NAME
 C753 'Q_CAP_DIFFBUS_C0201-DIFF BUS_0A':;

SECTION_NUMBER 1
 '@S9S_MB_2U_LIB.S9S_MB_2U(SCH_1):PAGE167_I158@PURE_QUANTA.Q_CAP_DIFFBUS(CHIPS)':
 C_PATH='@s9s_mb_2u_lib.s9s_mb_2u(sch_1):page167_i158@pure_quanta.q_cap_diffbus(~
chips)',
 P_PATH='@s9s_mb_2u_lib.s9s_mb_2u(sch_1):page176_i158@pure_quanta.q_cap_diffbus(~
chips)',
 PATH='I158',
 DRAWING='@S9S_MB_2U_LIB.S9S_MB_2U(SCH_1):PAGE167',
 PIN_NAMES_ROTATE='TRUE',
 PHYS_PAGE='176',
 XY='(3625,2575)',
 ROT='2',
 VER='2',
 PACK_TYPE='C0201',
 CDS_LIB='pure_quanta',
 CDS_PART_NAME='Q_CAP_DIFFBUS_C0201-DIFF BUS_0A',
 TOLERANCE='20%',
 MATERIAL='X6S',
 VOLTAGE='6.3V',
 VALUE='DIFF BUS_0.22UF',
 PRIM_FILE='./archive_libs/logical/q_cap_diffbus/chips/chips.prt';

PART_NAME
 C754 'Q_CAP_DIFFBUS_C0201-DIFF BUS_0A':;

SECTION_NUMBER 1
 '@S9S_MB_2U_LIB.S9S_MB_2U(SCH_1):PAGE167_I157@PURE_QUANTA.Q_CAP_DIFFBUS(CHIPS)':
 C_PATH='@s9s_mb_2u_lib.s9s_mb_2u(sch_1):page167_i157@pure_quanta.q_cap_diffbus(~
chips)',
 P_PATH='@s9s_mb_2u_lib.s9s_mb_2u(sch_1):page176_i157@pure_quanta.q_cap_diffbus(~
chips)',
 PATH='I157',
 DRAWING='@S9S_MB_2U_LIB.S9S_MB_2U(SCH_1):PAGE167',
 PIN_NAMES_ROTATE='TRUE',
 PHYS_PAGE='176',
 XY='(3625,2425)',
 ROT='2',
 VER='2',
 PACK_TYPE='C0201',
 CDS_LIB='pure_quanta',
 CDS_PART_NAME='Q_CAP_DIFFBUS_C0201-DIFF BUS_0A',
 TOLERANCE='20%',
 MATERIAL='X6S',
 VOLTAGE='6.3V',
 VALUE='DIFF BUS_0.22UF',
 PRIM_FILE='./archive_libs/logical/q_cap_diffbus/chips/chips.prt';

PART_NAME
 C755 'Q_CAP_DIFFBUS_C0201-DIFF BUS_0A':;

SECTION_NUMBER 1
 '@S9S_MB_2U_LIB.S9S_MB_2U(SCH_1):PAGE167_I156@PURE_QUANTA.Q_CAP_DIFFBUS(CHIPS)':
 C_PATH='@s9s_mb_2u_lib.s9s_mb_2u(sch_1):page167_i156@pure_quanta.q_cap_diffbus(~
chips)',
 P_PATH='@s9s_mb_2u_lib.s9s_mb_2u(sch_1):page176_i156@pure_quanta.q_cap_diffbus(~
chips)',
 PATH='I156',
 DRAWING='@S9S_MB_2U_LIB.S9S_MB_2U(SCH_1):PAGE167',
 PIN_NAMES_ROTATE='TRUE',
 PHYS_PAGE='176',
 XY='(3625,2375)',
 ROT='2',
 VER='2',
 PACK_TYPE='C0201',
 CDS_LIB='pure_quanta',
 CDS_PART_NAME='Q_CAP_DIFFBUS_C0201-DIFF BUS_0A',
 TOLERANCE='20%',
 MATERIAL='X6S',
 VOLTAGE='6.3V',
 VALUE='DIFF BUS_0.22UF',
 PRIM_FILE='./archive_libs/logical/q_cap_diffbus/chips/chips.prt';

PART_NAME
 C756 'Q_CAP_DIFFBUS_C0201-DIFF BUS_0A':;

SECTION_NUMBER 1
 '@S9S_MB_2U_LIB.S9S_MB_2U(SCH_1):PAGE167_I154@PURE_QUANTA.Q_CAP_DIFFBUS(CHIPS)':
 C_PATH='@s9s_mb_2u_lib.s9s_mb_2u(sch_1):page167_i154@pure_quanta.q_cap_diffbus(~
chips)',
 P_PATH='@s9s_mb_2u_lib.s9s_mb_2u(sch_1):page176_i154@pure_quanta.q_cap_diffbus(~
chips)',
 PATH='I154',
 DRAWING='@S9S_MB_2U_LIB.S9S_MB_2U(SCH_1):PAGE167',
 PIN_NAMES_ROTATE='TRUE',
 PHYS_PAGE='176',
 XY='(3625,2225)',
 ROT='2',
 VER='2',
 PACK_TYPE='C0201',
 CDS_LIB='pure_quanta',
 CDS_PART_NAME='Q_CAP_DIFFBUS_C0201-DIFF BUS_0A',
 TOLERANCE='20%',
 MATERIAL='X6S',
 VOLTAGE='6.3V',
 VALUE='DIFF BUS_0.22UF',
 PRIM_FILE='./archive_libs/logical/q_cap_diffbus/chips/chips.prt';

PART_NAME
 C757 'Q_CAP_DIFFBUS_C0201-DIFF BUS_0A':;

SECTION_NUMBER 1
 '@S9S_MB_2U_LIB.S9S_MB_2U(SCH_1):PAGE167_I155@PURE_QUANTA.Q_CAP_DIFFBUS(CHIPS)':
 C_PATH='@s9s_mb_2u_lib.s9s_mb_2u(sch_1):page167_i155@pure_quanta.q_cap_diffbus(~
chips)',
 P_PATH='@s9s_mb_2u_lib.s9s_mb_2u(sch_1):page176_i155@pure_quanta.q_cap_diffbus(~
chips)',
 PATH='I155',
 DRAWING='@S9S_MB_2U_LIB.S9S_MB_2U(SCH_1):PAGE167',
 PIN_NAMES_ROTATE='TRUE',
 PHYS_PAGE='176',
 XY='(3625,2175)',
 ROT='2',
 VER='2',
 PACK_TYPE='C0201',
 CDS_LIB='pure_quanta',
 CDS_PART_NAME='Q_CAP_DIFFBUS_C0201-DIFF BUS_0A',
 TOLERANCE='20%',
 MATERIAL='X6S',
 VOLTAGE='6.3V',
 VALUE='DIFF BUS_0.22UF',
 PRIM_FILE='./archive_libs/logical/q_cap_diffbus/chips/chips.prt';

PART_NAME
 C758 'Q_CAP_DIFFBUS_C0201-DIFF BUS_0A':;

SECTION_NUMBER 1
 '@S9S_MB_2U_LIB.S9S_MB_2U(SCH_1):PAGE167_I140@PURE_QUANTA.Q_CAP_DIFFBUS(CHIPS)':
 C_PATH='@s9s_mb_2u_lib.s9s_mb_2u(sch_1):page167_i140@pure_quanta.q_cap_diffbus(~
chips)',
 P_PATH='@s9s_mb_2u_lib.s9s_mb_2u(sch_1):page176_i140@pure_quanta.q_cap_diffbus(~
chips)',
 PATH='I140',
 DRAWING='@S9S_MB_2U_LIB.S9S_MB_2U(SCH_1):PAGE167',
 PIN_NAMES_ROTATE='TRUE',
 PHYS_PAGE='176',
 XY='(3625,1650)',
 ROT='2',
 VER='2',
 PACK_TYPE='C0201',
 CDS_LIB='pure_quanta',
 CDS_PART_NAME='Q_CAP_DIFFBUS_C0201-DIFF BUS_0A',
 TOLERANCE='20%',
 MATERIAL='X6S',
 VOLTAGE='6.3V',
 VALUE='DIFF BUS_0.22UF',
 PRIM_FILE='./archive_libs/logical/q_cap_diffbus/chips/chips.prt';

PART_NAME
 C759 'Q_CAP_DIFFBUS_C0201-DIFF BUS_0A':;

SECTION_NUMBER 1
 '@S9S_MB_2U_LIB.S9S_MB_2U(SCH_1):PAGE167_I139@PURE_QUANTA.Q_CAP_DIFFBUS(CHIPS)':
 C_PATH='@s9s_mb_2u_lib.s9s_mb_2u(sch_1):page167_i139@pure_quanta.q_cap_diffbus(~
chips)',
 P_PATH='@s9s_mb_2u_lib.s9s_mb_2u(sch_1):page176_i139@pure_quanta.q_cap_diffbus(~
chips)',
 PATH='I139',
 DRAWING='@S9S_MB_2U_LIB.S9S_MB_2U(SCH_1):PAGE167',
 PIN_NAMES_ROTATE='TRUE',
 PHYS_PAGE='176',
 XY='(3625,1600)',
 ROT='2',
 VER='2',
 PACK_TYPE='C0201',
 CDS_LIB='pure_quanta',
 CDS_PART_NAME='Q_CAP_DIFFBUS_C0201-DIFF BUS_0A',
 TOLERANCE='20%',
 MATERIAL='X6S',
 VOLTAGE='6.3V',
 VALUE='DIFF BUS_0.22UF',
 PRIM_FILE='./archive_libs/logical/q_cap_diffbus/chips/chips.prt';

PART_NAME
 C760 'Q_CAP_DIFFBUS_C0201-DIFF BUS_0A':;

SECTION_NUMBER 1
 '@S9S_MB_2U_LIB.S9S_MB_2U(SCH_1):PAGE167_I138@PURE_QUANTA.Q_CAP_DIFFBUS(CHIPS)':
 C_PATH='@s9s_mb_2u_lib.s9s_mb_2u(sch_1):page167_i138@pure_quanta.q_cap_diffbus(~
chips)',
 P_PATH='@s9s_mb_2u_lib.s9s_mb_2u(sch_1):page176_i138@pure_quanta.q_cap_diffbus(~
chips)',
 PATH='I138',
 DRAWING='@S9S_MB_2U_LIB.S9S_MB_2U(SCH_1):PAGE167',
 PIN_NAMES_ROTATE='TRUE',
 PHYS_PAGE='176',
 XY='(3625,1450)',
 ROT='2',
 VER='2',
 PACK_TYPE='C0201',
 CDS_LIB='pure_quanta',
 CDS_PART_NAME='Q_CAP_DIFFBUS_C0201-DIFF BUS_0A',
 TOLERANCE='20%',
 MATERIAL='X6S',
 VOLTAGE='6.3V',
 VALUE='DIFF BUS_0.22UF',
 PRIM_FILE='./archive_libs/logical/q_cap_diffbus/chips/chips.prt';

PART_NAME
 C761 'Q_CAP_DIFFBUS_C0201-DIFF BUS_0A':;

SECTION_NUMBER 1
 '@S9S_MB_2U_LIB.S9S_MB_2U(SCH_1):PAGE167_I137@PURE_QUANTA.Q_CAP_DIFFBUS(CHIPS)':
 C_PATH='@s9s_mb_2u_lib.s9s_mb_2u(sch_1):page167_i137@pure_quanta.q_cap_diffbus(~
chips)',
 P_PATH='@s9s_mb_2u_lib.s9s_mb_2u(sch_1):page176_i137@pure_quanta.q_cap_diffbus(~
chips)',
 PATH='I137',
 DRAWING='@S9S_MB_2U_LIB.S9S_MB_2U(SCH_1):PAGE167',
 PIN_NAMES_ROTATE='TRUE',
 PHYS_PAGE='176',
 XY='(3625,1400)',
 ROT='2',
 VER='2',
 PACK_TYPE='C0201',
 CDS_LIB='pure_quanta',
 CDS_PART_NAME='Q_CAP_DIFFBUS_C0201-DIFF BUS_0A',
 TOLERANCE='20%',
 MATERIAL='X6S',
 VOLTAGE='6.3V',
 VALUE='DIFF BUS_0.22UF',
 PRIM_FILE='./archive_libs/logical/q_cap_diffbus/chips/chips.prt';

PART_NAME
 C762 'Q_CAP_DIFFBUS_C0201-DIFF BUS_0A':;

SECTION_NUMBER 1
 '@S9S_MB_2U_LIB.S9S_MB_2U(SCH_1):PAGE167_I136@PURE_QUANTA.Q_CAP_DIFFBUS(CHIPS)':
 C_PATH='@s9s_mb_2u_lib.s9s_mb_2u(sch_1):page167_i136@pure_quanta.q_cap_diffbus(~
chips)',
 P_PATH='@s9s_mb_2u_lib.s9s_mb_2u(sch_1):page176_i136@pure_quanta.q_cap_diffbus(~
chips)',
 PATH='I136',
 DRAWING='@S9S_MB_2U_LIB.S9S_MB_2U(SCH_1):PAGE167',
 PIN_NAMES_ROTATE='TRUE',
 PHYS_PAGE='176',
 XY='(3625,1250)',
 ROT='2',
 VER='2',
 PACK_TYPE='C0201',
 CDS_LIB='pure_quanta',
 CDS_PART_NAME='Q_CAP_DIFFBUS_C0201-DIFF BUS_0A',
 TOLERANCE='20%',
 MATERIAL='X6S',
 VOLTAGE='6.3V',
 VALUE='DIFF BUS_0.22UF',
 PRIM_FILE='./archive_libs/logical/q_cap_diffbus/chips/chips.prt';

PART_NAME
 C763 'Q_CAP_DIFFBUS_C0201-DIFF BUS_0A':;

SECTION_NUMBER 1
 '@S9S_MB_2U_LIB.S9S_MB_2U(SCH_1):PAGE167_I135@PURE_QUANTA.Q_CAP_DIFFBUS(CHIPS)':
 C_PATH='@s9s_mb_2u_lib.s9s_mb_2u(sch_1):page167_i135@pure_quanta.q_cap_diffbus(~
chips)',
 P_PATH='@s9s_mb_2u_lib.s9s_mb_2u(sch_1):page176_i135@pure_quanta.q_cap_diffbus(~
chips)',
 PATH='I135',
 DRAWING='@S9S_MB_2U_LIB.S9S_MB_2U(SCH_1):PAGE167',
 PIN_NAMES_ROTATE='TRUE',
 PHYS_PAGE='176',
 XY='(3625,1200)',
 ROT='2',
 VER='2',
 PACK_TYPE='C0201',
 CDS_LIB='pure_quanta',
 CDS_PART_NAME='Q_CAP_DIFFBUS_C0201-DIFF BUS_0A',
 TOLERANCE='20%',
 MATERIAL='X6S',
 VOLTAGE='6.3V',
 VALUE='DIFF BUS_0.22UF',
 PRIM_FILE='./archive_libs/logical/q_cap_diffbus/chips/chips.prt';

PART_NAME
 C764 'Q_CAP_DIFFBUS_C0201-DIFF BUS_0A':;

SECTION_NUMBER 1
 '@S9S_MB_2U_LIB.S9S_MB_2U(SCH_1):PAGE167_I130@PURE_QUANTA.Q_CAP_DIFFBUS(CHIPS)':
 C_PATH='@s9s_mb_2u_lib.s9s_mb_2u(sch_1):page167_i130@pure_quanta.q_cap_diffbus(~
chips)',
 P_PATH='@s9s_mb_2u_lib.s9s_mb_2u(sch_1):page176_i130@pure_quanta.q_cap_diffbus(~
chips)',
 PATH='I130',
 DRAWING='@S9S_MB_2U_LIB.S9S_MB_2U(SCH_1):PAGE167',
 PIN_NAMES_ROTATE='TRUE',
 PHYS_PAGE='176',
 XY='(3625,1050)',
 ROT='2',
 VER='2',
 PACK_TYPE='C0201',
 CDS_LIB='pure_quanta',
 CDS_PART_NAME='Q_CAP_DIFFBUS_C0201-DIFF BUS_0A',
 TOLERANCE='20%',
 MATERIAL='X6S',
 VOLTAGE='6.3V',
 VALUE='DIFF BUS_0.22UF',
 PRIM_FILE='./archive_libs/logical/q_cap_diffbus/chips/chips.prt';

PART_NAME
 C765 'Q_CAP_DIFFBUS_C0201-DIFF BUS_0A':;

SECTION_NUMBER 1
 '@S9S_MB_2U_LIB.S9S_MB_2U(SCH_1):PAGE167_I131@PURE_QUANTA.Q_CAP_DIFFBUS(CHIPS)':
 C_PATH='@s9s_mb_2u_lib.s9s_mb_2u(sch_1):page167_i131@pure_quanta.q_cap_diffbus(~
chips)',
 P_PATH='@s9s_mb_2u_lib.s9s_mb_2u(sch_1):page176_i131@pure_quanta.q_cap_diffbus(~
chips)',
 PATH='I131',
 DRAWING='@S9S_MB_2U_LIB.S9S_MB_2U(SCH_1):PAGE167',
 PIN_NAMES_ROTATE='TRUE',
 PHYS_PAGE='176',
 XY='(3625,1000)',
 ROT='2',
 VER='2',
 PACK_TYPE='C0201',
 CDS_LIB='pure_quanta',
 CDS_PART_NAME='Q_CAP_DIFFBUS_C0201-DIFF BUS_0A',
 TOLERANCE='20%',
 MATERIAL='X6S',
 VOLTAGE='6.3V',
 VALUE='DIFF BUS_0.22UF',
 PRIM_FILE='./archive_libs/logical/q_cap_diffbus/chips/chips.prt';

PART_NAME
 C766 'Q_CAP_DIFFBUS_C0201-DIFF BUS_0A':;

SECTION_NUMBER 1
 '@S9S_MB_2U_LIB.S9S_MB_2U(SCH_1):PAGE167_I129@PURE_QUANTA.Q_CAP_DIFFBUS(CHIPS)':
 C_PATH='@s9s_mb_2u_lib.s9s_mb_2u(sch_1):page167_i129@pure_quanta.q_cap_diffbus(~
chips)',
 P_PATH='@s9s_mb_2u_lib.s9s_mb_2u(sch_1):page176_i129@pure_quanta.q_cap_diffbus(~
chips)',
 PATH='I129',
 DRAWING='@S9S_MB_2U_LIB.S9S_MB_2U(SCH_1):PAGE167',
 PIN_NAMES_ROTATE='TRUE',
 PHYS_PAGE='176',
 XY='(3625,850)',
 ROT='2',
 VER='2',
 PACK_TYPE='C0201',
 CDS_LIB='pure_quanta',
 CDS_PART_NAME='Q_CAP_DIFFBUS_C0201-DIFF BUS_0A',
 TOLERANCE='20%',
 MATERIAL='X6S',
 VOLTAGE='6.3V',
 VALUE='DIFF BUS_0.22UF',
 PRIM_FILE='./archive_libs/logical/q_cap_diffbus/chips/chips.prt';

PART_NAME
 C767 'Q_CAP_DIFFBUS_C0201-DIFF BUS_0A':;

SECTION_NUMBER 1
 '@S9S_MB_2U_LIB.S9S_MB_2U(SCH_1):PAGE167_I128@PURE_QUANTA.Q_CAP_DIFFBUS(CHIPS)':
 C_PATH='@s9s_mb_2u_lib.s9s_mb_2u(sch_1):page167_i128@pure_quanta.q_cap_diffbus(~
chips)',
 P_PATH='@s9s_mb_2u_lib.s9s_mb_2u(sch_1):page176_i128@pure_quanta.q_cap_diffbus(~
chips)',
 PATH='I128',
 DRAWING='@S9S_MB_2U_LIB.S9S_MB_2U(SCH_1):PAGE167',
 PIN_NAMES_ROTATE='TRUE',
 PHYS_PAGE='176',
 XY='(3625,800)',
 ROT='2',
 VER='2',
 PACK_TYPE='C0201',
 CDS_LIB='pure_quanta',
 CDS_PART_NAME='Q_CAP_DIFFBUS_C0201-DIFF BUS_0A',
 TOLERANCE='20%',
 MATERIAL='X6S',
 VOLTAGE='6.3V',
 VALUE='DIFF BUS_0.22UF',
 PRIM_FILE='./archive_libs/logical/q_cap_diffbus/chips/chips.prt';

PART_NAME
 C768 'Q_CAP_DIFFBUS_C0201-DIFF BUS_0A':;

SECTION_NUMBER 1
 '@S9S_MB_2U_LIB.S9S_MB_2U(SCH_1):PAGE167_I127@PURE_QUANTA.Q_CAP_DIFFBUS(CHIPS)':
 C_PATH='@s9s_mb_2u_lib.s9s_mb_2u(sch_1):page167_i127@pure_quanta.q_cap_diffbus(~
chips)',
 P_PATH='@s9s_mb_2u_lib.s9s_mb_2u(sch_1):page176_i127@pure_quanta.q_cap_diffbus(~
chips)',
 PATH='I127',
 DRAWING='@S9S_MB_2U_LIB.S9S_MB_2U(SCH_1):PAGE167',
 PIN_NAMES_ROTATE='TRUE',
 PHYS_PAGE='176',
 XY='(3625,650)',
 ROT='2',
 VER='2',
 PACK_TYPE='C0201',
 CDS_LIB='pure_quanta',
 CDS_PART_NAME='Q_CAP_DIFFBUS_C0201-DIFF BUS_0A',
 TOLERANCE='20%',
 MATERIAL='X6S',
 VOLTAGE='6.3V',
 VALUE='DIFF BUS_0.22UF',
 PRIM_FILE='./archive_libs/logical/q_cap_diffbus/chips/chips.prt';

PART_NAME
 C769 'Q_CAP_DIFFBUS_C0201-DIFF BUS_0A':;

SECTION_NUMBER 1
 '@S9S_MB_2U_LIB.S9S_MB_2U(SCH_1):PAGE167_I126@PURE_QUANTA.Q_CAP_DIFFBUS(CHIPS)':
 C_PATH='@s9s_mb_2u_lib.s9s_mb_2u(sch_1):page167_i126@pure_quanta.q_cap_diffbus(~
chips)',
 P_PATH='@s9s_mb_2u_lib.s9s_mb_2u(sch_1):page176_i126@pure_quanta.q_cap_diffbus(~
chips)',
 PATH='I126',
 DRAWING='@S9S_MB_2U_LIB.S9S_MB_2U(SCH_1):PAGE167',
 PIN_NAMES_ROTATE='TRUE',
 PHYS_PAGE='176',
 XY='(3625,600)',
 ROT='2',
 VER='2',
 PACK_TYPE='C0201',
 CDS_LIB='pure_quanta',
 CDS_PART_NAME='Q_CAP_DIFFBUS_C0201-DIFF BUS_0A',
 TOLERANCE='20%',
 MATERIAL='X6S',
 VOLTAGE='6.3V',
 VALUE='DIFF BUS_0.22UF',
 PRIM_FILE='./archive_libs/logical/q_cap_diffbus/chips/chips.prt';

PART_NAME
 C770 'Q_CAP_DIFFBUS_C0201-DIFF BUS_0A':;

SECTION_NUMBER 1
 '@S9S_MB_2U_LIB.S9S_MB_2U(SCH_1):PAGE167_I125@PURE_QUANTA.Q_CAP_DIFFBUS(CHIPS)':
 C_PATH='@s9s_mb_2u_lib.s9s_mb_2u(sch_1):page167_i125@pure_quanta.q_cap_diffbus(~
chips)',
 P_PATH='@s9s_mb_2u_lib.s9s_mb_2u(sch_1):page176_i125@pure_quanta.q_cap_diffbus(~
chips)',
 PATH='I125',
 DRAWING='@S9S_MB_2U_LIB.S9S_MB_2U(SCH_1):PAGE167',
 PIN_NAMES_ROTATE='TRUE',
 PHYS_PAGE='176',
 XY='(3625,450)',
 ROT='2',
 VER='2',
 PACK_TYPE='C0201',
 CDS_LIB='pure_quanta',
 CDS_PART_NAME='Q_CAP_DIFFBUS_C0201-DIFF BUS_0A',
 TOLERANCE='20%',
 MATERIAL='X6S',
 VOLTAGE='6.3V',
 VALUE='DIFF BUS_0.22UF',
 PRIM_FILE='./archive_libs/logical/q_cap_diffbus/chips/chips.prt';

PART_NAME
 C771 'Q_CAP_DIFFBUS_C0201-DIFF BUS_0A':;

SECTION_NUMBER 1
 '@S9S_MB_2U_LIB.S9S_MB_2U(SCH_1):PAGE167_I124@PURE_QUANTA.Q_CAP_DIFFBUS(CHIPS)':
 C_PATH='@s9s_mb_2u_lib.s9s_mb_2u(sch_1):page167_i124@pure_quanta.q_cap_diffbus(~
chips)',
 P_PATH='@s9s_mb_2u_lib.s9s_mb_2u(sch_1):page176_i124@pure_quanta.q_cap_diffbus(~
chips)',
 PATH='I124',
 DRAWING='@S9S_MB_2U_LIB.S9S_MB_2U(SCH_1):PAGE167',
 PIN_NAMES_ROTATE='TRUE',
 PHYS_PAGE='176',
 XY='(3625,400)',
 ROT='2',
 VER='2',
 PACK_TYPE='C0201',
 CDS_LIB='pure_quanta',
 CDS_PART_NAME='Q_CAP_DIFFBUS_C0201-DIFF BUS_0A',
 TOLERANCE='20%',
 MATERIAL='X6S',
 VOLTAGE='6.3V',
 VALUE='DIFF BUS_0.22UF',
 PRIM_FILE='./archive_libs/logical/q_cap_diffbus/chips/chips.prt';

PART_NAME
 C772 'Q_CAP_DIFFBUS_C0201-DIFF BUS_0A':;

SECTION_NUMBER 1
 '@S9S_MB_2U_LIB.S9S_MB_2U(SCH_1):PAGE167_I123@PURE_QUANTA.Q_CAP_DIFFBUS(CHIPS)':
 C_PATH='@s9s_mb_2u_lib.s9s_mb_2u(sch_1):page167_i123@pure_quanta.q_cap_diffbus(~
chips)',
 P_PATH='@s9s_mb_2u_lib.s9s_mb_2u(sch_1):page176_i123@pure_quanta.q_cap_diffbus(~
chips)',
 PATH='I123',
 DRAWING='@S9S_MB_2U_LIB.S9S_MB_2U(SCH_1):PAGE167',
 PIN_NAMES_ROTATE='TRUE',
 PHYS_PAGE='176',
 XY='(3625,250)',
 ROT='2',
 VER='2',
 PACK_TYPE='C0201',
 CDS_LIB='pure_quanta',
 CDS_PART_NAME='Q_CAP_DIFFBUS_C0201-DIFF BUS_0A',
 TOLERANCE='20%',
 MATERIAL='X6S',
 VOLTAGE='6.3V',
 VALUE='DIFF BUS_0.22UF',
 PRIM_FILE='./archive_libs/logical/q_cap_diffbus/chips/chips.prt';

PART_NAME
 C773 'Q_CAP_DIFFBUS_C0201-DIFF BUS_0A':;

SECTION_NUMBER 1
 '@S9S_MB_2U_LIB.S9S_MB_2U(SCH_1):PAGE167_I122@PURE_QUANTA.Q_CAP_DIFFBUS(CHIPS)':
 C_PATH='@s9s_mb_2u_lib.s9s_mb_2u(sch_1):page167_i122@pure_quanta.q_cap_diffbus(~
chips)',
 P_PATH='@s9s_mb_2u_lib.s9s_mb_2u(sch_1):page176_i122@pure_quanta.q_cap_diffbus(~
chips)',
 PATH='I122',
 DRAWING='@S9S_MB_2U_LIB.S9S_MB_2U(SCH_1):PAGE167',
 PIN_NAMES_ROTATE='TRUE',
 PHYS_PAGE='176',
 XY='(3625,200)',
 ROT='2',
 VER='2',
 PACK_TYPE='C0201',
 CDS_LIB='pure_quanta',
 CDS_PART_NAME='Q_CAP_DIFFBUS_C0201-DIFF BUS_0A',
 TOLERANCE='20%',
 MATERIAL='X6S',
 VOLTAGE='6.3V',
 VALUE='DIFF BUS_0.22UF',
 PRIM_FILE='./archive_libs/logical/q_cap_diffbus/chips/chips.prt';

PART_NAME
 C806 'Q_CAP_DIFFBUS_C0201-DIFF BUS_0A':;

SECTION_NUMBER 1
 '@S9S_MB_2U_LIB.S9S_MB_2U(SCH_1):PAGE166_I377@PURE_QUANTA.Q_CAP_DIFFBUS(CHIPS)':
 C_PATH='@s9s_mb_2u_lib.s9s_mb_2u(sch_1):page166_i377@pure_quanta.q_cap_diffbus(~
chips)',
 P_PATH='@s9s_mb_2u_lib.s9s_mb_2u(sch_1):page175_i377@pure_quanta.q_cap_diffbus(~
chips)',
 PATH='I377',
 DRAWING='@S9S_MB_2U_LIB.S9S_MB_2U(SCH_1):PAGE166',
 PIN_NAMES_ROTATE='TRUE',
 PHYS_PAGE='175',
 XY='(3575,3575)',
 ROT='2',
 VER='2',
 PACK_TYPE='C0201',
 CDS_LIB='pure_quanta',
 CDS_PART_NAME='Q_CAP_DIFFBUS_C0201-DIFF BUS_0A',
 TOLERANCE='20%',
 MATERIAL='X6S',
 VOLTAGE='6.3V',
 VALUE='DIFF BUS_0.22UF',
 PRIM_FILE='./archive_libs/logical/q_cap_diffbus/chips/chips.prt';

PART_NAME
 C807 'Q_CAP_DIFFBUS_C0201-DIFF BUS_0A':;

SECTION_NUMBER 1
 '@S9S_MB_2U_LIB.S9S_MB_2U(SCH_1):PAGE166_I378@PURE_QUANTA.Q_CAP_DIFFBUS(CHIPS)':
 C_PATH='@s9s_mb_2u_lib.s9s_mb_2u(sch_1):page166_i378@pure_quanta.q_cap_diffbus(~
chips)',
 P_PATH='@s9s_mb_2u_lib.s9s_mb_2u(sch_1):page175_i378@pure_quanta.q_cap_diffbus(~
chips)',
 PATH='I378',
 DRAWING='@S9S_MB_2U_LIB.S9S_MB_2U(SCH_1):PAGE166',
 PIN_NAMES_ROTATE='TRUE',
 PHYS_PAGE='175',
 XY='(3575,3525)',
 ROT='2',
 VER='2',
 PACK_TYPE='C0201',
 CDS_LIB='pure_quanta',
 CDS_PART_NAME='Q_CAP_DIFFBUS_C0201-DIFF BUS_0A',
 TOLERANCE='20%',
 MATERIAL='X6S',
 VOLTAGE='6.3V',
 VALUE='DIFF BUS_0.22UF',
 PRIM_FILE='./archive_libs/logical/q_cap_diffbus/chips/chips.prt';

PART_NAME
 C808 'Q_CAP_DIFFBUS_C0201-DIFF BUS_0A':;

SECTION_NUMBER 1
 '@S9S_MB_2U_LIB.S9S_MB_2U(SCH_1):PAGE166_I376@PURE_QUANTA.Q_CAP_DIFFBUS(CHIPS)':
 C_PATH='@s9s_mb_2u_lib.s9s_mb_2u(sch_1):page166_i376@pure_quanta.q_cap_diffbus(~
chips)',
 P_PATH='@s9s_mb_2u_lib.s9s_mb_2u(sch_1):page175_i376@pure_quanta.q_cap_diffbus(~
chips)',
 PATH='I376',
 DRAWING='@S9S_MB_2U_LIB.S9S_MB_2U(SCH_1):PAGE166',
 PIN_NAMES_ROTATE='TRUE',
 PHYS_PAGE='175',
 XY='(3575,3375)',
 ROT='2',
 VER='2',
 PACK_TYPE='C0201',
 CDS_LIB='pure_quanta',
 CDS_PART_NAME='Q_CAP_DIFFBUS_C0201-DIFF BUS_0A',
 TOLERANCE='20%',
 MATERIAL='X6S',
 VOLTAGE='6.3V',
 VALUE='DIFF BUS_0.22UF',
 PRIM_FILE='./archive_libs/logical/q_cap_diffbus/chips/chips.prt';

PART_NAME
 C809 'Q_CAP_DIFFBUS_C0201-DIFF BUS_0A':;

SECTION_NUMBER 1
 '@S9S_MB_2U_LIB.S9S_MB_2U(SCH_1):PAGE166_I375@PURE_QUANTA.Q_CAP_DIFFBUS(CHIPS)':
 C_PATH='@s9s_mb_2u_lib.s9s_mb_2u(sch_1):page166_i375@pure_quanta.q_cap_diffbus(~
chips)',
 P_PATH='@s9s_mb_2u_lib.s9s_mb_2u(sch_1):page175_i375@pure_quanta.q_cap_diffbus(~
chips)',
 PATH='I375',
 DRAWING='@S9S_MB_2U_LIB.S9S_MB_2U(SCH_1):PAGE166',
 PIN_NAMES_ROTATE='TRUE',
 PHYS_PAGE='175',
 XY='(3575,3325)',
 ROT='2',
 VER='2',
 PACK_TYPE='C0201',
 CDS_LIB='pure_quanta',
 CDS_PART_NAME='Q_CAP_DIFFBUS_C0201-DIFF BUS_0A',
 TOLERANCE='20%',
 MATERIAL='X6S',
 VOLTAGE='6.3V',
 VALUE='DIFF BUS_0.22UF',
 PRIM_FILE='./archive_libs/logical/q_cap_diffbus/chips/chips.prt';

PART_NAME
 C810 'Q_CAP_DIFFBUS_C0201-DIFF BUS_0A':;

SECTION_NUMBER 1
 '@S9S_MB_2U_LIB.S9S_MB_2U(SCH_1):PAGE166_I374@PURE_QUANTA.Q_CAP_DIFFBUS(CHIPS)':
 C_PATH='@s9s_mb_2u_lib.s9s_mb_2u(sch_1):page166_i374@pure_quanta.q_cap_diffbus(~
chips)',
 P_PATH='@s9s_mb_2u_lib.s9s_mb_2u(sch_1):page175_i374@pure_quanta.q_cap_diffbus(~
chips)',
 PATH='I374',
 DRAWING='@S9S_MB_2U_LIB.S9S_MB_2U(SCH_1):PAGE166',
 PIN_NAMES_ROTATE='TRUE',
 PHYS_PAGE='175',
 XY='(3575,3175)',
 ROT='2',
 VER='2',
 PACK_TYPE='C0201',
 CDS_LIB='pure_quanta',
 CDS_PART_NAME='Q_CAP_DIFFBUS_C0201-DIFF BUS_0A',
 TOLERANCE='20%',
 MATERIAL='X6S',
 VOLTAGE='6.3V',
 VALUE='DIFF BUS_0.22UF',
 PRIM_FILE='./archive_libs/logical/q_cap_diffbus/chips/chips.prt';

PART_NAME
 C811 'Q_CAP_DIFFBUS_C0201-DIFF BUS_0A':;

SECTION_NUMBER 1
 '@S9S_MB_2U_LIB.S9S_MB_2U(SCH_1):PAGE166_I373@PURE_QUANTA.Q_CAP_DIFFBUS(CHIPS)':
 C_PATH='@s9s_mb_2u_lib.s9s_mb_2u(sch_1):page166_i373@pure_quanta.q_cap_diffbus(~
chips)',
 P_PATH='@s9s_mb_2u_lib.s9s_mb_2u(sch_1):page175_i373@pure_quanta.q_cap_diffbus(~
chips)',
 PATH='I373',
 DRAWING='@S9S_MB_2U_LIB.S9S_MB_2U(SCH_1):PAGE166',
 PIN_NAMES_ROTATE='TRUE',
 PHYS_PAGE='175',
 XY='(3575,3125)',
 ROT='2',
 VER='2',
 PACK_TYPE='C0201',
 CDS_LIB='pure_quanta',
 CDS_PART_NAME='Q_CAP_DIFFBUS_C0201-DIFF BUS_0A',
 TOLERANCE='20%',
 MATERIAL='X6S',
 VOLTAGE='6.3V',
 VALUE='DIFF BUS_0.22UF',
 PRIM_FILE='./archive_libs/logical/q_cap_diffbus/chips/chips.prt';

PART_NAME
 C812 'Q_CAP_DIFFBUS_C0201-DIFF BUS_0A':;

SECTION_NUMBER 1
 '@S9S_MB_2U_LIB.S9S_MB_2U(SCH_1):PAGE166_I371@PURE_QUANTA.Q_CAP_DIFFBUS(CHIPS)':
 C_PATH='@s9s_mb_2u_lib.s9s_mb_2u(sch_1):page166_i371@pure_quanta.q_cap_diffbus(~
chips)',
 P_PATH='@s9s_mb_2u_lib.s9s_mb_2u(sch_1):page175_i371@pure_quanta.q_cap_diffbus(~
chips)',
 PATH='I371',
 DRAWING='@S9S_MB_2U_LIB.S9S_MB_2U(SCH_1):PAGE166',
 PIN_NAMES_ROTATE='TRUE',
 PHYS_PAGE='175',
 XY='(3575,2975)',
 ROT='2',
 VER='2',
 PACK_TYPE='C0201',
 CDS_LIB='pure_quanta',
 CDS_PART_NAME='Q_CAP_DIFFBUS_C0201-DIFF BUS_0A',
 TOLERANCE='20%',
 MATERIAL='X6S',
 VOLTAGE='6.3V',
 VALUE='DIFF BUS_0.22UF',
 PRIM_FILE='./archive_libs/logical/q_cap_diffbus/chips/chips.prt';

PART_NAME
 C813 'Q_CAP_DIFFBUS_C0201-DIFF BUS_0A':;

SECTION_NUMBER 1
 '@S9S_MB_2U_LIB.S9S_MB_2U(SCH_1):PAGE166_I372@PURE_QUANTA.Q_CAP_DIFFBUS(CHIPS)':
 C_PATH='@s9s_mb_2u_lib.s9s_mb_2u(sch_1):page166_i372@pure_quanta.q_cap_diffbus(~
chips)',
 P_PATH='@s9s_mb_2u_lib.s9s_mb_2u(sch_1):page175_i372@pure_quanta.q_cap_diffbus(~
chips)',
 PATH='I372',
 DRAWING='@S9S_MB_2U_LIB.S9S_MB_2U(SCH_1):PAGE166',
 PIN_NAMES_ROTATE='TRUE',
 PHYS_PAGE='175',
 XY='(3575,2925)',
 ROT='2',
 VER='2',
 PACK_TYPE='C0201',
 CDS_LIB='pure_quanta',
 CDS_PART_NAME='Q_CAP_DIFFBUS_C0201-DIFF BUS_0A',
 TOLERANCE='20%',
 MATERIAL='X6S',
 VOLTAGE='6.3V',
 VALUE='DIFF BUS_0.22UF',
 PRIM_FILE='./archive_libs/logical/q_cap_diffbus/chips/chips.prt';

PART_NAME
 C814 'Q_CAP_DIFFBUS_C0201-DIFF BUS_0A':;

SECTION_NUMBER 1
 '@S9S_MB_2U_LIB.S9S_MB_2U(SCH_1):PAGE166_I370@PURE_QUANTA.Q_CAP_DIFFBUS(CHIPS)':
 C_PATH='@s9s_mb_2u_lib.s9s_mb_2u(sch_1):page166_i370@pure_quanta.q_cap_diffbus(~
chips)',
 P_PATH='@s9s_mb_2u_lib.s9s_mb_2u(sch_1):page175_i370@pure_quanta.q_cap_diffbus(~
chips)',
 PATH='I370',
 DRAWING='@S9S_MB_2U_LIB.S9S_MB_2U(SCH_1):PAGE166',
 PIN_NAMES_ROTATE='TRUE',
 PHYS_PAGE='175',
 XY='(3575,2775)',
 ROT='2',
 VER='2',
 PACK_TYPE='C0201',
 CDS_LIB='pure_quanta',
 CDS_PART_NAME='Q_CAP_DIFFBUS_C0201-DIFF BUS_0A',
 TOLERANCE='20%',
 MATERIAL='X6S',
 VOLTAGE='6.3V',
 VALUE='DIFF BUS_0.22UF',
 PRIM_FILE='./archive_libs/logical/q_cap_diffbus/chips/chips.prt';

PART_NAME
 C815 'Q_CAP_DIFFBUS_C0201-DIFF BUS_0A':;

SECTION_NUMBER 1
 '@S9S_MB_2U_LIB.S9S_MB_2U(SCH_1):PAGE166_I369@PURE_QUANTA.Q_CAP_DIFFBUS(CHIPS)':
 C_PATH='@s9s_mb_2u_lib.s9s_mb_2u(sch_1):page166_i369@pure_quanta.q_cap_diffbus(~
chips)',
 P_PATH='@s9s_mb_2u_lib.s9s_mb_2u(sch_1):page175_i369@pure_quanta.q_cap_diffbus(~
chips)',
 PATH='I369',
 DRAWING='@S9S_MB_2U_LIB.S9S_MB_2U(SCH_1):PAGE166',
 PIN_NAMES_ROTATE='TRUE',
 PHYS_PAGE='175',
 XY='(3575,2725)',
 ROT='2',
 VER='2',
 PACK_TYPE='C0201',
 CDS_LIB='pure_quanta',
 CDS_PART_NAME='Q_CAP_DIFFBUS_C0201-DIFF BUS_0A',
 TOLERANCE='20%',
 MATERIAL='X6S',
 VOLTAGE='6.3V',
 VALUE='DIFF BUS_0.22UF',
 PRIM_FILE='./archive_libs/logical/q_cap_diffbus/chips/chips.prt';

PART_NAME
 C816 'Q_CAP_DIFFBUS_C0201-DIFF BUS_0A':;

SECTION_NUMBER 1
 '@S9S_MB_2U_LIB.S9S_MB_2U(SCH_1):PAGE166_I368@PURE_QUANTA.Q_CAP_DIFFBUS(CHIPS)':
 C_PATH='@s9s_mb_2u_lib.s9s_mb_2u(sch_1):page166_i368@pure_quanta.q_cap_diffbus(~
chips)',
 P_PATH='@s9s_mb_2u_lib.s9s_mb_2u(sch_1):page175_i368@pure_quanta.q_cap_diffbus(~
chips)',
 PATH='I368',
 DRAWING='@S9S_MB_2U_LIB.S9S_MB_2U(SCH_1):PAGE166',
 PIN_NAMES_ROTATE='TRUE',
 PHYS_PAGE='175',
 XY='(3575,2575)',
 ROT='2',
 VER='2',
 PACK_TYPE='C0201',
 CDS_LIB='pure_quanta',
 CDS_PART_NAME='Q_CAP_DIFFBUS_C0201-DIFF BUS_0A',
 TOLERANCE='20%',
 MATERIAL='X6S',
 VOLTAGE='6.3V',
 VALUE='DIFF BUS_0.22UF',
 PRIM_FILE='./archive_libs/logical/q_cap_diffbus/chips/chips.prt';

PART_NAME
 C817 'Q_CAP_DIFFBUS_C0201-DIFF BUS_0A':;

SECTION_NUMBER 1
 '@S9S_MB_2U_LIB.S9S_MB_2U(SCH_1):PAGE166_I367@PURE_QUANTA.Q_CAP_DIFFBUS(CHIPS)':
 C_PATH='@s9s_mb_2u_lib.s9s_mb_2u(sch_1):page166_i367@pure_quanta.q_cap_diffbus(~
chips)',
 P_PATH='@s9s_mb_2u_lib.s9s_mb_2u(sch_1):page175_i367@pure_quanta.q_cap_diffbus(~
chips)',
 PATH='I367',
 DRAWING='@S9S_MB_2U_LIB.S9S_MB_2U(SCH_1):PAGE166',
 PIN_NAMES_ROTATE='TRUE',
 PHYS_PAGE='175',
 XY='(3575,2525)',
 ROT='2',
 VER='2',
 PACK_TYPE='C0201',
 CDS_LIB='pure_quanta',
 CDS_PART_NAME='Q_CAP_DIFFBUS_C0201-DIFF BUS_0A',
 TOLERANCE='20%',
 MATERIAL='X6S',
 VOLTAGE='6.3V',
 VALUE='DIFF BUS_0.22UF',
 PRIM_FILE='./archive_libs/logical/q_cap_diffbus/chips/chips.prt';

PART_NAME
 C818 'Q_CAP_DIFFBUS_C0201-DIFF BUS_0A':;

SECTION_NUMBER 1
 '@S9S_MB_2U_LIB.S9S_MB_2U(SCH_1):PAGE166_I365@PURE_QUANTA.Q_CAP_DIFFBUS(CHIPS)':
 C_PATH='@s9s_mb_2u_lib.s9s_mb_2u(sch_1):page166_i365@pure_quanta.q_cap_diffbus(~
chips)',
 P_PATH='@s9s_mb_2u_lib.s9s_mb_2u(sch_1):page175_i365@pure_quanta.q_cap_diffbus(~
chips)',
 PATH='I365',
 DRAWING='@S9S_MB_2U_LIB.S9S_MB_2U(SCH_1):PAGE166',
 PIN_NAMES_ROTATE='TRUE',
 PHYS_PAGE='175',
 XY='(3575,2375)',
 ROT='2',
 VER='2',
 PACK_TYPE='C0201',
 CDS_LIB='pure_quanta',
 CDS_PART_NAME='Q_CAP_DIFFBUS_C0201-DIFF BUS_0A',
 TOLERANCE='20%',
 MATERIAL='X6S',
 VOLTAGE='6.3V',
 VALUE='DIFF BUS_0.22UF',
 PRIM_FILE='./archive_libs/logical/q_cap_diffbus/chips/chips.prt';

PART_NAME
 C819 'Q_CAP_DIFFBUS_C0201-DIFF BUS_0A':;

SECTION_NUMBER 1
 '@S9S_MB_2U_LIB.S9S_MB_2U(SCH_1):PAGE166_I366@PURE_QUANTA.Q_CAP_DIFFBUS(CHIPS)':
 C_PATH='@s9s_mb_2u_lib.s9s_mb_2u(sch_1):page166_i366@pure_quanta.q_cap_diffbus(~
chips)',
 P_PATH='@s9s_mb_2u_lib.s9s_mb_2u(sch_1):page175_i366@pure_quanta.q_cap_diffbus(~
chips)',
 PATH='I366',
 DRAWING='@S9S_MB_2U_LIB.S9S_MB_2U(SCH_1):PAGE166',
 PIN_NAMES_ROTATE='TRUE',
 PHYS_PAGE='175',
 XY='(3575,2325)',
 ROT='2',
 VER='2',
 PACK_TYPE='C0201',
 CDS_LIB='pure_quanta',
 CDS_PART_NAME='Q_CAP_DIFFBUS_C0201-DIFF BUS_0A',
 TOLERANCE='20%',
 MATERIAL='X6S',
 VOLTAGE='6.3V',
 VALUE='DIFF BUS_0.22UF',
 PRIM_FILE='./archive_libs/logical/q_cap_diffbus/chips/chips.prt';

PART_NAME
 C820 'Q_CAP_DIFFBUS_C0201-DIFF BUS_0A':;

SECTION_NUMBER 1
 '@S9S_MB_2U_LIB.S9S_MB_2U(SCH_1):PAGE166_I363@PURE_QUANTA.Q_CAP_DIFFBUS(CHIPS)':
 C_PATH='@s9s_mb_2u_lib.s9s_mb_2u(sch_1):page166_i363@pure_quanta.q_cap_diffbus(~
chips)',
 P_PATH='@s9s_mb_2u_lib.s9s_mb_2u(sch_1):page175_i363@pure_quanta.q_cap_diffbus(~
chips)',
 PATH='I363',
 DRAWING='@S9S_MB_2U_LIB.S9S_MB_2U(SCH_1):PAGE166',
 PIN_NAMES_ROTATE='TRUE',
 PHYS_PAGE='175',
 XY='(3575,2175)',
 ROT='2',
 VER='2',
 PACK_TYPE='C0201',
 CDS_LIB='pure_quanta',
 CDS_PART_NAME='Q_CAP_DIFFBUS_C0201-DIFF BUS_0A',
 TOLERANCE='20%',
 MATERIAL='X6S',
 VOLTAGE='6.3V',
 VALUE='DIFF BUS_0.22UF',
 PRIM_FILE='./archive_libs/logical/q_cap_diffbus/chips/chips.prt';

PART_NAME
 C821 'Q_CAP_DIFFBUS_C0201-DIFF BUS_0A':;

SECTION_NUMBER 1
 '@S9S_MB_2U_LIB.S9S_MB_2U(SCH_1):PAGE166_I364@PURE_QUANTA.Q_CAP_DIFFBUS(CHIPS)':
 C_PATH='@s9s_mb_2u_lib.s9s_mb_2u(sch_1):page166_i364@pure_quanta.q_cap_diffbus(~
chips)',
 P_PATH='@s9s_mb_2u_lib.s9s_mb_2u(sch_1):page175_i364@pure_quanta.q_cap_diffbus(~
chips)',
 PATH='I364',
 DRAWING='@S9S_MB_2U_LIB.S9S_MB_2U(SCH_1):PAGE166',
 PIN_NAMES_ROTATE='TRUE',
 PHYS_PAGE='175',
 XY='(3575,2125)',
 ROT='2',
 VER='2',
 PACK_TYPE='C0201',
 CDS_LIB='pure_quanta',
 CDS_PART_NAME='Q_CAP_DIFFBUS_C0201-DIFF BUS_0A',
 TOLERANCE='20%',
 MATERIAL='X6S',
 VOLTAGE='6.3V',
 VALUE='DIFF BUS_0.22UF',
 PRIM_FILE='./archive_libs/logical/q_cap_diffbus/chips/chips.prt';

PART_NAME
 C822 'Q_CAP_DIFFBUS_C0201-DIFF BUS_0A':;

SECTION_NUMBER 1
 '@S9S_MB_2U_LIB.S9S_MB_2U(SCH_1):PAGE166_I345@PURE_QUANTA.Q_CAP_DIFFBUS(CHIPS)':
 C_PATH='@s9s_mb_2u_lib.s9s_mb_2u(sch_1):page166_i345@pure_quanta.q_cap_diffbus(~
chips)',
 P_PATH='@s9s_mb_2u_lib.s9s_mb_2u(sch_1):page175_i345@pure_quanta.q_cap_diffbus(~
chips)',
 PATH='I345',
 DRAWING='@S9S_MB_2U_LIB.S9S_MB_2U(SCH_1):PAGE166',
 PIN_NAMES_ROTATE='TRUE',
 PHYS_PAGE='175',
 XY='(3575,1600)',
 ROT='2',
 VER='2',
 PACK_TYPE='C0201',
 CDS_LIB='pure_quanta',
 CDS_PART_NAME='Q_CAP_DIFFBUS_C0201-DIFF BUS_0A',
 TOLERANCE='20%',
 MATERIAL='X6S',
 VOLTAGE='6.3V',
 VALUE='DIFF BUS_0.22UF',
 PRIM_FILE='./archive_libs/logical/q_cap_diffbus/chips/chips.prt';

PART_NAME
 C823 'Q_CAP_DIFFBUS_C0201-DIFF BUS_0A':;

SECTION_NUMBER 1
 '@S9S_MB_2U_LIB.S9S_MB_2U(SCH_1):PAGE166_I346@PURE_QUANTA.Q_CAP_DIFFBUS(CHIPS)':
 C_PATH='@s9s_mb_2u_lib.s9s_mb_2u(sch_1):page166_i346@pure_quanta.q_cap_diffbus(~
chips)',
 P_PATH='@s9s_mb_2u_lib.s9s_mb_2u(sch_1):page175_i346@pure_quanta.q_cap_diffbus(~
chips)',
 PATH='I346',
 DRAWING='@S9S_MB_2U_LIB.S9S_MB_2U(SCH_1):PAGE166',
 PIN_NAMES_ROTATE='TRUE',
 PHYS_PAGE='175',
 XY='(3575,1550)',
 ROT='2',
 VER='2',
 PACK_TYPE='C0201',
 CDS_LIB='pure_quanta',
 CDS_PART_NAME='Q_CAP_DIFFBUS_C0201-DIFF BUS_0A',
 TOLERANCE='20%',
 MATERIAL='X6S',
 VOLTAGE='6.3V',
 VALUE='DIFF BUS_0.22UF',
 PRIM_FILE='./archive_libs/logical/q_cap_diffbus/chips/chips.prt';

PART_NAME
 C824 'Q_CAP_DIFFBUS_C0201-DIFF BUS_0A':;

SECTION_NUMBER 1
 '@S9S_MB_2U_LIB.S9S_MB_2U(SCH_1):PAGE166_I416@PURE_QUANTA.Q_CAP_DIFFBUS(CHIPS)':
 C_PATH='@s9s_mb_2u_lib.s9s_mb_2u(sch_1):page166_i416@pure_quanta.q_cap_diffbus(~
chips)',
 P_PATH='@s9s_mb_2u_lib.s9s_mb_2u(sch_1):page175_i416@pure_quanta.q_cap_diffbus(~
chips)',
 PATH='I416',
 DRAWING='@S9S_MB_2U_LIB.S9S_MB_2U(SCH_1):PAGE166',
 PIN_NAMES_ROTATE='TRUE',
 PHYS_PAGE='175',
 XY='(3575,1400)',
 ROT='2',
 VER='2',
 PACK_TYPE='C0201',
 CDS_LIB='pure_quanta',
 CDS_PART_NAME='Q_CAP_DIFFBUS_C0201-DIFF BUS_0A',
 TOLERANCE='20%',
 MATERIAL='X6S',
 VOLTAGE='6.3V',
 VALUE='DIFF BUS_0.22UF',
 PRIM_FILE='./archive_libs/logical/q_cap_diffbus/chips/chips.prt';

PART_NAME
 C825 'Q_CAP_DIFFBUS_C0201-DIFF BUS_0A':;

SECTION_NUMBER 1
 '@S9S_MB_2U_LIB.S9S_MB_2U(SCH_1):PAGE166_I415@PURE_QUANTA.Q_CAP_DIFFBUS(CHIPS)':
 C_PATH='@s9s_mb_2u_lib.s9s_mb_2u(sch_1):page166_i415@pure_quanta.q_cap_diffbus(~
chips)',
 P_PATH='@s9s_mb_2u_lib.s9s_mb_2u(sch_1):page175_i415@pure_quanta.q_cap_diffbus(~
chips)',
 PATH='I415',
 DRAWING='@S9S_MB_2U_LIB.S9S_MB_2U(SCH_1):PAGE166',
 PIN_NAMES_ROTATE='TRUE',
 PHYS_PAGE='175',
 XY='(3575,1350)',
 ROT='2',
 VER='2',
 PACK_TYPE='C0201',
 CDS_LIB='pure_quanta',
 CDS_PART_NAME='Q_CAP_DIFFBUS_C0201-DIFF BUS_0A',
 TOLERANCE='20%',
 MATERIAL='X6S',
 VOLTAGE='6.3V',
 VALUE='DIFF BUS_0.22UF',
 PRIM_FILE='./archive_libs/logical/q_cap_diffbus/chips/chips.prt';

PART_NAME
 C826 'Q_CAP_DIFFBUS_C0201-DIFF BUS_0A':;

SECTION_NUMBER 1
 '@S9S_MB_2U_LIB.S9S_MB_2U(SCH_1):PAGE166_I344@PURE_QUANTA.Q_CAP_DIFFBUS(CHIPS)':
 C_PATH='@s9s_mb_2u_lib.s9s_mb_2u(sch_1):page166_i344@pure_quanta.q_cap_diffbus(~
chips)',
 P_PATH='@s9s_mb_2u_lib.s9s_mb_2u(sch_1):page175_i344@pure_quanta.q_cap_diffbus(~
chips)',
 PATH='I344',
 DRAWING='@S9S_MB_2U_LIB.S9S_MB_2U(SCH_1):PAGE166',
 PIN_NAMES_ROTATE='TRUE',
 PHYS_PAGE='175',
 XY='(3575,1200)',
 ROT='2',
 VER='2',
 PACK_TYPE='C0201',
 CDS_LIB='pure_quanta',
 CDS_PART_NAME='Q_CAP_DIFFBUS_C0201-DIFF BUS_0A',
 TOLERANCE='20%',
 MATERIAL='X6S',
 VOLTAGE='6.3V',
 VALUE='DIFF BUS_0.22UF',
 PRIM_FILE='./archive_libs/logical/q_cap_diffbus/chips/chips.prt';

PART_NAME
 C827 'Q_CAP_DIFFBUS_C0201-DIFF BUS_0A':;

SECTION_NUMBER 1
 '@S9S_MB_2U_LIB.S9S_MB_2U(SCH_1):PAGE166_I343@PURE_QUANTA.Q_CAP_DIFFBUS(CHIPS)':
 C_PATH='@s9s_mb_2u_lib.s9s_mb_2u(sch_1):page166_i343@pure_quanta.q_cap_diffbus(~
chips)',
 P_PATH='@s9s_mb_2u_lib.s9s_mb_2u(sch_1):page175_i343@pure_quanta.q_cap_diffbus(~
chips)',
 PATH='I343',
 DRAWING='@S9S_MB_2U_LIB.S9S_MB_2U(SCH_1):PAGE166',
 PIN_NAMES_ROTATE='TRUE',
 PHYS_PAGE='175',
 XY='(3575,1150)',
 ROT='2',
 VER='2',
 PACK_TYPE='C0201',
 CDS_LIB='pure_quanta',
 CDS_PART_NAME='Q_CAP_DIFFBUS_C0201-DIFF BUS_0A',
 TOLERANCE='20%',
 MATERIAL='X6S',
 VOLTAGE='6.3V',
 VALUE='DIFF BUS_0.22UF',
 PRIM_FILE='./archive_libs/logical/q_cap_diffbus/chips/chips.prt';

PART_NAME
 C828 'Q_CAP_DIFFBUS_C0201-DIFF BUS_0A':;

SECTION_NUMBER 1
 '@S9S_MB_2U_LIB.S9S_MB_2U(SCH_1):PAGE166_I340@PURE_QUANTA.Q_CAP_DIFFBUS(CHIPS)':
 C_PATH='@s9s_mb_2u_lib.s9s_mb_2u(sch_1):page166_i340@pure_quanta.q_cap_diffbus(~
chips)',
 P_PATH='@s9s_mb_2u_lib.s9s_mb_2u(sch_1):page175_i340@pure_quanta.q_cap_diffbus(~
chips)',
 PATH='I340',
 DRAWING='@S9S_MB_2U_LIB.S9S_MB_2U(SCH_1):PAGE166',
 PIN_NAMES_ROTATE='TRUE',
 PHYS_PAGE='175',
 XY='(3575,1000)',
 ROT='2',
 VER='2',
 PACK_TYPE='C0201',
 CDS_LIB='pure_quanta',
 CDS_PART_NAME='Q_CAP_DIFFBUS_C0201-DIFF BUS_0A',
 TOLERANCE='20%',
 MATERIAL='X6S',
 VOLTAGE='6.3V',
 VALUE='DIFF BUS_0.22UF',
 PRIM_FILE='./archive_libs/logical/q_cap_diffbus/chips/chips.prt';

PART_NAME
 C829 'Q_CAP_DIFFBUS_C0201-DIFF BUS_0A':;

SECTION_NUMBER 1
 '@S9S_MB_2U_LIB.S9S_MB_2U(SCH_1):PAGE166_I342@PURE_QUANTA.Q_CAP_DIFFBUS(CHIPS)':
 C_PATH='@s9s_mb_2u_lib.s9s_mb_2u(sch_1):page166_i342@pure_quanta.q_cap_diffbus(~
chips)',
 P_PATH='@s9s_mb_2u_lib.s9s_mb_2u(sch_1):page175_i342@pure_quanta.q_cap_diffbus(~
chips)',
 PATH='I342',
 DRAWING='@S9S_MB_2U_LIB.S9S_MB_2U(SCH_1):PAGE166',
 PIN_NAMES_ROTATE='TRUE',
 PHYS_PAGE='175',
 XY='(3575,950)',
 ROT='2',
 VER='2',
 PACK_TYPE='C0201',
 CDS_LIB='pure_quanta',
 CDS_PART_NAME='Q_CAP_DIFFBUS_C0201-DIFF BUS_0A',
 TOLERANCE='20%',
 MATERIAL='X6S',
 VOLTAGE='6.3V',
 VALUE='DIFF BUS_0.22UF',
 PRIM_FILE='./archive_libs/logical/q_cap_diffbus/chips/chips.prt';

PART_NAME
 C830 'Q_CAP_DIFFBUS_C0201-DIFF BUS_0A':;

SECTION_NUMBER 1
 '@S9S_MB_2U_LIB.S9S_MB_2U(SCH_1):PAGE166_I341@PURE_QUANTA.Q_CAP_DIFFBUS(CHIPS)':
 C_PATH='@s9s_mb_2u_lib.s9s_mb_2u(sch_1):page166_i341@pure_quanta.q_cap_diffbus(~
chips)',
 P_PATH='@s9s_mb_2u_lib.s9s_mb_2u(sch_1):page175_i341@pure_quanta.q_cap_diffbus(~
chips)',
 PATH='I341',
 DRAWING='@S9S_MB_2U_LIB.S9S_MB_2U(SCH_1):PAGE166',
 PIN_NAMES_ROTATE='TRUE',
 PHYS_PAGE='175',
 XY='(3575,800)',
 ROT='2',
 VER='2',
 PACK_TYPE='C0201',
 CDS_LIB='pure_quanta',
 CDS_PART_NAME='Q_CAP_DIFFBUS_C0201-DIFF BUS_0A',
 TOLERANCE='20%',
 MATERIAL='X6S',
 VOLTAGE='6.3V',
 VALUE='DIFF BUS_0.22UF',
 PRIM_FILE='./archive_libs/logical/q_cap_diffbus/chips/chips.prt';

PART_NAME
 C831 'Q_CAP_DIFFBUS_C0201-DIFF BUS_0A':;

SECTION_NUMBER 1
 '@S9S_MB_2U_LIB.S9S_MB_2U(SCH_1):PAGE166_I337@PURE_QUANTA.Q_CAP_DIFFBUS(CHIPS)':
 C_PATH='@s9s_mb_2u_lib.s9s_mb_2u(sch_1):page166_i337@pure_quanta.q_cap_diffbus(~
chips)',
 P_PATH='@s9s_mb_2u_lib.s9s_mb_2u(sch_1):page175_i337@pure_quanta.q_cap_diffbus(~
chips)',
 PATH='I337',
 DRAWING='@S9S_MB_2U_LIB.S9S_MB_2U(SCH_1):PAGE166',
 PIN_NAMES_ROTATE='TRUE',
 PHYS_PAGE='175',
 XY='(3575,750)',
 ROT='2',
 VER='2',
 PACK_TYPE='C0201',
 CDS_LIB='pure_quanta',
 CDS_PART_NAME='Q_CAP_DIFFBUS_C0201-DIFF BUS_0A',
 TOLERANCE='20%',
 MATERIAL='X6S',
 VOLTAGE='6.3V',
 VALUE='DIFF BUS_0.22UF',
 PRIM_FILE='./archive_libs/logical/q_cap_diffbus/chips/chips.prt';

PART_NAME
 C832 'Q_CAP_DIFFBUS_C0201-DIFF BUS_0A':;

SECTION_NUMBER 1
 '@S9S_MB_2U_LIB.S9S_MB_2U(SCH_1):PAGE166_I338@PURE_QUANTA.Q_CAP_DIFFBUS(CHIPS)':
 C_PATH='@s9s_mb_2u_lib.s9s_mb_2u(sch_1):page166_i338@pure_quanta.q_cap_diffbus(~
chips)',
 P_PATH='@s9s_mb_2u_lib.s9s_mb_2u(sch_1):page175_i338@pure_quanta.q_cap_diffbus(~
chips)',
 PATH='I338',
 DRAWING='@S9S_MB_2U_LIB.S9S_MB_2U(SCH_1):PAGE166',
 PIN_NAMES_ROTATE='TRUE',
 PHYS_PAGE='175',
 XY='(3575,600)',
 ROT='2',
 VER='2',
 PACK_TYPE='C0201',
 CDS_LIB='pure_quanta',
 CDS_PART_NAME='Q_CAP_DIFFBUS_C0201-DIFF BUS_0A',
 TOLERANCE='20%',
 MATERIAL='X6S',
 VOLTAGE='6.3V',
 VALUE='DIFF BUS_0.22UF',
 PRIM_FILE='./archive_libs/logical/q_cap_diffbus/chips/chips.prt';

PART_NAME
 C833 'Q_CAP_DIFFBUS_C0201-DIFF BUS_0A':;

SECTION_NUMBER 1
 '@S9S_MB_2U_LIB.S9S_MB_2U(SCH_1):PAGE166_I339@PURE_QUANTA.Q_CAP_DIFFBUS(CHIPS)':
 C_PATH='@s9s_mb_2u_lib.s9s_mb_2u(sch_1):page166_i339@pure_quanta.q_cap_diffbus(~
chips)',
 P_PATH='@s9s_mb_2u_lib.s9s_mb_2u(sch_1):page175_i339@pure_quanta.q_cap_diffbus(~
chips)',
 PATH='I339',
 DRAWING='@S9S_MB_2U_LIB.S9S_MB_2U(SCH_1):PAGE166',
 PIN_NAMES_ROTATE='TRUE',
 PHYS_PAGE='175',
 XY='(3575,550)',
 ROT='2',
 VER='2',
 PACK_TYPE='C0201',
 CDS_LIB='pure_quanta',
 CDS_PART_NAME='Q_CAP_DIFFBUS_C0201-DIFF BUS_0A',
 TOLERANCE='20%',
 MATERIAL='X6S',
 VOLTAGE='6.3V',
 VALUE='DIFF BUS_0.22UF',
 PRIM_FILE='./archive_libs/logical/q_cap_diffbus/chips/chips.prt';

PART_NAME
 C834 'Q_CAP_DIFFBUS_C0201-DIFF BUS_0A':;

SECTION_NUMBER 1
 '@S9S_MB_2U_LIB.S9S_MB_2U(SCH_1):PAGE166_I335@PURE_QUANTA.Q_CAP_DIFFBUS(CHIPS)':
 C_PATH='@s9s_mb_2u_lib.s9s_mb_2u(sch_1):page166_i335@pure_quanta.q_cap_diffbus(~
chips)',
 P_PATH='@s9s_mb_2u_lib.s9s_mb_2u(sch_1):page175_i335@pure_quanta.q_cap_diffbus(~
chips)',
 PATH='I335',
 DRAWING='@S9S_MB_2U_LIB.S9S_MB_2U(SCH_1):PAGE166',
 PIN_NAMES_ROTATE='TRUE',
 PHYS_PAGE='175',
 XY='(3575,400)',
 ROT='2',
 VER='2',
 PACK_TYPE='C0201',
 CDS_LIB='pure_quanta',
 CDS_PART_NAME='Q_CAP_DIFFBUS_C0201-DIFF BUS_0A',
 TOLERANCE='20%',
 MATERIAL='X6S',
 VOLTAGE='6.3V',
 VALUE='DIFF BUS_0.22UF',
 PRIM_FILE='./archive_libs/logical/q_cap_diffbus/chips/chips.prt';

PART_NAME
 C835 'Q_CAP_DIFFBUS_C0201-DIFF BUS_0A':;

SECTION_NUMBER 1
 '@S9S_MB_2U_LIB.S9S_MB_2U(SCH_1):PAGE166_I336@PURE_QUANTA.Q_CAP_DIFFBUS(CHIPS)':
 C_PATH='@s9s_mb_2u_lib.s9s_mb_2u(sch_1):page166_i336@pure_quanta.q_cap_diffbus(~
chips)',
 P_PATH='@s9s_mb_2u_lib.s9s_mb_2u(sch_1):page175_i336@pure_quanta.q_cap_diffbus(~
chips)',
 PATH='I336',
 DRAWING='@S9S_MB_2U_LIB.S9S_MB_2U(SCH_1):PAGE166',
 PIN_NAMES_ROTATE='TRUE',
 PHYS_PAGE='175',
 XY='(3575,350)',
 ROT='2',
 VER='2',
 PACK_TYPE='C0201',
 CDS_LIB='pure_quanta',
 CDS_PART_NAME='Q_CAP_DIFFBUS_C0201-DIFF BUS_0A',
 TOLERANCE='20%',
 MATERIAL='X6S',
 VOLTAGE='6.3V',
 VALUE='DIFF BUS_0.22UF',
 PRIM_FILE='./archive_libs/logical/q_cap_diffbus/chips/chips.prt';

PART_NAME
 C836 'Q_CAP_DIFFBUS_C0201-DIFF BUS_0A':;

SECTION_NUMBER 1
 '@S9S_MB_2U_LIB.S9S_MB_2U(SCH_1):PAGE166_I333@PURE_QUANTA.Q_CAP_DIFFBUS(CHIPS)':
 C_PATH='@s9s_mb_2u_lib.s9s_mb_2u(sch_1):page166_i333@pure_quanta.q_cap_diffbus(~
chips)',
 P_PATH='@s9s_mb_2u_lib.s9s_mb_2u(sch_1):page175_i333@pure_quanta.q_cap_diffbus(~
chips)',
 PATH='I333',
 DRAWING='@S9S_MB_2U_LIB.S9S_MB_2U(SCH_1):PAGE166',
 PIN_NAMES_ROTATE='TRUE',
 PHYS_PAGE='175',
 XY='(3575,200)',
 ROT='2',
 VER='2',
 PACK_TYPE='C0201',
 CDS_LIB='pure_quanta',
 CDS_PART_NAME='Q_CAP_DIFFBUS_C0201-DIFF BUS_0A',
 TOLERANCE='20%',
 MATERIAL='X6S',
 VOLTAGE='6.3V',
 VALUE='DIFF BUS_0.22UF',
 PRIM_FILE='./archive_libs/logical/q_cap_diffbus/chips/chips.prt';

PART_NAME
 C837 'Q_CAP_DIFFBUS_C0201-DIFF BUS_0A':;

SECTION_NUMBER 1
 '@S9S_MB_2U_LIB.S9S_MB_2U(SCH_1):PAGE166_I334@PURE_QUANTA.Q_CAP_DIFFBUS(CHIPS)':
 C_PATH='@s9s_mb_2u_lib.s9s_mb_2u(sch_1):page166_i334@pure_quanta.q_cap_diffbus(~
chips)',
 P_PATH='@s9s_mb_2u_lib.s9s_mb_2u(sch_1):page175_i334@pure_quanta.q_cap_diffbus(~
chips)',
 PATH='I334',
 DRAWING='@S9S_MB_2U_LIB.S9S_MB_2U(SCH_1):PAGE166',
 PIN_NAMES_ROTATE='TRUE',
 PHYS_PAGE='175',
 XY='(3575,150)',
 ROT='2',
 VER='2',
 PACK_TYPE='C0201',
 CDS_LIB='pure_quanta',
 CDS_PART_NAME='Q_CAP_DIFFBUS_C0201-DIFF BUS_0A',
 TOLERANCE='20%',
 MATERIAL='X6S',
 VOLTAGE='6.3V',
 VALUE='DIFF BUS_0.22UF',
 PRIM_FILE='./archive_libs/logical/q_cap_diffbus/chips/chips.prt';

PART_NAME
 C838 'Q_CAP_DIFFBUS_C0201-DIFF BUS_0A':;

SECTION_NUMBER 1
 '@S9S_MB_2U_LIB.S9S_MB_2U(SCH_1):PAGE165_I80@PURE_QUANTA.Q_CAP_DIFFBUS(CHIPS)':
 C_PATH='@s9s_mb_2u_lib.s9s_mb_2u(sch_1):page165_i80@pure_quanta.q_cap_diffbus(c~
hips)',
 P_PATH='@s9s_mb_2u_lib.s9s_mb_2u(sch_1):page174_i80@pure_quanta.q_cap_diffbus(c~
hips)',
 PATH='I80',
 DRAWING='@S9S_MB_2U_LIB.S9S_MB_2U(SCH_1):PAGE165',
 PIN_NAMES_ROTATE='TRUE',
 PHYS_PAGE='174',
 XY='(-650,3550)',
 ROT='2',
 VER='2',
 PACK_TYPE='C0201',
 CDS_LIB='pure_quanta',
 CDS_PART_NAME='Q_CAP_DIFFBUS_C0201-DIFF BUS_0A',
 TOLERANCE='20%',
 MATERIAL='X6S',
 VOLTAGE='6.3V',
 VALUE='DIFF BUS_0.22UF',
 PRIM_FILE='./archive_libs/logical/q_cap_diffbus/chips/chips.prt';

PART_NAME
 C839 'Q_CAP_DIFFBUS_C0201-DIFF BUS_0A':;

SECTION_NUMBER 1
 '@S9S_MB_2U_LIB.S9S_MB_2U(SCH_1):PAGE165_I81@PURE_QUANTA.Q_CAP_DIFFBUS(CHIPS)':
 C_PATH='@s9s_mb_2u_lib.s9s_mb_2u(sch_1):page165_i81@pure_quanta.q_cap_diffbus(c~
hips)',
 P_PATH='@s9s_mb_2u_lib.s9s_mb_2u(sch_1):page174_i81@pure_quanta.q_cap_diffbus(c~
hips)',
 PATH='I81',
 DRAWING='@S9S_MB_2U_LIB.S9S_MB_2U(SCH_1):PAGE165',
 PIN_NAMES_ROTATE='TRUE',
 PHYS_PAGE='174',
 XY='(-650,3500)',
 ROT='2',
 VER='2',
 PACK_TYPE='C0201',
 CDS_LIB='pure_quanta',
 CDS_PART_NAME='Q_CAP_DIFFBUS_C0201-DIFF BUS_0A',
 TOLERANCE='20%',
 MATERIAL='X6S',
 VOLTAGE='6.3V',
 VALUE='DIFF BUS_0.22UF',
 PRIM_FILE='./archive_libs/logical/q_cap_diffbus/chips/chips.prt';

PART_NAME
 C840 'Q_CAP_DIFFBUS_C0201-DIFF BUS_0A':;

SECTION_NUMBER 1
 '@S9S_MB_2U_LIB.S9S_MB_2U(SCH_1):PAGE165_I79@PURE_QUANTA.Q_CAP_DIFFBUS(CHIPS)':
 C_PATH='@s9s_mb_2u_lib.s9s_mb_2u(sch_1):page165_i79@pure_quanta.q_cap_diffbus(c~
hips)',
 P_PATH='@s9s_mb_2u_lib.s9s_mb_2u(sch_1):page174_i79@pure_quanta.q_cap_diffbus(c~
hips)',
 PATH='I79',
 DRAWING='@S9S_MB_2U_LIB.S9S_MB_2U(SCH_1):PAGE165',
 PIN_NAMES_ROTATE='TRUE',
 PHYS_PAGE='174',
 XY='(-650,3350)',
 ROT='2',
 VER='2',
 PACK_TYPE='C0201',
 CDS_LIB='pure_quanta',
 CDS_PART_NAME='Q_CAP_DIFFBUS_C0201-DIFF BUS_0A',
 TOLERANCE='20%',
 MATERIAL='X6S',
 VOLTAGE='6.3V',
 VALUE='DIFF BUS_0.22UF',
 PRIM_FILE='./archive_libs/logical/q_cap_diffbus/chips/chips.prt';

PART_NAME
 C841 'Q_CAP_DIFFBUS_C0201-DIFF BUS_0A':;

SECTION_NUMBER 1
 '@S9S_MB_2U_LIB.S9S_MB_2U(SCH_1):PAGE165_I78@PURE_QUANTA.Q_CAP_DIFFBUS(CHIPS)':
 C_PATH='@s9s_mb_2u_lib.s9s_mb_2u(sch_1):page165_i78@pure_quanta.q_cap_diffbus(c~
hips)',
 P_PATH='@s9s_mb_2u_lib.s9s_mb_2u(sch_1):page174_i78@pure_quanta.q_cap_diffbus(c~
hips)',
 PATH='I78',
 DRAWING='@S9S_MB_2U_LIB.S9S_MB_2U(SCH_1):PAGE165',
 PIN_NAMES_ROTATE='TRUE',
 PHYS_PAGE='174',
 XY='(-650,3300)',
 ROT='2',
 VER='2',
 PACK_TYPE='C0201',
 CDS_LIB='pure_quanta',
 CDS_PART_NAME='Q_CAP_DIFFBUS_C0201-DIFF BUS_0A',
 TOLERANCE='20%',
 MATERIAL='X6S',
 VOLTAGE='6.3V',
 VALUE='DIFF BUS_0.22UF',
 PRIM_FILE='./archive_libs/logical/q_cap_diffbus/chips/chips.prt';

PART_NAME
 C842 'Q_CAP_DIFFBUS_C0201-DIFF BUS_0A':;

SECTION_NUMBER 1
 '@S9S_MB_2U_LIB.S9S_MB_2U(SCH_1):PAGE165_I76@PURE_QUANTA.Q_CAP_DIFFBUS(CHIPS)':
 C_PATH='@s9s_mb_2u_lib.s9s_mb_2u(sch_1):page165_i76@pure_quanta.q_cap_diffbus(c~
hips)',
 P_PATH='@s9s_mb_2u_lib.s9s_mb_2u(sch_1):page174_i76@pure_quanta.q_cap_diffbus(c~
hips)',
 PATH='I76',
 DRAWING='@S9S_MB_2U_LIB.S9S_MB_2U(SCH_1):PAGE165',
 PIN_NAMES_ROTATE='TRUE',
 PHYS_PAGE='174',
 XY='(-650,3150)',
 ROT='2',
 VER='2',
 PACK_TYPE='C0201',
 CDS_LIB='pure_quanta',
 CDS_PART_NAME='Q_CAP_DIFFBUS_C0201-DIFF BUS_0A',
 TOLERANCE='20%',
 MATERIAL='X6S',
 VOLTAGE='6.3V',
 VALUE='DIFF BUS_0.22UF',
 PRIM_FILE='./archive_libs/logical/q_cap_diffbus/chips/chips.prt';

PART_NAME
 C843 'Q_CAP_DIFFBUS_C0201-DIFF BUS_0A':;

SECTION_NUMBER 1
 '@S9S_MB_2U_LIB.S9S_MB_2U(SCH_1):PAGE165_I77@PURE_QUANTA.Q_CAP_DIFFBUS(CHIPS)':
 C_PATH='@s9s_mb_2u_lib.s9s_mb_2u(sch_1):page165_i77@pure_quanta.q_cap_diffbus(c~
hips)',
 P_PATH='@s9s_mb_2u_lib.s9s_mb_2u(sch_1):page174_i77@pure_quanta.q_cap_diffbus(c~
hips)',
 PATH='I77',
 DRAWING='@S9S_MB_2U_LIB.S9S_MB_2U(SCH_1):PAGE165',
 PIN_NAMES_ROTATE='TRUE',
 PHYS_PAGE='174',
 XY='(-650,3100)',
 ROT='2',
 VER='2',
 PACK_TYPE='C0201',
 CDS_LIB='pure_quanta',
 CDS_PART_NAME='Q_CAP_DIFFBUS_C0201-DIFF BUS_0A',
 TOLERANCE='20%',
 MATERIAL='X6S',
 VOLTAGE='6.3V',
 VALUE='DIFF BUS_0.22UF',
 PRIM_FILE='./archive_libs/logical/q_cap_diffbus/chips/chips.prt';

PART_NAME
 C844 'Q_CAP_DIFFBUS_C0201-DIFF BUS_0A':;

SECTION_NUMBER 1
 '@S9S_MB_2U_LIB.S9S_MB_2U(SCH_1):PAGE165_I70@PURE_QUANTA.Q_CAP_DIFFBUS(CHIPS)':
 C_PATH='@s9s_mb_2u_lib.s9s_mb_2u(sch_1):page165_i70@pure_quanta.q_cap_diffbus(c~
hips)',
 P_PATH='@s9s_mb_2u_lib.s9s_mb_2u(sch_1):page174_i70@pure_quanta.q_cap_diffbus(c~
hips)',
 PATH='I70',
 DRAWING='@S9S_MB_2U_LIB.S9S_MB_2U(SCH_1):PAGE165',
 PIN_NAMES_ROTATE='TRUE',
 PHYS_PAGE='174',
 XY='(-650,2950)',
 ROT='2',
 VER='2',
 PACK_TYPE='C0201',
 CDS_LIB='pure_quanta',
 CDS_PART_NAME='Q_CAP_DIFFBUS_C0201-DIFF BUS_0A',
 TOLERANCE='20%',
 MATERIAL='X6S',
 VOLTAGE='6.3V',
 VALUE='DIFF BUS_0.22UF',
 PRIM_FILE='./archive_libs/logical/q_cap_diffbus/chips/chips.prt';

PART_NAME
 C845 'Q_CAP_DIFFBUS_C0201-DIFF BUS_0A':;

SECTION_NUMBER 1
 '@S9S_MB_2U_LIB.S9S_MB_2U(SCH_1):PAGE165_I69@PURE_QUANTA.Q_CAP_DIFFBUS(CHIPS)':
 C_PATH='@s9s_mb_2u_lib.s9s_mb_2u(sch_1):page165_i69@pure_quanta.q_cap_diffbus(c~
hips)',
 P_PATH='@s9s_mb_2u_lib.s9s_mb_2u(sch_1):page174_i69@pure_quanta.q_cap_diffbus(c~
hips)',
 PATH='I69',
 DRAWING='@S9S_MB_2U_LIB.S9S_MB_2U(SCH_1):PAGE165',
 PIN_NAMES_ROTATE='TRUE',
 PHYS_PAGE='174',
 XY='(-650,2900)',
 ROT='2',
 VER='2',
 PACK_TYPE='C0201',
 CDS_LIB='pure_quanta',
 CDS_PART_NAME='Q_CAP_DIFFBUS_C0201-DIFF BUS_0A',
 TOLERANCE='20%',
 MATERIAL='X6S',
 VOLTAGE='6.3V',
 VALUE='DIFF BUS_0.22UF',
 PRIM_FILE='./archive_libs/logical/q_cap_diffbus/chips/chips.prt';

PART_NAME
 C846 'Q_CAP_DIFFBUS_C0201-DIFF BUS_0A':;

SECTION_NUMBER 1
 '@S9S_MB_2U_LIB.S9S_MB_2U(SCH_1):PAGE165_I68@PURE_QUANTA.Q_CAP_DIFFBUS(CHIPS)':
 C_PATH='@s9s_mb_2u_lib.s9s_mb_2u(sch_1):page165_i68@pure_quanta.q_cap_diffbus(c~
hips)',
 P_PATH='@s9s_mb_2u_lib.s9s_mb_2u(sch_1):page174_i68@pure_quanta.q_cap_diffbus(c~
hips)',
 PATH='I68',
 DRAWING='@S9S_MB_2U_LIB.S9S_MB_2U(SCH_1):PAGE165',
 PIN_NAMES_ROTATE='TRUE',
 PHYS_PAGE='174',
 XY='(-650,2750)',
 ROT='2',
 VER='2',
 PACK_TYPE='C0201',
 CDS_LIB='pure_quanta',
 CDS_PART_NAME='Q_CAP_DIFFBUS_C0201-DIFF BUS_0A',
 TOLERANCE='20%',
 MATERIAL='X6S',
 VOLTAGE='6.3V',
 VALUE='DIFF BUS_0.22UF',
 PRIM_FILE='./archive_libs/logical/q_cap_diffbus/chips/chips.prt';

PART_NAME
 C847 'Q_CAP_DIFFBUS_C0201-DIFF BUS_0A':;

SECTION_NUMBER 1
 '@S9S_MB_2U_LIB.S9S_MB_2U(SCH_1):PAGE165_I67@PURE_QUANTA.Q_CAP_DIFFBUS(CHIPS)':
 C_PATH='@s9s_mb_2u_lib.s9s_mb_2u(sch_1):page165_i67@pure_quanta.q_cap_diffbus(c~
hips)',
 P_PATH='@s9s_mb_2u_lib.s9s_mb_2u(sch_1):page174_i67@pure_quanta.q_cap_diffbus(c~
hips)',
 PATH='I67',
 DRAWING='@S9S_MB_2U_LIB.S9S_MB_2U(SCH_1):PAGE165',
 PIN_NAMES_ROTATE='TRUE',
 PHYS_PAGE='174',
 XY='(-650,2700)',
 ROT='2',
 VER='2',
 PACK_TYPE='C0201',
 CDS_LIB='pure_quanta',
 CDS_PART_NAME='Q_CAP_DIFFBUS_C0201-DIFF BUS_0A',
 TOLERANCE='20%',
 MATERIAL='X6S',
 VOLTAGE='6.3V',
 VALUE='DIFF BUS_0.22UF',
 PRIM_FILE='./archive_libs/logical/q_cap_diffbus/chips/chips.prt';

PART_NAME
 C848 'Q_CAP_DIFFBUS_C0201-DIFF BUS_0A':;

SECTION_NUMBER 1
 '@S9S_MB_2U_LIB.S9S_MB_2U(SCH_1):PAGE165_I66@PURE_QUANTA.Q_CAP_DIFFBUS(CHIPS)':
 C_PATH='@s9s_mb_2u_lib.s9s_mb_2u(sch_1):page165_i66@pure_quanta.q_cap_diffbus(c~
hips)',
 P_PATH='@s9s_mb_2u_lib.s9s_mb_2u(sch_1):page174_i66@pure_quanta.q_cap_diffbus(c~
hips)',
 PATH='I66',
 DRAWING='@S9S_MB_2U_LIB.S9S_MB_2U(SCH_1):PAGE165',
 PIN_NAMES_ROTATE='TRUE',
 PHYS_PAGE='174',
 XY='(-650,2550)',
 ROT='2',
 VER='2',
 PACK_TYPE='C0201',
 CDS_LIB='pure_quanta',
 CDS_PART_NAME='Q_CAP_DIFFBUS_C0201-DIFF BUS_0A',
 TOLERANCE='20%',
 MATERIAL='X6S',
 VOLTAGE='6.3V',
 VALUE='DIFF BUS_0.22UF',
 PRIM_FILE='./archive_libs/logical/q_cap_diffbus/chips/chips.prt';

PART_NAME
 C849 'Q_CAP_DIFFBUS_C0201-DIFF BUS_0A':;

SECTION_NUMBER 1
 '@S9S_MB_2U_LIB.S9S_MB_2U(SCH_1):PAGE165_I65@PURE_QUANTA.Q_CAP_DIFFBUS(CHIPS)':
 C_PATH='@s9s_mb_2u_lib.s9s_mb_2u(sch_1):page165_i65@pure_quanta.q_cap_diffbus(c~
hips)',
 P_PATH='@s9s_mb_2u_lib.s9s_mb_2u(sch_1):page174_i65@pure_quanta.q_cap_diffbus(c~
hips)',
 PATH='I65',
 DRAWING='@S9S_MB_2U_LIB.S9S_MB_2U(SCH_1):PAGE165',
 PIN_NAMES_ROTATE='TRUE',
 PHYS_PAGE='174',
 XY='(-650,2500)',
 ROT='2',
 VER='2',
 PACK_TYPE='C0201',
 CDS_LIB='pure_quanta',
 CDS_PART_NAME='Q_CAP_DIFFBUS_C0201-DIFF BUS_0A',
 TOLERANCE='20%',
 MATERIAL='X6S',
 VOLTAGE='6.3V',
 VALUE='DIFF BUS_0.22UF',
 PRIM_FILE='./archive_libs/logical/q_cap_diffbus/chips/chips.prt';

PART_NAME
 C850 'Q_CAP_DIFFBUS_C0201-DIFF BUS_0A':;

SECTION_NUMBER 1
 '@S9S_MB_2U_LIB.S9S_MB_2U(SCH_1):PAGE165_I64@PURE_QUANTA.Q_CAP_DIFFBUS(CHIPS)':
 C_PATH='@s9s_mb_2u_lib.s9s_mb_2u(sch_1):page165_i64@pure_quanta.q_cap_diffbus(c~
hips)',
 P_PATH='@s9s_mb_2u_lib.s9s_mb_2u(sch_1):page174_i64@pure_quanta.q_cap_diffbus(c~
hips)',
 PATH='I64',
 DRAWING='@S9S_MB_2U_LIB.S9S_MB_2U(SCH_1):PAGE165',
 PIN_NAMES_ROTATE='TRUE',
 PHYS_PAGE='174',
 XY='(-650,2350)',
 ROT='2',
 VER='2',
 PACK_TYPE='C0201',
 CDS_LIB='pure_quanta',
 CDS_PART_NAME='Q_CAP_DIFFBUS_C0201-DIFF BUS_0A',
 TOLERANCE='20%',
 MATERIAL='X6S',
 VOLTAGE='6.3V',
 VALUE='DIFF BUS_0.22UF',
 PRIM_FILE='./archive_libs/logical/q_cap_diffbus/chips/chips.prt';

PART_NAME
 C851 'Q_CAP_DIFFBUS_C0201-DIFF BUS_0A':;

SECTION_NUMBER 1
 '@S9S_MB_2U_LIB.S9S_MB_2U(SCH_1):PAGE165_I63@PURE_QUANTA.Q_CAP_DIFFBUS(CHIPS)':
 C_PATH='@s9s_mb_2u_lib.s9s_mb_2u(sch_1):page165_i63@pure_quanta.q_cap_diffbus(c~
hips)',
 P_PATH='@s9s_mb_2u_lib.s9s_mb_2u(sch_1):page174_i63@pure_quanta.q_cap_diffbus(c~
hips)',
 PATH='I63',
 DRAWING='@S9S_MB_2U_LIB.S9S_MB_2U(SCH_1):PAGE165',
 PIN_NAMES_ROTATE='TRUE',
 PHYS_PAGE='174',
 XY='(-650,2300)',
 ROT='2',
 VER='2',
 PACK_TYPE='C0201',
 CDS_LIB='pure_quanta',
 CDS_PART_NAME='Q_CAP_DIFFBUS_C0201-DIFF BUS_0A',
 TOLERANCE='20%',
 MATERIAL='X6S',
 VOLTAGE='6.3V',
 VALUE='DIFF BUS_0.22UF',
 PRIM_FILE='./archive_libs/logical/q_cap_diffbus/chips/chips.prt';

PART_NAME
 C852 'Q_CAP_DIFFBUS_C0201-DIFF BUS_0A':;

SECTION_NUMBER 1
 '@S9S_MB_2U_LIB.S9S_MB_2U(SCH_1):PAGE165_I61@PURE_QUANTA.Q_CAP_DIFFBUS(CHIPS)':
 C_PATH='@s9s_mb_2u_lib.s9s_mb_2u(sch_1):page165_i61@pure_quanta.q_cap_diffbus(c~
hips)',
 P_PATH='@s9s_mb_2u_lib.s9s_mb_2u(sch_1):page174_i61@pure_quanta.q_cap_diffbus(c~
hips)',
 PATH='I61',
 DRAWING='@S9S_MB_2U_LIB.S9S_MB_2U(SCH_1):PAGE165',
 PIN_NAMES_ROTATE='TRUE',
 PHYS_PAGE='174',
 XY='(-650,2150)',
 ROT='2',
 VER='2',
 PACK_TYPE='C0201',
 CDS_LIB='pure_quanta',
 CDS_PART_NAME='Q_CAP_DIFFBUS_C0201-DIFF BUS_0A',
 TOLERANCE='20%',
 MATERIAL='X6S',
 VOLTAGE='6.3V',
 VALUE='DIFF BUS_0.22UF',
 PRIM_FILE='./archive_libs/logical/q_cap_diffbus/chips/chips.prt';

PART_NAME
 C853 'Q_CAP_DIFFBUS_C0201-DIFF BUS_0A':;

SECTION_NUMBER 1
 '@S9S_MB_2U_LIB.S9S_MB_2U(SCH_1):PAGE165_I62@PURE_QUANTA.Q_CAP_DIFFBUS(CHIPS)':
 C_PATH='@s9s_mb_2u_lib.s9s_mb_2u(sch_1):page165_i62@pure_quanta.q_cap_diffbus(c~
hips)',
 P_PATH='@s9s_mb_2u_lib.s9s_mb_2u(sch_1):page174_i62@pure_quanta.q_cap_diffbus(c~
hips)',
 PATH='I62',
 DRAWING='@S9S_MB_2U_LIB.S9S_MB_2U(SCH_1):PAGE165',
 PIN_NAMES_ROTATE='TRUE',
 PHYS_PAGE='174',
 XY='(-650,2100)',
 ROT='2',
 VER='2',
 PACK_TYPE='C0201',
 CDS_LIB='pure_quanta',
 CDS_PART_NAME='Q_CAP_DIFFBUS_C0201-DIFF BUS_0A',
 TOLERANCE='20%',
 MATERIAL='X6S',
 VOLTAGE='6.3V',
 VALUE='DIFF BUS_0.22UF',
 PRIM_FILE='./archive_libs/logical/q_cap_diffbus/chips/chips.prt';

PART_NAME
 C854 'Q_CAP_DIFFBUS_C0201-DIFF BUS_0A':;

SECTION_NUMBER 1
 '@S9S_MB_2U_LIB.S9S_MB_2U(SCH_1):PAGE165_I41@PURE_QUANTA.Q_CAP_DIFFBUS(CHIPS)':
 C_PATH='@s9s_mb_2u_lib.s9s_mb_2u(sch_1):page165_i41@pure_quanta.q_cap_diffbus(c~
hips)',
 P_PATH='@s9s_mb_2u_lib.s9s_mb_2u(sch_1):page174_i41@pure_quanta.q_cap_diffbus(c~
hips)',
 PATH='I41',
 DRAWING='@S9S_MB_2U_LIB.S9S_MB_2U(SCH_1):PAGE165',
 PIN_NAMES_ROTATE='TRUE',
 PHYS_PAGE='174',
 XY='(-650,1575)',
 ROT='2',
 VER='2',
 PACK_TYPE='C0201',
 CDS_LIB='pure_quanta',
 CDS_PART_NAME='Q_CAP_DIFFBUS_C0201-DIFF BUS_0A',
 TOLERANCE='20%',
 MATERIAL='X6S',
 VOLTAGE='6.3V',
 VALUE='DIFF BUS_0.22UF',
 PRIM_FILE='./archive_libs/logical/q_cap_diffbus/chips/chips.prt';

PART_NAME
 C855 'Q_CAP_DIFFBUS_C0201-DIFF BUS_0A':;

SECTION_NUMBER 1
 '@S9S_MB_2U_LIB.S9S_MB_2U(SCH_1):PAGE165_I40@PURE_QUANTA.Q_CAP_DIFFBUS(CHIPS)':
 C_PATH='@s9s_mb_2u_lib.s9s_mb_2u(sch_1):page165_i40@pure_quanta.q_cap_diffbus(c~
hips)',
 P_PATH='@s9s_mb_2u_lib.s9s_mb_2u(sch_1):page174_i40@pure_quanta.q_cap_diffbus(c~
hips)',
 PATH='I40',
 DRAWING='@S9S_MB_2U_LIB.S9S_MB_2U(SCH_1):PAGE165',
 PIN_NAMES_ROTATE='TRUE',
 PHYS_PAGE='174',
 XY='(-650,1525)',
 ROT='2',
 VER='2',
 PACK_TYPE='C0201',
 CDS_LIB='pure_quanta',
 CDS_PART_NAME='Q_CAP_DIFFBUS_C0201-DIFF BUS_0A',
 TOLERANCE='20%',
 MATERIAL='X6S',
 VOLTAGE='6.3V',
 VALUE='DIFF BUS_0.22UF',
 PRIM_FILE='./archive_libs/logical/q_cap_diffbus/chips/chips.prt';

PART_NAME
 C856 'Q_CAP_DIFFBUS_C0201-DIFF BUS_0A':;

SECTION_NUMBER 1
 '@S9S_MB_2U_LIB.S9S_MB_2U(SCH_1):PAGE165_I39@PURE_QUANTA.Q_CAP_DIFFBUS(CHIPS)':
 C_PATH='@s9s_mb_2u_lib.s9s_mb_2u(sch_1):page165_i39@pure_quanta.q_cap_diffbus(c~
hips)',
 P_PATH='@s9s_mb_2u_lib.s9s_mb_2u(sch_1):page174_i39@pure_quanta.q_cap_diffbus(c~
hips)',
 PATH='I39',
 DRAWING='@S9S_MB_2U_LIB.S9S_MB_2U(SCH_1):PAGE165',
 PIN_NAMES_ROTATE='TRUE',
 PHYS_PAGE='174',
 XY='(-650,1375)',
 ROT='2',
 VER='2',
 PACK_TYPE='C0201',
 CDS_LIB='pure_quanta',
 CDS_PART_NAME='Q_CAP_DIFFBUS_C0201-DIFF BUS_0A',
 TOLERANCE='20%',
 MATERIAL='X6S',
 VOLTAGE='6.3V',
 VALUE='DIFF BUS_0.22UF',
 PRIM_FILE='./archive_libs/logical/q_cap_diffbus/chips/chips.prt';

PART_NAME
 C857 'Q_CAP_DIFFBUS_C0201-DIFF BUS_0A':;

SECTION_NUMBER 1
 '@S9S_MB_2U_LIB.S9S_MB_2U(SCH_1):PAGE165_I38@PURE_QUANTA.Q_CAP_DIFFBUS(CHIPS)':
 C_PATH='@s9s_mb_2u_lib.s9s_mb_2u(sch_1):page165_i38@pure_quanta.q_cap_diffbus(c~
hips)',
 P_PATH='@s9s_mb_2u_lib.s9s_mb_2u(sch_1):page174_i38@pure_quanta.q_cap_diffbus(c~
hips)',
 PATH='I38',
 DRAWING='@S9S_MB_2U_LIB.S9S_MB_2U(SCH_1):PAGE165',
 PIN_NAMES_ROTATE='TRUE',
 PHYS_PAGE='174',
 XY='(-650,1325)',
 ROT='2',
 VER='2',
 PACK_TYPE='C0201',
 CDS_LIB='pure_quanta',
 CDS_PART_NAME='Q_CAP_DIFFBUS_C0201-DIFF BUS_0A',
 TOLERANCE='20%',
 MATERIAL='X6S',
 VOLTAGE='6.3V',
 VALUE='DIFF BUS_0.22UF',
 PRIM_FILE='./archive_libs/logical/q_cap_diffbus/chips/chips.prt';

PART_NAME
 C858 'Q_CAP_DIFFBUS_C0201-DIFF BUS_0A':;

SECTION_NUMBER 1
 '@S9S_MB_2U_LIB.S9S_MB_2U(SCH_1):PAGE165_I37@PURE_QUANTA.Q_CAP_DIFFBUS(CHIPS)':
 C_PATH='@s9s_mb_2u_lib.s9s_mb_2u(sch_1):page165_i37@pure_quanta.q_cap_diffbus(c~
hips)',
 P_PATH='@s9s_mb_2u_lib.s9s_mb_2u(sch_1):page174_i37@pure_quanta.q_cap_diffbus(c~
hips)',
 PATH='I37',
 DRAWING='@S9S_MB_2U_LIB.S9S_MB_2U(SCH_1):PAGE165',
 PIN_NAMES_ROTATE='TRUE',
 PHYS_PAGE='174',
 XY='(-650,1175)',
 ROT='2',
 VER='2',
 PACK_TYPE='C0201',
 CDS_LIB='pure_quanta',
 CDS_PART_NAME='Q_CAP_DIFFBUS_C0201-DIFF BUS_0A',
 TOLERANCE='20%',
 MATERIAL='X6S',
 VOLTAGE='6.3V',
 VALUE='DIFF BUS_0.22UF',
 PRIM_FILE='./archive_libs/logical/q_cap_diffbus/chips/chips.prt';

PART_NAME
 C859 'Q_CAP_DIFFBUS_C0201-DIFF BUS_0A':;

SECTION_NUMBER 1
 '@S9S_MB_2U_LIB.S9S_MB_2U(SCH_1):PAGE165_I36@PURE_QUANTA.Q_CAP_DIFFBUS(CHIPS)':
 C_PATH='@s9s_mb_2u_lib.s9s_mb_2u(sch_1):page165_i36@pure_quanta.q_cap_diffbus(c~
hips)',
 P_PATH='@s9s_mb_2u_lib.s9s_mb_2u(sch_1):page174_i36@pure_quanta.q_cap_diffbus(c~
hips)',
 PATH='I36',
 DRAWING='@S9S_MB_2U_LIB.S9S_MB_2U(SCH_1):PAGE165',
 PIN_NAMES_ROTATE='TRUE',
 PHYS_PAGE='174',
 XY='(-650,1125)',
 ROT='2',
 VER='2',
 PACK_TYPE='C0201',
 CDS_LIB='pure_quanta',
 CDS_PART_NAME='Q_CAP_DIFFBUS_C0201-DIFF BUS_0A',
 TOLERANCE='20%',
 MATERIAL='X6S',
 VOLTAGE='6.3V',
 VALUE='DIFF BUS_0.22UF',
 PRIM_FILE='./archive_libs/logical/q_cap_diffbus/chips/chips.prt';

PART_NAME
 C860 'Q_CAP_DIFFBUS_C0201-DIFF BUS_0A':;

SECTION_NUMBER 1
 '@S9S_MB_2U_LIB.S9S_MB_2U(SCH_1):PAGE165_I30@PURE_QUANTA.Q_CAP_DIFFBUS(CHIPS)':
 C_PATH='@s9s_mb_2u_lib.s9s_mb_2u(sch_1):page165_i30@pure_quanta.q_cap_diffbus(c~
hips)',
 P_PATH='@s9s_mb_2u_lib.s9s_mb_2u(sch_1):page174_i30@pure_quanta.q_cap_diffbus(c~
hips)',
 PATH='I30',
 DRAWING='@S9S_MB_2U_LIB.S9S_MB_2U(SCH_1):PAGE165',
 PIN_NAMES_ROTATE='TRUE',
 PHYS_PAGE='174',
 XY='(-650,975)',
 ROT='2',
 VER='2',
 PACK_TYPE='C0201',
 CDS_LIB='pure_quanta',
 CDS_PART_NAME='Q_CAP_DIFFBUS_C0201-DIFF BUS_0A',
 TOLERANCE='20%',
 MATERIAL='X6S',
 VOLTAGE='6.3V',
 VALUE='DIFF BUS_0.22UF',
 PRIM_FILE='./archive_libs/logical/q_cap_diffbus/chips/chips.prt';

PART_NAME
 C861 'Q_CAP_DIFFBUS_C0201-DIFF BUS_0A':;

SECTION_NUMBER 1
 '@S9S_MB_2U_LIB.S9S_MB_2U(SCH_1):PAGE165_I29@PURE_QUANTA.Q_CAP_DIFFBUS(CHIPS)':
 C_PATH='@s9s_mb_2u_lib.s9s_mb_2u(sch_1):page165_i29@pure_quanta.q_cap_diffbus(c~
hips)',
 P_PATH='@s9s_mb_2u_lib.s9s_mb_2u(sch_1):page174_i29@pure_quanta.q_cap_diffbus(c~
hips)',
 PATH='I29',
 DRAWING='@S9S_MB_2U_LIB.S9S_MB_2U(SCH_1):PAGE165',
 PIN_NAMES_ROTATE='TRUE',
 PHYS_PAGE='174',
 XY='(-650,925)',
 ROT='2',
 VER='2',
 PACK_TYPE='C0201',
 CDS_LIB='pure_quanta',
 CDS_PART_NAME='Q_CAP_DIFFBUS_C0201-DIFF BUS_0A',
 TOLERANCE='20%',
 MATERIAL='X6S',
 VOLTAGE='6.3V',
 VALUE='DIFF BUS_0.22UF',
 PRIM_FILE='./archive_libs/logical/q_cap_diffbus/chips/chips.prt';

PART_NAME
 C862 'Q_CAP_DIFFBUS_C0201-DIFF BUS_0A':;

SECTION_NUMBER 1
 '@S9S_MB_2U_LIB.S9S_MB_2U(SCH_1):PAGE165_I28@PURE_QUANTA.Q_CAP_DIFFBUS(CHIPS)':
 C_PATH='@s9s_mb_2u_lib.s9s_mb_2u(sch_1):page165_i28@pure_quanta.q_cap_diffbus(c~
hips)',
 P_PATH='@s9s_mb_2u_lib.s9s_mb_2u(sch_1):page174_i28@pure_quanta.q_cap_diffbus(c~
hips)',
 PATH='I28',
 DRAWING='@S9S_MB_2U_LIB.S9S_MB_2U(SCH_1):PAGE165',
 PIN_NAMES_ROTATE='TRUE',
 PHYS_PAGE='174',
 XY='(-650,775)',
 ROT='2',
 VER='2',
 PACK_TYPE='C0201',
 CDS_LIB='pure_quanta',
 CDS_PART_NAME='Q_CAP_DIFFBUS_C0201-DIFF BUS_0A',
 TOLERANCE='20%',
 MATERIAL='X6S',
 VOLTAGE='6.3V',
 VALUE='DIFF BUS_0.22UF',
 PRIM_FILE='./archive_libs/logical/q_cap_diffbus/chips/chips.prt';

PART_NAME
 C863 'Q_CAP_DIFFBUS_C0201-DIFF BUS_0A':;

SECTION_NUMBER 1
 '@S9S_MB_2U_LIB.S9S_MB_2U(SCH_1):PAGE165_I27@PURE_QUANTA.Q_CAP_DIFFBUS(CHIPS)':
 C_PATH='@s9s_mb_2u_lib.s9s_mb_2u(sch_1):page165_i27@pure_quanta.q_cap_diffbus(c~
hips)',
 P_PATH='@s9s_mb_2u_lib.s9s_mb_2u(sch_1):page174_i27@pure_quanta.q_cap_diffbus(c~
hips)',
 PATH='I27',
 DRAWING='@S9S_MB_2U_LIB.S9S_MB_2U(SCH_1):PAGE165',
 PIN_NAMES_ROTATE='TRUE',
 PHYS_PAGE='174',
 XY='(-650,725)',
 ROT='2',
 VER='2',
 PACK_TYPE='C0201',
 CDS_LIB='pure_quanta',
 CDS_PART_NAME='Q_CAP_DIFFBUS_C0201-DIFF BUS_0A',
 TOLERANCE='20%',
 MATERIAL='X6S',
 VOLTAGE='6.3V',
 VALUE='DIFF BUS_0.22UF',
 PRIM_FILE='./archive_libs/logical/q_cap_diffbus/chips/chips.prt';

PART_NAME
 C864 'Q_CAP_DIFFBUS_C0201-DIFF BUS_0A':;

SECTION_NUMBER 1
 '@S9S_MB_2U_LIB.S9S_MB_2U(SCH_1):PAGE165_I25@PURE_QUANTA.Q_CAP_DIFFBUS(CHIPS)':
 C_PATH='@s9s_mb_2u_lib.s9s_mb_2u(sch_1):page165_i25@pure_quanta.q_cap_diffbus(c~
hips)',
 P_PATH='@s9s_mb_2u_lib.s9s_mb_2u(sch_1):page174_i25@pure_quanta.q_cap_diffbus(c~
hips)',
 PATH='I25',
 DRAWING='@S9S_MB_2U_LIB.S9S_MB_2U(SCH_1):PAGE165',
 PIN_NAMES_ROTATE='TRUE',
 PHYS_PAGE='174',
 XY='(-650,575)',
 ROT='2',
 VER='2',
 PACK_TYPE='C0201',
 CDS_LIB='pure_quanta',
 CDS_PART_NAME='Q_CAP_DIFFBUS_C0201-DIFF BUS_0A',
 TOLERANCE='20%',
 MATERIAL='X6S',
 VOLTAGE='6.3V',
 VALUE='DIFF BUS_0.22UF',
 PRIM_FILE='./archive_libs/logical/q_cap_diffbus/chips/chips.prt';

PART_NAME
 C865 'Q_CAP_DIFFBUS_C0201-DIFF BUS_0A':;

SECTION_NUMBER 1
 '@S9S_MB_2U_LIB.S9S_MB_2U(SCH_1):PAGE165_I26@PURE_QUANTA.Q_CAP_DIFFBUS(CHIPS)':
 C_PATH='@s9s_mb_2u_lib.s9s_mb_2u(sch_1):page165_i26@pure_quanta.q_cap_diffbus(c~
hips)',
 P_PATH='@s9s_mb_2u_lib.s9s_mb_2u(sch_1):page174_i26@pure_quanta.q_cap_diffbus(c~
hips)',
 PATH='I26',
 DRAWING='@S9S_MB_2U_LIB.S9S_MB_2U(SCH_1):PAGE165',
 PIN_NAMES_ROTATE='TRUE',
 PHYS_PAGE='174',
 XY='(-650,525)',
 ROT='2',
 VER='2',
 PACK_TYPE='C0201',
 CDS_LIB='pure_quanta',
 CDS_PART_NAME='Q_CAP_DIFFBUS_C0201-DIFF BUS_0A',
 TOLERANCE='20%',
 MATERIAL='X6S',
 VOLTAGE='6.3V',
 VALUE='DIFF BUS_0.22UF',
 PRIM_FILE='./archive_libs/logical/q_cap_diffbus/chips/chips.prt';

PART_NAME
 C866 'Q_CAP_DIFFBUS_C0201-DIFF BUS_0A':;

SECTION_NUMBER 1
 '@S9S_MB_2U_LIB.S9S_MB_2U(SCH_1):PAGE165_I24@PURE_QUANTA.Q_CAP_DIFFBUS(CHIPS)':
 C_PATH='@s9s_mb_2u_lib.s9s_mb_2u(sch_1):page165_i24@pure_quanta.q_cap_diffbus(c~
hips)',
 P_PATH='@s9s_mb_2u_lib.s9s_mb_2u(sch_1):page174_i24@pure_quanta.q_cap_diffbus(c~
hips)',
 PATH='I24',
 DRAWING='@S9S_MB_2U_LIB.S9S_MB_2U(SCH_1):PAGE165',
 PIN_NAMES_ROTATE='TRUE',
 PHYS_PAGE='174',
 XY='(-650,375)',
 ROT='2',
 VER='2',
 PACK_TYPE='C0201',
 CDS_LIB='pure_quanta',
 CDS_PART_NAME='Q_CAP_DIFFBUS_C0201-DIFF BUS_0A',
 TOLERANCE='20%',
 MATERIAL='X6S',
 VOLTAGE='6.3V',
 VALUE='DIFF BUS_0.22UF',
 PRIM_FILE='./archive_libs/logical/q_cap_diffbus/chips/chips.prt';

PART_NAME
 C867 'Q_CAP_DIFFBUS_C0201-DIFF BUS_0A':;

SECTION_NUMBER 1
 '@S9S_MB_2U_LIB.S9S_MB_2U(SCH_1):PAGE165_I23@PURE_QUANTA.Q_CAP_DIFFBUS(CHIPS)':
 C_PATH='@s9s_mb_2u_lib.s9s_mb_2u(sch_1):page165_i23@pure_quanta.q_cap_diffbus(c~
hips)',
 P_PATH='@s9s_mb_2u_lib.s9s_mb_2u(sch_1):page174_i23@pure_quanta.q_cap_diffbus(c~
hips)',
 PATH='I23',
 DRAWING='@S9S_MB_2U_LIB.S9S_MB_2U(SCH_1):PAGE165',
 PIN_NAMES_ROTATE='TRUE',
 PHYS_PAGE='174',
 XY='(-650,325)',
 ROT='2',
 VER='2',
 PACK_TYPE='C0201',
 CDS_LIB='pure_quanta',
 CDS_PART_NAME='Q_CAP_DIFFBUS_C0201-DIFF BUS_0A',
 TOLERANCE='20%',
 MATERIAL='X6S',
 VOLTAGE='6.3V',
 VALUE='DIFF BUS_0.22UF',
 PRIM_FILE='./archive_libs/logical/q_cap_diffbus/chips/chips.prt';

PART_NAME
 C868 'Q_CAP_DIFFBUS_C0201-DIFF BUS_0A':;

SECTION_NUMBER 1
 '@S9S_MB_2U_LIB.S9S_MB_2U(SCH_1):PAGE165_I22@PURE_QUANTA.Q_CAP_DIFFBUS(CHIPS)':
 C_PATH='@s9s_mb_2u_lib.s9s_mb_2u(sch_1):page165_i22@pure_quanta.q_cap_diffbus(c~
hips)',
 P_PATH='@s9s_mb_2u_lib.s9s_mb_2u(sch_1):page174_i22@pure_quanta.q_cap_diffbus(c~
hips)',
 PATH='I22',
 DRAWING='@S9S_MB_2U_LIB.S9S_MB_2U(SCH_1):PAGE165',
 PIN_NAMES_ROTATE='TRUE',
 PHYS_PAGE='174',
 XY='(-650,175)',
 ROT='2',
 VER='2',
 PACK_TYPE='C0201',
 CDS_LIB='pure_quanta',
 CDS_PART_NAME='Q_CAP_DIFFBUS_C0201-DIFF BUS_0A',
 TOLERANCE='20%',
 MATERIAL='X6S',
 VOLTAGE='6.3V',
 VALUE='DIFF BUS_0.22UF',
 PRIM_FILE='./archive_libs/logical/q_cap_diffbus/chips/chips.prt';

PART_NAME
 C869 'Q_CAP_DIFFBUS_C0201-DIFF BUS_0A':;

SECTION_NUMBER 1
 '@S9S_MB_2U_LIB.S9S_MB_2U(SCH_1):PAGE165_I21@PURE_QUANTA.Q_CAP_DIFFBUS(CHIPS)':
 C_PATH='@s9s_mb_2u_lib.s9s_mb_2u(sch_1):page165_i21@pure_quanta.q_cap_diffbus(c~
hips)',
 P_PATH='@s9s_mb_2u_lib.s9s_mb_2u(sch_1):page174_i21@pure_quanta.q_cap_diffbus(c~
hips)',
 PATH='I21',
 DRAWING='@S9S_MB_2U_LIB.S9S_MB_2U(SCH_1):PAGE165',
 PIN_NAMES_ROTATE='TRUE',
 PHYS_PAGE='174',
 XY='(-650,125)',
 ROT='2',
 VER='2',
 PACK_TYPE='C0201',
 CDS_LIB='pure_quanta',
 CDS_PART_NAME='Q_CAP_DIFFBUS_C0201-DIFF BUS_0A',
 TOLERANCE='20%',
 MATERIAL='X6S',
 VOLTAGE='6.3V',
 VALUE='DIFF BUS_0.22UF',
 PRIM_FILE='./archive_libs/logical/q_cap_diffbus/chips/chips.prt';

PART_NAME
 C870 'Q_CAP_DIFFBUS_C0201-DIFF BUS_0A':;

SECTION_NUMBER 1
 '@S9S_MB_2U_LIB.S9S_MB_2U(SCH_1):PAGE165_I169@PURE_QUANTA.Q_CAP_DIFFBUS(CHIPS)':
 C_PATH='@s9s_mb_2u_lib.s9s_mb_2u(sch_1):page165_i169@pure_quanta.q_cap_diffbus(~
chips)',
 P_PATH='@s9s_mb_2u_lib.s9s_mb_2u(sch_1):page174_i169@pure_quanta.q_cap_diffbus(~
chips)',
 PATH='I169',
 DRAWING='@S9S_MB_2U_LIB.S9S_MB_2U(SCH_1):PAGE165',
 PIN_NAMES_ROTATE='TRUE',
 PHYS_PAGE='174',
 XY='(3825,3550)',
 ROT='2',
 VER='2',
 PACK_TYPE='C0201',
 CDS_LIB='pure_quanta',
 CDS_PART_NAME='Q_CAP_DIFFBUS_C0201-DIFF BUS_0A',
 TOLERANCE='20%',
 MATERIAL='X6S',
 VOLTAGE='6.3V',
 VALUE='DIFF BUS_0.22UF',
 PRIM_FILE='./archive_libs/logical/q_cap_diffbus/chips/chips.prt';

PART_NAME
 C871 'Q_CAP_DIFFBUS_C0201-DIFF BUS_0A':;

SECTION_NUMBER 1
 '@S9S_MB_2U_LIB.S9S_MB_2U(SCH_1):PAGE165_I168@PURE_QUANTA.Q_CAP_DIFFBUS(CHIPS)':
 C_PATH='@s9s_mb_2u_lib.s9s_mb_2u(sch_1):page165_i168@pure_quanta.q_cap_diffbus(~
chips)',
 P_PATH='@s9s_mb_2u_lib.s9s_mb_2u(sch_1):page174_i168@pure_quanta.q_cap_diffbus(~
chips)',
 PATH='I168',
 DRAWING='@S9S_MB_2U_LIB.S9S_MB_2U(SCH_1):PAGE165',
 PIN_NAMES_ROTATE='TRUE',
 PHYS_PAGE='174',
 XY='(3825,3500)',
 ROT='2',
 VER='2',
 PACK_TYPE='C0201',
 CDS_LIB='pure_quanta',
 CDS_PART_NAME='Q_CAP_DIFFBUS_C0201-DIFF BUS_0A',
 TOLERANCE='20%',
 MATERIAL='X6S',
 VOLTAGE='6.3V',
 VALUE='DIFF BUS_0.22UF',
 PRIM_FILE='./archive_libs/logical/q_cap_diffbus/chips/chips.prt';

PART_NAME
 C872 'Q_CAP_DIFFBUS_C0201-DIFF BUS_0A':;

SECTION_NUMBER 1
 '@S9S_MB_2U_LIB.S9S_MB_2U(SCH_1):PAGE165_I167@PURE_QUANTA.Q_CAP_DIFFBUS(CHIPS)':
 C_PATH='@s9s_mb_2u_lib.s9s_mb_2u(sch_1):page165_i167@pure_quanta.q_cap_diffbus(~
chips)',
 P_PATH='@s9s_mb_2u_lib.s9s_mb_2u(sch_1):page174_i167@pure_quanta.q_cap_diffbus(~
chips)',
 PATH='I167',
 DRAWING='@S9S_MB_2U_LIB.S9S_MB_2U(SCH_1):PAGE165',
 PIN_NAMES_ROTATE='TRUE',
 PHYS_PAGE='174',
 XY='(3825,3350)',
 ROT='2',
 VER='2',
 PACK_TYPE='C0201',
 CDS_LIB='pure_quanta',
 CDS_PART_NAME='Q_CAP_DIFFBUS_C0201-DIFF BUS_0A',
 TOLERANCE='20%',
 MATERIAL='X6S',
 VOLTAGE='6.3V',
 VALUE='DIFF BUS_0.22UF',
 PRIM_FILE='./archive_libs/logical/q_cap_diffbus/chips/chips.prt';

PART_NAME
 C873 'Q_CAP_DIFFBUS_C0201-DIFF BUS_0A':;

SECTION_NUMBER 1
 '@S9S_MB_2U_LIB.S9S_MB_2U(SCH_1):PAGE165_I166@PURE_QUANTA.Q_CAP_DIFFBUS(CHIPS)':
 C_PATH='@s9s_mb_2u_lib.s9s_mb_2u(sch_1):page165_i166@pure_quanta.q_cap_diffbus(~
chips)',
 P_PATH='@s9s_mb_2u_lib.s9s_mb_2u(sch_1):page174_i166@pure_quanta.q_cap_diffbus(~
chips)',
 PATH='I166',
 DRAWING='@S9S_MB_2U_LIB.S9S_MB_2U(SCH_1):PAGE165',
 PIN_NAMES_ROTATE='TRUE',
 PHYS_PAGE='174',
 XY='(3825,3300)',
 ROT='2',
 VER='2',
 PACK_TYPE='C0201',
 CDS_LIB='pure_quanta',
 CDS_PART_NAME='Q_CAP_DIFFBUS_C0201-DIFF BUS_0A',
 TOLERANCE='20%',
 MATERIAL='X6S',
 VOLTAGE='6.3V',
 VALUE='DIFF BUS_0.22UF',
 PRIM_FILE='./archive_libs/logical/q_cap_diffbus/chips/chips.prt';

PART_NAME
 C874 'Q_CAP_DIFFBUS_C0201-DIFF BUS_0A':;

SECTION_NUMBER 1
 '@S9S_MB_2U_LIB.S9S_MB_2U(SCH_1):PAGE165_I165@PURE_QUANTA.Q_CAP_DIFFBUS(CHIPS)':
 C_PATH='@s9s_mb_2u_lib.s9s_mb_2u(sch_1):page165_i165@pure_quanta.q_cap_diffbus(~
chips)',
 P_PATH='@s9s_mb_2u_lib.s9s_mb_2u(sch_1):page174_i165@pure_quanta.q_cap_diffbus(~
chips)',
 PATH='I165',
 DRAWING='@S9S_MB_2U_LIB.S9S_MB_2U(SCH_1):PAGE165',
 PIN_NAMES_ROTATE='TRUE',
 PHYS_PAGE='174',
 XY='(3825,3150)',
 ROT='2',
 VER='2',
 PACK_TYPE='C0201',
 CDS_LIB='pure_quanta',
 CDS_PART_NAME='Q_CAP_DIFFBUS_C0201-DIFF BUS_0A',
 TOLERANCE='20%',
 MATERIAL='X6S',
 VOLTAGE='6.3V',
 VALUE='DIFF BUS_0.22UF',
 PRIM_FILE='./archive_libs/logical/q_cap_diffbus/chips/chips.prt';

PART_NAME
 C875 'Q_CAP_DIFFBUS_C0201-DIFF BUS_0A':;

SECTION_NUMBER 1
 '@S9S_MB_2U_LIB.S9S_MB_2U(SCH_1):PAGE165_I164@PURE_QUANTA.Q_CAP_DIFFBUS(CHIPS)':
 C_PATH='@s9s_mb_2u_lib.s9s_mb_2u(sch_1):page165_i164@pure_quanta.q_cap_diffbus(~
chips)',
 P_PATH='@s9s_mb_2u_lib.s9s_mb_2u(sch_1):page174_i164@pure_quanta.q_cap_diffbus(~
chips)',
 PATH='I164',
 DRAWING='@S9S_MB_2U_LIB.S9S_MB_2U(SCH_1):PAGE165',
 PIN_NAMES_ROTATE='TRUE',
 PHYS_PAGE='174',
 XY='(3825,3100)',
 ROT='2',
 VER='2',
 PACK_TYPE='C0201',
 CDS_LIB='pure_quanta',
 CDS_PART_NAME='Q_CAP_DIFFBUS_C0201-DIFF BUS_0A',
 TOLERANCE='20%',
 MATERIAL='X6S',
 VOLTAGE='6.3V',
 VALUE='DIFF BUS_0.22UF',
 PRIM_FILE='./archive_libs/logical/q_cap_diffbus/chips/chips.prt';

PART_NAME
 C876 'Q_CAP_DIFFBUS_C0201-DIFF BUS_0A':;

SECTION_NUMBER 1
 '@S9S_MB_2U_LIB.S9S_MB_2U(SCH_1):PAGE165_I160@PURE_QUANTA.Q_CAP_DIFFBUS(CHIPS)':
 C_PATH='@s9s_mb_2u_lib.s9s_mb_2u(sch_1):page165_i160@pure_quanta.q_cap_diffbus(~
chips)',
 P_PATH='@s9s_mb_2u_lib.s9s_mb_2u(sch_1):page174_i160@pure_quanta.q_cap_diffbus(~
chips)',
 PATH='I160',
 DRAWING='@S9S_MB_2U_LIB.S9S_MB_2U(SCH_1):PAGE165',
 PIN_NAMES_ROTATE='TRUE',
 PHYS_PAGE='174',
 XY='(3825,2950)',
 ROT='2',
 VER='2',
 PACK_TYPE='C0201',
 CDS_LIB='pure_quanta',
 CDS_PART_NAME='Q_CAP_DIFFBUS_C0201-DIFF BUS_0A',
 TOLERANCE='20%',
 MATERIAL='X6S',
 VOLTAGE='6.3V',
 VALUE='DIFF BUS_0.22UF',
 PRIM_FILE='./archive_libs/logical/q_cap_diffbus/chips/chips.prt';

PART_NAME
 C877 'Q_CAP_DIFFBUS_C0201-DIFF BUS_0A':;

SECTION_NUMBER 1
 '@S9S_MB_2U_LIB.S9S_MB_2U(SCH_1):PAGE165_I159@PURE_QUANTA.Q_CAP_DIFFBUS(CHIPS)':
 C_PATH='@s9s_mb_2u_lib.s9s_mb_2u(sch_1):page165_i159@pure_quanta.q_cap_diffbus(~
chips)',
 P_PATH='@s9s_mb_2u_lib.s9s_mb_2u(sch_1):page174_i159@pure_quanta.q_cap_diffbus(~
chips)',
 PATH='I159',
 DRAWING='@S9S_MB_2U_LIB.S9S_MB_2U(SCH_1):PAGE165',
 PIN_NAMES_ROTATE='TRUE',
 PHYS_PAGE='174',
 XY='(3825,2900)',
 ROT='2',
 VER='2',
 PACK_TYPE='C0201',
 CDS_LIB='pure_quanta',
 CDS_PART_NAME='Q_CAP_DIFFBUS_C0201-DIFF BUS_0A',
 TOLERANCE='20%',
 MATERIAL='X6S',
 VOLTAGE='6.3V',
 VALUE='DIFF BUS_0.22UF',
 PRIM_FILE='./archive_libs/logical/q_cap_diffbus/chips/chips.prt';

PART_NAME
 C878 'Q_CAP_DIFFBUS_C0201-DIFF BUS_0A':;

SECTION_NUMBER 1
 '@S9S_MB_2U_LIB.S9S_MB_2U(SCH_1):PAGE165_I157@PURE_QUANTA.Q_CAP_DIFFBUS(CHIPS)':
 C_PATH='@s9s_mb_2u_lib.s9s_mb_2u(sch_1):page165_i157@pure_quanta.q_cap_diffbus(~
chips)',
 P_PATH='@s9s_mb_2u_lib.s9s_mb_2u(sch_1):page174_i157@pure_quanta.q_cap_diffbus(~
chips)',
 PATH='I157',
 DRAWING='@S9S_MB_2U_LIB.S9S_MB_2U(SCH_1):PAGE165',
 PIN_NAMES_ROTATE='TRUE',
 PHYS_PAGE='174',
 XY='(3825,2750)',
 ROT='2',
 VER='2',
 PACK_TYPE='C0201',
 CDS_LIB='pure_quanta',
 CDS_PART_NAME='Q_CAP_DIFFBUS_C0201-DIFF BUS_0A',
 TOLERANCE='20%',
 MATERIAL='X6S',
 VOLTAGE='6.3V',
 VALUE='DIFF BUS_0.22UF',
 PRIM_FILE='./archive_libs/logical/q_cap_diffbus/chips/chips.prt';

PART_NAME
 C879 'Q_CAP_DIFFBUS_C0201-DIFF BUS_0A':;

SECTION_NUMBER 1
 '@S9S_MB_2U_LIB.S9S_MB_2U(SCH_1):PAGE165_I158@PURE_QUANTA.Q_CAP_DIFFBUS(CHIPS)':
 C_PATH='@s9s_mb_2u_lib.s9s_mb_2u(sch_1):page165_i158@pure_quanta.q_cap_diffbus(~
chips)',
 P_PATH='@s9s_mb_2u_lib.s9s_mb_2u(sch_1):page174_i158@pure_quanta.q_cap_diffbus(~
chips)',
 PATH='I158',
 DRAWING='@S9S_MB_2U_LIB.S9S_MB_2U(SCH_1):PAGE165',
 PIN_NAMES_ROTATE='TRUE',
 PHYS_PAGE='174',
 XY='(3825,2700)',
 ROT='2',
 VER='2',
 PACK_TYPE='C0201',
 CDS_LIB='pure_quanta',
 CDS_PART_NAME='Q_CAP_DIFFBUS_C0201-DIFF BUS_0A',
 TOLERANCE='20%',
 MATERIAL='X6S',
 VOLTAGE='6.3V',
 VALUE='DIFF BUS_0.22UF',
 PRIM_FILE='./archive_libs/logical/q_cap_diffbus/chips/chips.prt';

PART_NAME
 C880 'Q_CAP_DIFFBUS_C0201-DIFF BUS_0A':;

SECTION_NUMBER 1
 '@S9S_MB_2U_LIB.S9S_MB_2U(SCH_1):PAGE165_I156@PURE_QUANTA.Q_CAP_DIFFBUS(CHIPS)':
 C_PATH='@s9s_mb_2u_lib.s9s_mb_2u(sch_1):page165_i156@pure_quanta.q_cap_diffbus(~
chips)',
 P_PATH='@s9s_mb_2u_lib.s9s_mb_2u(sch_1):page174_i156@pure_quanta.q_cap_diffbus(~
chips)',
 PATH='I156',
 DRAWING='@S9S_MB_2U_LIB.S9S_MB_2U(SCH_1):PAGE165',
 PIN_NAMES_ROTATE='TRUE',
 PHYS_PAGE='174',
 XY='(3825,2550)',
 ROT='2',
 VER='2',
 PACK_TYPE='C0201',
 CDS_LIB='pure_quanta',
 CDS_PART_NAME='Q_CAP_DIFFBUS_C0201-DIFF BUS_0A',
 TOLERANCE='20%',
 MATERIAL='X6S',
 VOLTAGE='6.3V',
 VALUE='DIFF BUS_0.22UF',
 PRIM_FILE='./archive_libs/logical/q_cap_diffbus/chips/chips.prt';

PART_NAME
 C881 'Q_CAP_DIFFBUS_C0201-DIFF BUS_0A':;

SECTION_NUMBER 1
 '@S9S_MB_2U_LIB.S9S_MB_2U(SCH_1):PAGE165_I155@PURE_QUANTA.Q_CAP_DIFFBUS(CHIPS)':
 C_PATH='@s9s_mb_2u_lib.s9s_mb_2u(sch_1):page165_i155@pure_quanta.q_cap_diffbus(~
chips)',
 P_PATH='@s9s_mb_2u_lib.s9s_mb_2u(sch_1):page174_i155@pure_quanta.q_cap_diffbus(~
chips)',
 PATH='I155',
 DRAWING='@S9S_MB_2U_LIB.S9S_MB_2U(SCH_1):PAGE165',
 PIN_NAMES_ROTATE='TRUE',
 PHYS_PAGE='174',
 XY='(3825,2500)',
 ROT='2',
 VER='2',
 PACK_TYPE='C0201',
 CDS_LIB='pure_quanta',
 CDS_PART_NAME='Q_CAP_DIFFBUS_C0201-DIFF BUS_0A',
 TOLERANCE='20%',
 MATERIAL='X6S',
 VOLTAGE='6.3V',
 VALUE='DIFF BUS_0.22UF',
 PRIM_FILE='./archive_libs/logical/q_cap_diffbus/chips/chips.prt';

PART_NAME
 C882 'Q_CAP_DIFFBUS_C0201-DIFF BUS_0A':;

SECTION_NUMBER 1
 '@S9S_MB_2U_LIB.S9S_MB_2U(SCH_1):PAGE165_I154@PURE_QUANTA.Q_CAP_DIFFBUS(CHIPS)':
 C_PATH='@s9s_mb_2u_lib.s9s_mb_2u(sch_1):page165_i154@pure_quanta.q_cap_diffbus(~
chips)',
 P_PATH='@s9s_mb_2u_lib.s9s_mb_2u(sch_1):page174_i154@pure_quanta.q_cap_diffbus(~
chips)',
 PATH='I154',
 DRAWING='@S9S_MB_2U_LIB.S9S_MB_2U(SCH_1):PAGE165',
 PIN_NAMES_ROTATE='TRUE',
 PHYS_PAGE='174',
 XY='(3825,2350)',
 ROT='2',
 VER='2',
 PACK_TYPE='C0201',
 CDS_LIB='pure_quanta',
 CDS_PART_NAME='Q_CAP_DIFFBUS_C0201-DIFF BUS_0A',
 TOLERANCE='20%',
 MATERIAL='X6S',
 VOLTAGE='6.3V',
 VALUE='DIFF BUS_0.22UF',
 PRIM_FILE='./archive_libs/logical/q_cap_diffbus/chips/chips.prt';

PART_NAME
 C883 'Q_CAP_DIFFBUS_C0201-DIFF BUS_0A':;

SECTION_NUMBER 1
 '@S9S_MB_2U_LIB.S9S_MB_2U(SCH_1):PAGE165_I153@PURE_QUANTA.Q_CAP_DIFFBUS(CHIPS)':
 C_PATH='@s9s_mb_2u_lib.s9s_mb_2u(sch_1):page165_i153@pure_quanta.q_cap_diffbus(~
chips)',
 P_PATH='@s9s_mb_2u_lib.s9s_mb_2u(sch_1):page174_i153@pure_quanta.q_cap_diffbus(~
chips)',
 PATH='I153',
 DRAWING='@S9S_MB_2U_LIB.S9S_MB_2U(SCH_1):PAGE165',
 PIN_NAMES_ROTATE='TRUE',
 PHYS_PAGE='174',
 XY='(3825,2300)',
 ROT='2',
 VER='2',
 PACK_TYPE='C0201',
 CDS_LIB='pure_quanta',
 CDS_PART_NAME='Q_CAP_DIFFBUS_C0201-DIFF BUS_0A',
 TOLERANCE='20%',
 MATERIAL='X6S',
 VOLTAGE='6.3V',
 VALUE='DIFF BUS_0.22UF',
 PRIM_FILE='./archive_libs/logical/q_cap_diffbus/chips/chips.prt';

PART_NAME
 C884 'Q_CAP_DIFFBUS_C0201-DIFF BUS_0A':;

SECTION_NUMBER 1
 '@S9S_MB_2U_LIB.S9S_MB_2U(SCH_1):PAGE165_I151@PURE_QUANTA.Q_CAP_DIFFBUS(CHIPS)':
 C_PATH='@s9s_mb_2u_lib.s9s_mb_2u(sch_1):page165_i151@pure_quanta.q_cap_diffbus(~
chips)',
 P_PATH='@s9s_mb_2u_lib.s9s_mb_2u(sch_1):page174_i151@pure_quanta.q_cap_diffbus(~
chips)',
 PATH='I151',
 DRAWING='@S9S_MB_2U_LIB.S9S_MB_2U(SCH_1):PAGE165',
 PIN_NAMES_ROTATE='TRUE',
 PHYS_PAGE='174',
 XY='(3825,2150)',
 ROT='2',
 VER='2',
 PACK_TYPE='C0201',
 CDS_LIB='pure_quanta',
 CDS_PART_NAME='Q_CAP_DIFFBUS_C0201-DIFF BUS_0A',
 TOLERANCE='20%',
 MATERIAL='X6S',
 VOLTAGE='6.3V',
 VALUE='DIFF BUS_0.22UF',
 PRIM_FILE='./archive_libs/logical/q_cap_diffbus/chips/chips.prt';

PART_NAME
 C885 'Q_CAP_DIFFBUS_C0201-DIFF BUS_0A':;

SECTION_NUMBER 1
 '@S9S_MB_2U_LIB.S9S_MB_2U(SCH_1):PAGE165_I152@PURE_QUANTA.Q_CAP_DIFFBUS(CHIPS)':
 C_PATH='@s9s_mb_2u_lib.s9s_mb_2u(sch_1):page165_i152@pure_quanta.q_cap_diffbus(~
chips)',
 P_PATH='@s9s_mb_2u_lib.s9s_mb_2u(sch_1):page174_i152@pure_quanta.q_cap_diffbus(~
chips)',
 PATH='I152',
 DRAWING='@S9S_MB_2U_LIB.S9S_MB_2U(SCH_1):PAGE165',
 PIN_NAMES_ROTATE='TRUE',
 PHYS_PAGE='174',
 XY='(3825,2100)',
 ROT='2',
 VER='2',
 PACK_TYPE='C0201',
 CDS_LIB='pure_quanta',
 CDS_PART_NAME='Q_CAP_DIFFBUS_C0201-DIFF BUS_0A',
 TOLERANCE='20%',
 MATERIAL='X6S',
 VOLTAGE='6.3V',
 VALUE='DIFF BUS_0.22UF',
 PRIM_FILE='./archive_libs/logical/q_cap_diffbus/chips/chips.prt';

PART_NAME
 C886 'Q_CAP_DIFFBUS_C0201-DIFF BUS_0A':;

SECTION_NUMBER 1
 '@S9S_MB_2U_LIB.S9S_MB_2U(SCH_1):PAGE165_I137@PURE_QUANTA.Q_CAP_DIFFBUS(CHIPS)':
 C_PATH='@s9s_mb_2u_lib.s9s_mb_2u(sch_1):page165_i137@pure_quanta.q_cap_diffbus(~
chips)',
 P_PATH='@s9s_mb_2u_lib.s9s_mb_2u(sch_1):page174_i137@pure_quanta.q_cap_diffbus(~
chips)',
 PATH='I137',
 DRAWING='@S9S_MB_2U_LIB.S9S_MB_2U(SCH_1):PAGE165',
 PIN_NAMES_ROTATE='TRUE',
 PHYS_PAGE='174',
 XY='(3825,1575)',
 ROT='2',
 VER='2',
 PACK_TYPE='C0201',
 CDS_LIB='pure_quanta',
 CDS_PART_NAME='Q_CAP_DIFFBUS_C0201-DIFF BUS_0A',
 TOLERANCE='20%',
 MATERIAL='X6S',
 VOLTAGE='6.3V',
 VALUE='DIFF BUS_0.22UF',
 PRIM_FILE='./archive_libs/logical/q_cap_diffbus/chips/chips.prt';

PART_NAME
 C887 'Q_CAP_DIFFBUS_C0201-DIFF BUS_0A':;

SECTION_NUMBER 1
 '@S9S_MB_2U_LIB.S9S_MB_2U(SCH_1):PAGE165_I136@PURE_QUANTA.Q_CAP_DIFFBUS(CHIPS)':
 C_PATH='@s9s_mb_2u_lib.s9s_mb_2u(sch_1):page165_i136@pure_quanta.q_cap_diffbus(~
chips)',
 P_PATH='@s9s_mb_2u_lib.s9s_mb_2u(sch_1):page174_i136@pure_quanta.q_cap_diffbus(~
chips)',
 PATH='I136',
 DRAWING='@S9S_MB_2U_LIB.S9S_MB_2U(SCH_1):PAGE165',
 PIN_NAMES_ROTATE='TRUE',
 PHYS_PAGE='174',
 XY='(3825,1525)',
 ROT='2',
 VER='2',
 PACK_TYPE='C0201',
 CDS_LIB='pure_quanta',
 CDS_PART_NAME='Q_CAP_DIFFBUS_C0201-DIFF BUS_0A',
 TOLERANCE='20%',
 MATERIAL='X6S',
 VOLTAGE='6.3V',
 VALUE='DIFF BUS_0.22UF',
 PRIM_FILE='./archive_libs/logical/q_cap_diffbus/chips/chips.prt';

PART_NAME
 C888 'Q_CAP_DIFFBUS_C0201-DIFF BUS_0A':;

SECTION_NUMBER 1
 '@S9S_MB_2U_LIB.S9S_MB_2U(SCH_1):PAGE165_I135@PURE_QUANTA.Q_CAP_DIFFBUS(CHIPS)':
 C_PATH='@s9s_mb_2u_lib.s9s_mb_2u(sch_1):page165_i135@pure_quanta.q_cap_diffbus(~
chips)',
 P_PATH='@s9s_mb_2u_lib.s9s_mb_2u(sch_1):page174_i135@pure_quanta.q_cap_diffbus(~
chips)',
 PATH='I135',
 DRAWING='@S9S_MB_2U_LIB.S9S_MB_2U(SCH_1):PAGE165',
 PIN_NAMES_ROTATE='TRUE',
 PHYS_PAGE='174',
 XY='(3825,1375)',
 ROT='2',
 VER='2',
 PACK_TYPE='C0201',
 CDS_LIB='pure_quanta',
 CDS_PART_NAME='Q_CAP_DIFFBUS_C0201-DIFF BUS_0A',
 TOLERANCE='20%',
 MATERIAL='X6S',
 VOLTAGE='6.3V',
 VALUE='DIFF BUS_0.22UF',
 PRIM_FILE='./archive_libs/logical/q_cap_diffbus/chips/chips.prt';

PART_NAME
 C889 'Q_CAP_DIFFBUS_C0201-DIFF BUS_0A':;

SECTION_NUMBER 1
 '@S9S_MB_2U_LIB.S9S_MB_2U(SCH_1):PAGE165_I134@PURE_QUANTA.Q_CAP_DIFFBUS(CHIPS)':
 C_PATH='@s9s_mb_2u_lib.s9s_mb_2u(sch_1):page165_i134@pure_quanta.q_cap_diffbus(~
chips)',
 P_PATH='@s9s_mb_2u_lib.s9s_mb_2u(sch_1):page174_i134@pure_quanta.q_cap_diffbus(~
chips)',
 PATH='I134',
 DRAWING='@S9S_MB_2U_LIB.S9S_MB_2U(SCH_1):PAGE165',
 PIN_NAMES_ROTATE='TRUE',
 PHYS_PAGE='174',
 XY='(3825,1325)',
 ROT='2',
 VER='2',
 PACK_TYPE='C0201',
 CDS_LIB='pure_quanta',
 CDS_PART_NAME='Q_CAP_DIFFBUS_C0201-DIFF BUS_0A',
 TOLERANCE='20%',
 MATERIAL='X6S',
 VOLTAGE='6.3V',
 VALUE='DIFF BUS_0.22UF',
 PRIM_FILE='./archive_libs/logical/q_cap_diffbus/chips/chips.prt';

PART_NAME
 C890 'Q_CAP_DIFFBUS_C0201-DIFF BUS_0A':;

SECTION_NUMBER 1
 '@S9S_MB_2U_LIB.S9S_MB_2U(SCH_1):PAGE165_I133@PURE_QUANTA.Q_CAP_DIFFBUS(CHIPS)':
 C_PATH='@s9s_mb_2u_lib.s9s_mb_2u(sch_1):page165_i133@pure_quanta.q_cap_diffbus(~
chips)',
 P_PATH='@s9s_mb_2u_lib.s9s_mb_2u(sch_1):page174_i133@pure_quanta.q_cap_diffbus(~
chips)',
 PATH='I133',
 DRAWING='@S9S_MB_2U_LIB.S9S_MB_2U(SCH_1):PAGE165',
 PIN_NAMES_ROTATE='TRUE',
 PHYS_PAGE='174',
 XY='(3825,1175)',
 ROT='2',
 VER='2',
 PACK_TYPE='C0201',
 CDS_LIB='pure_quanta',
 CDS_PART_NAME='Q_CAP_DIFFBUS_C0201-DIFF BUS_0A',
 TOLERANCE='20%',
 MATERIAL='X6S',
 VOLTAGE='6.3V',
 VALUE='DIFF BUS_0.22UF',
 PRIM_FILE='./archive_libs/logical/q_cap_diffbus/chips/chips.prt';

PART_NAME
 C891 'Q_CAP_DIFFBUS_C0201-DIFF BUS_0A':;

SECTION_NUMBER 1
 '@S9S_MB_2U_LIB.S9S_MB_2U(SCH_1):PAGE165_I132@PURE_QUANTA.Q_CAP_DIFFBUS(CHIPS)':
 C_PATH='@s9s_mb_2u_lib.s9s_mb_2u(sch_1):page165_i132@pure_quanta.q_cap_diffbus(~
chips)',
 P_PATH='@s9s_mb_2u_lib.s9s_mb_2u(sch_1):page174_i132@pure_quanta.q_cap_diffbus(~
chips)',
 PATH='I132',
 DRAWING='@S9S_MB_2U_LIB.S9S_MB_2U(SCH_1):PAGE165',
 PIN_NAMES_ROTATE='TRUE',
 PHYS_PAGE='174',
 XY='(3825,1125)',
 ROT='2',
 VER='2',
 PACK_TYPE='C0201',
 CDS_LIB='pure_quanta',
 CDS_PART_NAME='Q_CAP_DIFFBUS_C0201-DIFF BUS_0A',
 TOLERANCE='20%',
 MATERIAL='X6S',
 VOLTAGE='6.3V',
 VALUE='DIFF BUS_0.22UF',
 PRIM_FILE='./archive_libs/logical/q_cap_diffbus/chips/chips.prt';

PART_NAME
 C892 'Q_CAP_DIFFBUS_C0201-DIFF BUS_0A':;

SECTION_NUMBER 1
 '@S9S_MB_2U_LIB.S9S_MB_2U(SCH_1):PAGE165_I127@PURE_QUANTA.Q_CAP_DIFFBUS(CHIPS)':
 C_PATH='@s9s_mb_2u_lib.s9s_mb_2u(sch_1):page165_i127@pure_quanta.q_cap_diffbus(~
chips)',
 P_PATH='@s9s_mb_2u_lib.s9s_mb_2u(sch_1):page174_i127@pure_quanta.q_cap_diffbus(~
chips)',
 PATH='I127',
 DRAWING='@S9S_MB_2U_LIB.S9S_MB_2U(SCH_1):PAGE165',
 PIN_NAMES_ROTATE='TRUE',
 PHYS_PAGE='174',
 XY='(3825,975)',
 ROT='2',
 VER='2',
 PACK_TYPE='C0201',
 CDS_LIB='pure_quanta',
 CDS_PART_NAME='Q_CAP_DIFFBUS_C0201-DIFF BUS_0A',
 TOLERANCE='20%',
 MATERIAL='X6S',
 VOLTAGE='6.3V',
 VALUE='DIFF BUS_0.22UF',
 PRIM_FILE='./archive_libs/logical/q_cap_diffbus/chips/chips.prt';

PART_NAME
 C893 'Q_CAP_DIFFBUS_C0201-DIFF BUS_0A':;

SECTION_NUMBER 1
 '@S9S_MB_2U_LIB.S9S_MB_2U(SCH_1):PAGE165_I128@PURE_QUANTA.Q_CAP_DIFFBUS(CHIPS)':
 C_PATH='@s9s_mb_2u_lib.s9s_mb_2u(sch_1):page165_i128@pure_quanta.q_cap_diffbus(~
chips)',
 P_PATH='@s9s_mb_2u_lib.s9s_mb_2u(sch_1):page174_i128@pure_quanta.q_cap_diffbus(~
chips)',
 PATH='I128',
 DRAWING='@S9S_MB_2U_LIB.S9S_MB_2U(SCH_1):PAGE165',
 PIN_NAMES_ROTATE='TRUE',
 PHYS_PAGE='174',
 XY='(3825,925)',
 ROT='2',
 VER='2',
 PACK_TYPE='C0201',
 CDS_LIB='pure_quanta',
 CDS_PART_NAME='Q_CAP_DIFFBUS_C0201-DIFF BUS_0A',
 TOLERANCE='20%',
 MATERIAL='X6S',
 VOLTAGE='6.3V',
 VALUE='DIFF BUS_0.22UF',
 PRIM_FILE='./archive_libs/logical/q_cap_diffbus/chips/chips.prt';

PART_NAME
 C894 'Q_CAP_DIFFBUS_C0201-DIFF BUS_0A':;

SECTION_NUMBER 1
 '@S9S_MB_2U_LIB.S9S_MB_2U(SCH_1):PAGE165_I126@PURE_QUANTA.Q_CAP_DIFFBUS(CHIPS)':
 C_PATH='@s9s_mb_2u_lib.s9s_mb_2u(sch_1):page165_i126@pure_quanta.q_cap_diffbus(~
chips)',
 P_PATH='@s9s_mb_2u_lib.s9s_mb_2u(sch_1):page174_i126@pure_quanta.q_cap_diffbus(~
chips)',
 PATH='I126',
 DRAWING='@S9S_MB_2U_LIB.S9S_MB_2U(SCH_1):PAGE165',
 PIN_NAMES_ROTATE='TRUE',
 PHYS_PAGE='174',
 XY='(3825,775)',
 ROT='2',
 VER='2',
 PACK_TYPE='C0201',
 CDS_LIB='pure_quanta',
 CDS_PART_NAME='Q_CAP_DIFFBUS_C0201-DIFF BUS_0A',
 TOLERANCE='20%',
 MATERIAL='X6S',
 VOLTAGE='6.3V',
 VALUE='DIFF BUS_0.22UF',
 PRIM_FILE='./archive_libs/logical/q_cap_diffbus/chips/chips.prt';

PART_NAME
 C895 'Q_CAP_DIFFBUS_C0201-DIFF BUS_0A':;

SECTION_NUMBER 1
 '@S9S_MB_2U_LIB.S9S_MB_2U(SCH_1):PAGE165_I125@PURE_QUANTA.Q_CAP_DIFFBUS(CHIPS)':
 C_PATH='@s9s_mb_2u_lib.s9s_mb_2u(sch_1):page165_i125@pure_quanta.q_cap_diffbus(~
chips)',
 P_PATH='@s9s_mb_2u_lib.s9s_mb_2u(sch_1):page174_i125@pure_quanta.q_cap_diffbus(~
chips)',
 PATH='I125',
 DRAWING='@S9S_MB_2U_LIB.S9S_MB_2U(SCH_1):PAGE165',
 PIN_NAMES_ROTATE='TRUE',
 PHYS_PAGE='174',
 XY='(3825,725)',
 ROT='2',
 VER='2',
 PACK_TYPE='C0201',
 CDS_LIB='pure_quanta',
 CDS_PART_NAME='Q_CAP_DIFFBUS_C0201-DIFF BUS_0A',
 TOLERANCE='20%',
 MATERIAL='X6S',
 VOLTAGE='6.3V',
 VALUE='DIFF BUS_0.22UF',
 PRIM_FILE='./archive_libs/logical/q_cap_diffbus/chips/chips.prt';

PART_NAME
 C896 'Q_CAP_DIFFBUS_C0201-DIFF BUS_0A':;

SECTION_NUMBER 1
 '@S9S_MB_2U_LIB.S9S_MB_2U(SCH_1):PAGE165_I124@PURE_QUANTA.Q_CAP_DIFFBUS(CHIPS)':
 C_PATH='@s9s_mb_2u_lib.s9s_mb_2u(sch_1):page165_i124@pure_quanta.q_cap_diffbus(~
chips)',
 P_PATH='@s9s_mb_2u_lib.s9s_mb_2u(sch_1):page174_i124@pure_quanta.q_cap_diffbus(~
chips)',
 PATH='I124',
 DRAWING='@S9S_MB_2U_LIB.S9S_MB_2U(SCH_1):PAGE165',
 PIN_NAMES_ROTATE='TRUE',
 PHYS_PAGE='174',
 XY='(3825,575)',
 ROT='2',
 VER='2',
 PACK_TYPE='C0201',
 CDS_LIB='pure_quanta',
 CDS_PART_NAME='Q_CAP_DIFFBUS_C0201-DIFF BUS_0A',
 TOLERANCE='20%',
 MATERIAL='X6S',
 VOLTAGE='6.3V',
 VALUE='DIFF BUS_0.22UF',
 PRIM_FILE='./archive_libs/logical/q_cap_diffbus/chips/chips.prt';

PART_NAME
 C897 'Q_CAP_DIFFBUS_C0201-DIFF BUS_0A':;

SECTION_NUMBER 1
 '@S9S_MB_2U_LIB.S9S_MB_2U(SCH_1):PAGE165_I123@PURE_QUANTA.Q_CAP_DIFFBUS(CHIPS)':
 C_PATH='@s9s_mb_2u_lib.s9s_mb_2u(sch_1):page165_i123@pure_quanta.q_cap_diffbus(~
chips)',
 P_PATH='@s9s_mb_2u_lib.s9s_mb_2u(sch_1):page174_i123@pure_quanta.q_cap_diffbus(~
chips)',
 PATH='I123',
 DRAWING='@S9S_MB_2U_LIB.S9S_MB_2U(SCH_1):PAGE165',
 PIN_NAMES_ROTATE='TRUE',
 PHYS_PAGE='174',
 XY='(3825,525)',
 ROT='2',
 VER='2',
 PACK_TYPE='C0201',
 CDS_LIB='pure_quanta',
 CDS_PART_NAME='Q_CAP_DIFFBUS_C0201-DIFF BUS_0A',
 TOLERANCE='20%',
 MATERIAL='X6S',
 VOLTAGE='6.3V',
 VALUE='DIFF BUS_0.22UF',
 PRIM_FILE='./archive_libs/logical/q_cap_diffbus/chips/chips.prt';

PART_NAME
 C898 'Q_CAP_DIFFBUS_C0201-DIFF BUS_0A':;

SECTION_NUMBER 1
 '@S9S_MB_2U_LIB.S9S_MB_2U(SCH_1):PAGE165_I206@PURE_QUANTA.Q_CAP_DIFFBUS(CHIPS)':
 C_PATH='@s9s_mb_2u_lib.s9s_mb_2u(sch_1):page165_i206@pure_quanta.q_cap_diffbus(~
chips)',
 P_PATH='@s9s_mb_2u_lib.s9s_mb_2u(sch_1):page174_i206@pure_quanta.q_cap_diffbus(~
chips)',
 PATH='I206',
 DRAWING='@S9S_MB_2U_LIB.S9S_MB_2U(SCH_1):PAGE165',
 PIN_NAMES_ROTATE='TRUE',
 PHYS_PAGE='174',
 XY='(3825,375)',
 ROT='2',
 VER='2',
 PACK_TYPE='C0201',
 CDS_LIB='pure_quanta',
 CDS_PART_NAME='Q_CAP_DIFFBUS_C0201-DIFF BUS_0A',
 TOLERANCE='20%',
 MATERIAL='X6S',
 VOLTAGE='6.3V',
 VALUE='DIFF BUS_0.22UF',
 PRIM_FILE='./archive_libs/logical/q_cap_diffbus/chips/chips.prt';

PART_NAME
 C899 'Q_CAP_DIFFBUS_C0201-DIFF BUS_0A':;

SECTION_NUMBER 1
 '@S9S_MB_2U_LIB.S9S_MB_2U(SCH_1):PAGE165_I122@PURE_QUANTA.Q_CAP_DIFFBUS(CHIPS)':
 C_PATH='@s9s_mb_2u_lib.s9s_mb_2u(sch_1):page165_i122@pure_quanta.q_cap_diffbus(~
chips)',
 P_PATH='@s9s_mb_2u_lib.s9s_mb_2u(sch_1):page174_i122@pure_quanta.q_cap_diffbus(~
chips)',
 PATH='I122',
 DRAWING='@S9S_MB_2U_LIB.S9S_MB_2U(SCH_1):PAGE165',
 PIN_NAMES_ROTATE='TRUE',
 PHYS_PAGE='174',
 XY='(3825,325)',
 ROT='2',
 VER='2',
 PACK_TYPE='C0201',
 CDS_LIB='pure_quanta',
 CDS_PART_NAME='Q_CAP_DIFFBUS_C0201-DIFF BUS_0A',
 TOLERANCE='20%',
 MATERIAL='X6S',
 VOLTAGE='6.3V',
 VALUE='DIFF BUS_0.22UF',
 PRIM_FILE='./archive_libs/logical/q_cap_diffbus/chips/chips.prt';

PART_NAME
 C900 'Q_CAP_DIFFBUS_C0201-DIFF BUS_0A':;

SECTION_NUMBER 1
 '@S9S_MB_2U_LIB.S9S_MB_2U(SCH_1):PAGE165_I121@PURE_QUANTA.Q_CAP_DIFFBUS(CHIPS)':
 C_PATH='@s9s_mb_2u_lib.s9s_mb_2u(sch_1):page165_i121@pure_quanta.q_cap_diffbus(~
chips)',
 P_PATH='@s9s_mb_2u_lib.s9s_mb_2u(sch_1):page174_i121@pure_quanta.q_cap_diffbus(~
chips)',
 PATH='I121',
 DRAWING='@S9S_MB_2U_LIB.S9S_MB_2U(SCH_1):PAGE165',
 PIN_NAMES_ROTATE='TRUE',
 PHYS_PAGE='174',
 XY='(3825,175)',
 ROT='2',
 VER='2',
 PACK_TYPE='C0201',
 CDS_LIB='pure_quanta',
 CDS_PART_NAME='Q_CAP_DIFFBUS_C0201-DIFF BUS_0A',
 TOLERANCE='20%',
 MATERIAL='X6S',
 VOLTAGE='6.3V',
 VALUE='DIFF BUS_0.22UF',
 PRIM_FILE='./archive_libs/logical/q_cap_diffbus/chips/chips.prt';

PART_NAME
 C901 'Q_CAP_DIFFBUS_C0201-DIFF BUS_0A':;

SECTION_NUMBER 1
 '@S9S_MB_2U_LIB.S9S_MB_2U(SCH_1):PAGE165_I120@PURE_QUANTA.Q_CAP_DIFFBUS(CHIPS)':
 C_PATH='@s9s_mb_2u_lib.s9s_mb_2u(sch_1):page165_i120@pure_quanta.q_cap_diffbus(~
chips)',
 P_PATH='@s9s_mb_2u_lib.s9s_mb_2u(sch_1):page174_i120@pure_quanta.q_cap_diffbus(~
chips)',
 PATH='I120',
 DRAWING='@S9S_MB_2U_LIB.S9S_MB_2U(SCH_1):PAGE165',
 PIN_NAMES_ROTATE='TRUE',
 PHYS_PAGE='174',
 XY='(3825,125)',
 ROT='2',
 VER='2',
 PACK_TYPE='C0201',
 CDS_LIB='pure_quanta',
 CDS_PART_NAME='Q_CAP_DIFFBUS_C0201-DIFF BUS_0A',
 TOLERANCE='20%',
 MATERIAL='X6S',
 VOLTAGE='6.3V',
 VALUE='DIFF BUS_0.22UF',
 PRIM_FILE='./archive_libs/logical/q_cap_diffbus/chips/chips.prt';

PART_NAME
 C902 'Q_CAP_DIFFBUS_C0201-DIFF BUS_0A':;

SECTION_NUMBER 1
 '@S9S_MB_2U_LIB.S9S_MB_2U(SCH_1):PAGE164_I68@PURE_QUANTA.Q_CAP_DIFFBUS(CHIPS)':
 C_PATH='@s9s_mb_2u_lib.s9s_mb_2u(sch_1):page164_i68@pure_quanta.q_cap_diffbus(c~
hips)',
 P_PATH='@s9s_mb_2u_lib.s9s_mb_2u(sch_1):page173_i68@pure_quanta.q_cap_diffbus(c~
hips)',
 PATH='I68',
 DRAWING='@S9S_MB_2U_LIB.S9S_MB_2U(SCH_1):PAGE164',
 PIN_NAMES_ROTATE='TRUE',
 PHYS_PAGE='173',
 XY='(-575,3750)',
 ROT='2',
 VER='2',
 PACK_TYPE='C0201',
 CDS_LIB='pure_quanta',
 CDS_PART_NAME='Q_CAP_DIFFBUS_C0201-DIFF BUS_0A',
 TOLERANCE='20%',
 MATERIAL='X6S',
 VOLTAGE='6.3V',
 VALUE='DIFF BUS_0.22UF',
 PRIM_FILE='./archive_libs/logical/q_cap_diffbus/chips/chips.prt';

PART_NAME
 C903 'Q_CAP_DIFFBUS_C0201-DIFF BUS_0A':;

SECTION_NUMBER 1
 '@S9S_MB_2U_LIB.S9S_MB_2U(SCH_1):PAGE164_I67@PURE_QUANTA.Q_CAP_DIFFBUS(CHIPS)':
 C_PATH='@s9s_mb_2u_lib.s9s_mb_2u(sch_1):page164_i67@pure_quanta.q_cap_diffbus(c~
hips)',
 P_PATH='@s9s_mb_2u_lib.s9s_mb_2u(sch_1):page173_i67@pure_quanta.q_cap_diffbus(c~
hips)',
 PATH='I67',
 DRAWING='@S9S_MB_2U_LIB.S9S_MB_2U(SCH_1):PAGE164',
 PIN_NAMES_ROTATE='TRUE',
 PHYS_PAGE='173',
 XY='(-575,3700)',
 ROT='2',
 VER='2',
 PACK_TYPE='C0201',
 CDS_LIB='pure_quanta',
 CDS_PART_NAME='Q_CAP_DIFFBUS_C0201-DIFF BUS_0A',
 TOLERANCE='20%',
 MATERIAL='X6S',
 VOLTAGE='6.3V',
 VALUE='DIFF BUS_0.22UF',
 PRIM_FILE='./archive_libs/logical/q_cap_diffbus/chips/chips.prt';

PART_NAME
 C904 'Q_CAP_DIFFBUS_C0201-DIFF BUS_0A':;

SECTION_NUMBER 1
 '@S9S_MB_2U_LIB.S9S_MB_2U(SCH_1):PAGE164_I66@PURE_QUANTA.Q_CAP_DIFFBUS(CHIPS)':
 C_PATH='@s9s_mb_2u_lib.s9s_mb_2u(sch_1):page164_i66@pure_quanta.q_cap_diffbus(c~
hips)',
 P_PATH='@s9s_mb_2u_lib.s9s_mb_2u(sch_1):page173_i66@pure_quanta.q_cap_diffbus(c~
hips)',
 PATH='I66',
 DRAWING='@S9S_MB_2U_LIB.S9S_MB_2U(SCH_1):PAGE164',
 PIN_NAMES_ROTATE='TRUE',
 PHYS_PAGE='173',
 XY='(-575,3550)',
 ROT='2',
 VER='2',
 PACK_TYPE='C0201',
 CDS_LIB='pure_quanta',
 CDS_PART_NAME='Q_CAP_DIFFBUS_C0201-DIFF BUS_0A',
 TOLERANCE='20%',
 MATERIAL='X6S',
 VOLTAGE='6.3V',
 VALUE='DIFF BUS_0.22UF',
 PRIM_FILE='./archive_libs/logical/q_cap_diffbus/chips/chips.prt';

PART_NAME
 C905 'Q_CAP_DIFFBUS_C0201-DIFF BUS_0A':;

SECTION_NUMBER 1
 '@S9S_MB_2U_LIB.S9S_MB_2U(SCH_1):PAGE164_I65@PURE_QUANTA.Q_CAP_DIFFBUS(CHIPS)':
 C_PATH='@s9s_mb_2u_lib.s9s_mb_2u(sch_1):page164_i65@pure_quanta.q_cap_diffbus(c~
hips)',
 P_PATH='@s9s_mb_2u_lib.s9s_mb_2u(sch_1):page173_i65@pure_quanta.q_cap_diffbus(c~
hips)',
 PATH='I65',
 DRAWING='@S9S_MB_2U_LIB.S9S_MB_2U(SCH_1):PAGE164',
 PIN_NAMES_ROTATE='TRUE',
 PHYS_PAGE='173',
 XY='(-575,3500)',
 ROT='2',
 VER='2',
 PACK_TYPE='C0201',
 CDS_LIB='pure_quanta',
 CDS_PART_NAME='Q_CAP_DIFFBUS_C0201-DIFF BUS_0A',
 TOLERANCE='20%',
 MATERIAL='X6S',
 VOLTAGE='6.3V',
 VALUE='DIFF BUS_0.22UF',
 PRIM_FILE='./archive_libs/logical/q_cap_diffbus/chips/chips.prt';

PART_NAME
 C906 'Q_CAP_DIFFBUS_C0201-DIFF BUS_0A':;

SECTION_NUMBER 1
 '@S9S_MB_2U_LIB.S9S_MB_2U(SCH_1):PAGE164_I63@PURE_QUANTA.Q_CAP_DIFFBUS(CHIPS)':
 C_PATH='@s9s_mb_2u_lib.s9s_mb_2u(sch_1):page164_i63@pure_quanta.q_cap_diffbus(c~
hips)',
 P_PATH='@s9s_mb_2u_lib.s9s_mb_2u(sch_1):page173_i63@pure_quanta.q_cap_diffbus(c~
hips)',
 PATH='I63',
 DRAWING='@S9S_MB_2U_LIB.S9S_MB_2U(SCH_1):PAGE164',
 PIN_NAMES_ROTATE='TRUE',
 PHYS_PAGE='173',
 XY='(-575,3350)',
 ROT='2',
 VER='2',
 PACK_TYPE='C0201',
 CDS_LIB='pure_quanta',
 CDS_PART_NAME='Q_CAP_DIFFBUS_C0201-DIFF BUS_0A',
 TOLERANCE='20%',
 MATERIAL='X6S',
 VOLTAGE='6.3V',
 VALUE='DIFF BUS_0.22UF',
 PRIM_FILE='./archive_libs/logical/q_cap_diffbus/chips/chips.prt';

PART_NAME
 C907 'Q_CAP_DIFFBUS_C0201-DIFF BUS_0A':;

SECTION_NUMBER 1
 '@S9S_MB_2U_LIB.S9S_MB_2U(SCH_1):PAGE164_I64@PURE_QUANTA.Q_CAP_DIFFBUS(CHIPS)':
 C_PATH='@s9s_mb_2u_lib.s9s_mb_2u(sch_1):page164_i64@pure_quanta.q_cap_diffbus(c~
hips)',
 P_PATH='@s9s_mb_2u_lib.s9s_mb_2u(sch_1):page173_i64@pure_quanta.q_cap_diffbus(c~
hips)',
 PATH='I64',
 DRAWING='@S9S_MB_2U_LIB.S9S_MB_2U(SCH_1):PAGE164',
 PIN_NAMES_ROTATE='TRUE',
 PHYS_PAGE='173',
 XY='(-575,3300)',
 ROT='2',
 VER='2',
 PACK_TYPE='C0201',
 CDS_LIB='pure_quanta',
 CDS_PART_NAME='Q_CAP_DIFFBUS_C0201-DIFF BUS_0A',
 TOLERANCE='20%',
 MATERIAL='X6S',
 VOLTAGE='6.3V',
 VALUE='DIFF BUS_0.22UF',
 PRIM_FILE='./archive_libs/logical/q_cap_diffbus/chips/chips.prt';

PART_NAME
 C908 'Q_CAP_DIFFBUS_C0201-DIFF BUS_0A':;

SECTION_NUMBER 1
 '@S9S_MB_2U_LIB.S9S_MB_2U(SCH_1):PAGE164_I62@PURE_QUANTA.Q_CAP_DIFFBUS(CHIPS)':
 C_PATH='@s9s_mb_2u_lib.s9s_mb_2u(sch_1):page164_i62@pure_quanta.q_cap_diffbus(c~
hips)',
 P_PATH='@s9s_mb_2u_lib.s9s_mb_2u(sch_1):page173_i62@pure_quanta.q_cap_diffbus(c~
hips)',
 PATH='I62',
 DRAWING='@S9S_MB_2U_LIB.S9S_MB_2U(SCH_1):PAGE164',
 PIN_NAMES_ROTATE='TRUE',
 PHYS_PAGE='173',
 XY='(-575,3150)',
 ROT='2',
 VER='2',
 PACK_TYPE='C0201',
 CDS_LIB='pure_quanta',
 CDS_PART_NAME='Q_CAP_DIFFBUS_C0201-DIFF BUS_0A',
 TOLERANCE='20%',
 MATERIAL='X6S',
 VOLTAGE='6.3V',
 VALUE='DIFF BUS_0.22UF',
 PRIM_FILE='./archive_libs/logical/q_cap_diffbus/chips/chips.prt';

PART_NAME
 C909 'Q_CAP_DIFFBUS_C0201-DIFF BUS_0A':;

SECTION_NUMBER 1
 '@S9S_MB_2U_LIB.S9S_MB_2U(SCH_1):PAGE164_I61@PURE_QUANTA.Q_CAP_DIFFBUS(CHIPS)':
 C_PATH='@s9s_mb_2u_lib.s9s_mb_2u(sch_1):page164_i61@pure_quanta.q_cap_diffbus(c~
hips)',
 P_PATH='@s9s_mb_2u_lib.s9s_mb_2u(sch_1):page173_i61@pure_quanta.q_cap_diffbus(c~
hips)',
 PATH='I61',
 DRAWING='@S9S_MB_2U_LIB.S9S_MB_2U(SCH_1):PAGE164',
 PIN_NAMES_ROTATE='TRUE',
 PHYS_PAGE='173',
 XY='(-575,3100)',
 ROT='2',
 VER='2',
 PACK_TYPE='C0201',
 CDS_LIB='pure_quanta',
 CDS_PART_NAME='Q_CAP_DIFFBUS_C0201-DIFF BUS_0A',
 TOLERANCE='20%',
 MATERIAL='X6S',
 VOLTAGE='6.3V',
 VALUE='DIFF BUS_0.22UF',
 PRIM_FILE='./archive_libs/logical/q_cap_diffbus/chips/chips.prt';

PART_NAME
 C910 'Q_CAP_DIFFBUS_C0201-DIFF BUS_0A':;

SECTION_NUMBER 1
 '@S9S_MB_2U_LIB.S9S_MB_2U(SCH_1):PAGE164_I60@PURE_QUANTA.Q_CAP_DIFFBUS(CHIPS)':
 C_PATH='@s9s_mb_2u_lib.s9s_mb_2u(sch_1):page164_i60@pure_quanta.q_cap_diffbus(c~
hips)',
 P_PATH='@s9s_mb_2u_lib.s9s_mb_2u(sch_1):page173_i60@pure_quanta.q_cap_diffbus(c~
hips)',
 PATH='I60',
 DRAWING='@S9S_MB_2U_LIB.S9S_MB_2U(SCH_1):PAGE164',
 PIN_NAMES_ROTATE='TRUE',
 PHYS_PAGE='173',
 XY='(-575,2950)',
 ROT='2',
 VER='2',
 PACK_TYPE='C0201',
 CDS_LIB='pure_quanta',
 CDS_PART_NAME='Q_CAP_DIFFBUS_C0201-DIFF BUS_0A',
 TOLERANCE='20%',
 MATERIAL='X6S',
 VOLTAGE='6.3V',
 VALUE='DIFF BUS_0.22UF',
 PRIM_FILE='./archive_libs/logical/q_cap_diffbus/chips/chips.prt';

PART_NAME
 C911 'Q_CAP_DIFFBUS_C0201-DIFF BUS_0A':;

SECTION_NUMBER 1
 '@S9S_MB_2U_LIB.S9S_MB_2U(SCH_1):PAGE164_I59@PURE_QUANTA.Q_CAP_DIFFBUS(CHIPS)':
 C_PATH='@s9s_mb_2u_lib.s9s_mb_2u(sch_1):page164_i59@pure_quanta.q_cap_diffbus(c~
hips)',
 P_PATH='@s9s_mb_2u_lib.s9s_mb_2u(sch_1):page173_i59@pure_quanta.q_cap_diffbus(c~
hips)',
 PATH='I59',
 DRAWING='@S9S_MB_2U_LIB.S9S_MB_2U(SCH_1):PAGE164',
 PIN_NAMES_ROTATE='TRUE',
 PHYS_PAGE='173',
 XY='(-575,2900)',
 ROT='2',
 VER='2',
 PACK_TYPE='C0201',
 CDS_LIB='pure_quanta',
 CDS_PART_NAME='Q_CAP_DIFFBUS_C0201-DIFF BUS_0A',
 TOLERANCE='20%',
 MATERIAL='X6S',
 VOLTAGE='6.3V',
 VALUE='DIFF BUS_0.22UF',
 PRIM_FILE='./archive_libs/logical/q_cap_diffbus/chips/chips.prt';

PART_NAME
 C912 'Q_CAP_DIFFBUS_C0201-DIFF BUS_0A':;

SECTION_NUMBER 1
 '@S9S_MB_2U_LIB.S9S_MB_2U(SCH_1):PAGE164_I58@PURE_QUANTA.Q_CAP_DIFFBUS(CHIPS)':
 C_PATH='@s9s_mb_2u_lib.s9s_mb_2u(sch_1):page164_i58@pure_quanta.q_cap_diffbus(c~
hips)',
 P_PATH='@s9s_mb_2u_lib.s9s_mb_2u(sch_1):page173_i58@pure_quanta.q_cap_diffbus(c~
hips)',
 PATH='I58',
 DRAWING='@S9S_MB_2U_LIB.S9S_MB_2U(SCH_1):PAGE164',
 PIN_NAMES_ROTATE='TRUE',
 PHYS_PAGE='173',
 XY='(-575,2750)',
 ROT='2',
 VER='2',
 PACK_TYPE='C0201',
 CDS_LIB='pure_quanta',
 CDS_PART_NAME='Q_CAP_DIFFBUS_C0201-DIFF BUS_0A',
 TOLERANCE='20%',
 MATERIAL='X6S',
 VOLTAGE='6.3V',
 VALUE='DIFF BUS_0.22UF',
 PRIM_FILE='./archive_libs/logical/q_cap_diffbus/chips/chips.prt';

PART_NAME
 C913 'Q_CAP_DIFFBUS_C0201-DIFF BUS_0A':;

SECTION_NUMBER 1
 '@S9S_MB_2U_LIB.S9S_MB_2U(SCH_1):PAGE164_I57@PURE_QUANTA.Q_CAP_DIFFBUS(CHIPS)':
 C_PATH='@s9s_mb_2u_lib.s9s_mb_2u(sch_1):page164_i57@pure_quanta.q_cap_diffbus(c~
hips)',
 P_PATH='@s9s_mb_2u_lib.s9s_mb_2u(sch_1):page173_i57@pure_quanta.q_cap_diffbus(c~
hips)',
 PATH='I57',
 DRAWING='@S9S_MB_2U_LIB.S9S_MB_2U(SCH_1):PAGE164',
 PIN_NAMES_ROTATE='TRUE',
 PHYS_PAGE='173',
 XY='(-575,2700)',
 ROT='2',
 VER='2',
 PACK_TYPE='C0201',
 CDS_LIB='pure_quanta',
 CDS_PART_NAME='Q_CAP_DIFFBUS_C0201-DIFF BUS_0A',
 TOLERANCE='20%',
 MATERIAL='X6S',
 VOLTAGE='6.3V',
 VALUE='DIFF BUS_0.22UF',
 PRIM_FILE='./archive_libs/logical/q_cap_diffbus/chips/chips.prt';

PART_NAME
 C914 'Q_CAP_DIFFBUS_C0201-DIFF BUS_0A':;

SECTION_NUMBER 1
 '@S9S_MB_2U_LIB.S9S_MB_2U(SCH_1):PAGE164_I56@PURE_QUANTA.Q_CAP_DIFFBUS(CHIPS)':
 C_PATH='@s9s_mb_2u_lib.s9s_mb_2u(sch_1):page164_i56@pure_quanta.q_cap_diffbus(c~
hips)',
 P_PATH='@s9s_mb_2u_lib.s9s_mb_2u(sch_1):page173_i56@pure_quanta.q_cap_diffbus(c~
hips)',
 PATH='I56',
 DRAWING='@S9S_MB_2U_LIB.S9S_MB_2U(SCH_1):PAGE164',
 PIN_NAMES_ROTATE='TRUE',
 PHYS_PAGE='173',
 XY='(-575,2550)',
 ROT='2',
 VER='2',
 PACK_TYPE='C0201',
 CDS_LIB='pure_quanta',
 CDS_PART_NAME='Q_CAP_DIFFBUS_C0201-DIFF BUS_0A',
 TOLERANCE='20%',
 MATERIAL='X6S',
 VOLTAGE='6.3V',
 VALUE='DIFF BUS_0.22UF',
 PRIM_FILE='./archive_libs/logical/q_cap_diffbus/chips/chips.prt';

PART_NAME
 C915 'Q_CAP_DIFFBUS_C0201-DIFF BUS_0A':;

SECTION_NUMBER 1
 '@S9S_MB_2U_LIB.S9S_MB_2U(SCH_1):PAGE164_I55@PURE_QUANTA.Q_CAP_DIFFBUS(CHIPS)':
 C_PATH='@s9s_mb_2u_lib.s9s_mb_2u(sch_1):page164_i55@pure_quanta.q_cap_diffbus(c~
hips)',
 P_PATH='@s9s_mb_2u_lib.s9s_mb_2u(sch_1):page173_i55@pure_quanta.q_cap_diffbus(c~
hips)',
 PATH='I55',
 DRAWING='@S9S_MB_2U_LIB.S9S_MB_2U(SCH_1):PAGE164',
 PIN_NAMES_ROTATE='TRUE',
 PHYS_PAGE='173',
 XY='(-575,2500)',
 ROT='2',
 VER='2',
 PACK_TYPE='C0201',
 CDS_LIB='pure_quanta',
 CDS_PART_NAME='Q_CAP_DIFFBUS_C0201-DIFF BUS_0A',
 TOLERANCE='20%',
 MATERIAL='X6S',
 VOLTAGE='6.3V',
 VALUE='DIFF BUS_0.22UF',
 PRIM_FILE='./archive_libs/logical/q_cap_diffbus/chips/chips.prt';

PART_NAME
 C916 'Q_CAP_DIFFBUS_C0201-DIFF BUS_0A':;

SECTION_NUMBER 1
 '@S9S_MB_2U_LIB.S9S_MB_2U(SCH_1):PAGE164_I53@PURE_QUANTA.Q_CAP_DIFFBUS(CHIPS)':
 C_PATH='@s9s_mb_2u_lib.s9s_mb_2u(sch_1):page164_i53@pure_quanta.q_cap_diffbus(c~
hips)',
 P_PATH='@s9s_mb_2u_lib.s9s_mb_2u(sch_1):page173_i53@pure_quanta.q_cap_diffbus(c~
hips)',
 PATH='I53',
 DRAWING='@S9S_MB_2U_LIB.S9S_MB_2U(SCH_1):PAGE164',
 PIN_NAMES_ROTATE='TRUE',
 PHYS_PAGE='173',
 XY='(-575,2350)',
 ROT='2',
 VER='2',
 PACK_TYPE='C0201',
 CDS_LIB='pure_quanta',
 CDS_PART_NAME='Q_CAP_DIFFBUS_C0201-DIFF BUS_0A',
 TOLERANCE='20%',
 MATERIAL='X6S',
 VOLTAGE='6.3V',
 VALUE='DIFF BUS_0.22UF',
 PRIM_FILE='./archive_libs/logical/q_cap_diffbus/chips/chips.prt';

PART_NAME
 C917 'Q_CAP_DIFFBUS_C0201-DIFF BUS_0A':;

SECTION_NUMBER 1
 '@S9S_MB_2U_LIB.S9S_MB_2U(SCH_1):PAGE164_I54@PURE_QUANTA.Q_CAP_DIFFBUS(CHIPS)':
 C_PATH='@s9s_mb_2u_lib.s9s_mb_2u(sch_1):page164_i54@pure_quanta.q_cap_diffbus(c~
hips)',
 P_PATH='@s9s_mb_2u_lib.s9s_mb_2u(sch_1):page173_i54@pure_quanta.q_cap_diffbus(c~
hips)',
 PATH='I54',
 DRAWING='@S9S_MB_2U_LIB.S9S_MB_2U(SCH_1):PAGE164',
 PIN_NAMES_ROTATE='TRUE',
 PHYS_PAGE='173',
 XY='(-575,2300)',
 ROT='2',
 VER='2',
 PACK_TYPE='C0201',
 CDS_LIB='pure_quanta',
 CDS_PART_NAME='Q_CAP_DIFFBUS_C0201-DIFF BUS_0A',
 TOLERANCE='20%',
 MATERIAL='X6S',
 VOLTAGE='6.3V',
 VALUE='DIFF BUS_0.22UF',
 PRIM_FILE='./archive_libs/logical/q_cap_diffbus/chips/chips.prt';

PART_NAME
 C918 'Q_CAP_DIFFBUS_C0201-DIFF BUS_0A':;

SECTION_NUMBER 1
 '@S9S_MB_2U_LIB.S9S_MB_2U(SCH_1):PAGE164_I35@PURE_QUANTA.Q_CAP_DIFFBUS(CHIPS)':
 C_PATH='@s9s_mb_2u_lib.s9s_mb_2u(sch_1):page164_i35@pure_quanta.q_cap_diffbus(c~
hips)',
 P_PATH='@s9s_mb_2u_lib.s9s_mb_2u(sch_1):page173_i35@pure_quanta.q_cap_diffbus(c~
hips)',
 PATH='I35',
 DRAWING='@S9S_MB_2U_LIB.S9S_MB_2U(SCH_1):PAGE164',
 PIN_NAMES_ROTATE='TRUE',
 PHYS_PAGE='173',
 XY='(-575,1775)',
 ROT='2',
 VER='2',
 PACK_TYPE='C0201',
 CDS_LIB='pure_quanta',
 CDS_PART_NAME='Q_CAP_DIFFBUS_C0201-DIFF BUS_0A',
 TOLERANCE='20%',
 MATERIAL='X6S',
 VOLTAGE='6.3V',
 VALUE='DIFF BUS_0.22UF',
 PRIM_FILE='./archive_libs/logical/q_cap_diffbus/chips/chips.prt';

PART_NAME
 C919 'Q_CAP_DIFFBUS_C0201-DIFF BUS_0A':;

SECTION_NUMBER 1
 '@S9S_MB_2U_LIB.S9S_MB_2U(SCH_1):PAGE164_I36@PURE_QUANTA.Q_CAP_DIFFBUS(CHIPS)':
 C_PATH='@s9s_mb_2u_lib.s9s_mb_2u(sch_1):page164_i36@pure_quanta.q_cap_diffbus(c~
hips)',
 P_PATH='@s9s_mb_2u_lib.s9s_mb_2u(sch_1):page173_i36@pure_quanta.q_cap_diffbus(c~
hips)',
 PATH='I36',
 DRAWING='@S9S_MB_2U_LIB.S9S_MB_2U(SCH_1):PAGE164',
 PIN_NAMES_ROTATE='TRUE',
 PHYS_PAGE='173',
 XY='(-575,1725)',
 ROT='2',
 VER='2',
 PACK_TYPE='C0201',
 CDS_LIB='pure_quanta',
 CDS_PART_NAME='Q_CAP_DIFFBUS_C0201-DIFF BUS_0A',
 TOLERANCE='20%',
 MATERIAL='X6S',
 VOLTAGE='6.3V',
 VALUE='DIFF BUS_0.22UF',
 PRIM_FILE='./archive_libs/logical/q_cap_diffbus/chips/chips.prt';

PART_NAME
 C920 'Q_CAP_DIFFBUS_C0201-DIFF BUS_0A':;

SECTION_NUMBER 1
 '@S9S_MB_2U_LIB.S9S_MB_2U(SCH_1):PAGE164_I34@PURE_QUANTA.Q_CAP_DIFFBUS(CHIPS)':
 C_PATH='@s9s_mb_2u_lib.s9s_mb_2u(sch_1):page164_i34@pure_quanta.q_cap_diffbus(c~
hips)',
 P_PATH='@s9s_mb_2u_lib.s9s_mb_2u(sch_1):page173_i34@pure_quanta.q_cap_diffbus(c~
hips)',
 PATH='I34',
 DRAWING='@S9S_MB_2U_LIB.S9S_MB_2U(SCH_1):PAGE164',
 PIN_NAMES_ROTATE='TRUE',
 PHYS_PAGE='173',
 XY='(-575,1575)',
 ROT='2',
 VER='2',
 PACK_TYPE='C0201',
 CDS_LIB='pure_quanta',
 CDS_PART_NAME='Q_CAP_DIFFBUS_C0201-DIFF BUS_0A',
 TOLERANCE='20%',
 MATERIAL='X6S',
 VOLTAGE='6.3V',
 VALUE='DIFF BUS_0.22UF',
 PRIM_FILE='./archive_libs/logical/q_cap_diffbus/chips/chips.prt';

PART_NAME
 C921 'Q_CAP_DIFFBUS_C0201-DIFF BUS_0A':;

SECTION_NUMBER 1
 '@S9S_MB_2U_LIB.S9S_MB_2U(SCH_1):PAGE164_I33@PURE_QUANTA.Q_CAP_DIFFBUS(CHIPS)':
 C_PATH='@s9s_mb_2u_lib.s9s_mb_2u(sch_1):page164_i33@pure_quanta.q_cap_diffbus(c~
hips)',
 P_PATH='@s9s_mb_2u_lib.s9s_mb_2u(sch_1):page173_i33@pure_quanta.q_cap_diffbus(c~
hips)',
 PATH='I33',
 DRAWING='@S9S_MB_2U_LIB.S9S_MB_2U(SCH_1):PAGE164',
 PIN_NAMES_ROTATE='TRUE',
 PHYS_PAGE='173',
 XY='(-575,1525)',
 ROT='2',
 VER='2',
 PACK_TYPE='C0201',
 CDS_LIB='pure_quanta',
 CDS_PART_NAME='Q_CAP_DIFFBUS_C0201-DIFF BUS_0A',
 TOLERANCE='20%',
 MATERIAL='X6S',
 VOLTAGE='6.3V',
 VALUE='DIFF BUS_0.22UF',
 PRIM_FILE='./archive_libs/logical/q_cap_diffbus/chips/chips.prt';

PART_NAME
 C922 'Q_CAP_DIFFBUS_C0201-DIFF BUS_0A':;

SECTION_NUMBER 1
 '@S9S_MB_2U_LIB.S9S_MB_2U(SCH_1):PAGE164_I32@PURE_QUANTA.Q_CAP_DIFFBUS(CHIPS)':
 C_PATH='@s9s_mb_2u_lib.s9s_mb_2u(sch_1):page164_i32@pure_quanta.q_cap_diffbus(c~
hips)',
 P_PATH='@s9s_mb_2u_lib.s9s_mb_2u(sch_1):page173_i32@pure_quanta.q_cap_diffbus(c~
hips)',
 PATH='I32',
 DRAWING='@S9S_MB_2U_LIB.S9S_MB_2U(SCH_1):PAGE164',
 PIN_NAMES_ROTATE='TRUE',
 PHYS_PAGE='173',
 XY='(-575,1375)',
 ROT='2',
 VER='2',
 PACK_TYPE='C0201',
 CDS_LIB='pure_quanta',
 CDS_PART_NAME='Q_CAP_DIFFBUS_C0201-DIFF BUS_0A',
 TOLERANCE='20%',
 MATERIAL='X6S',
 VOLTAGE='6.3V',
 VALUE='DIFF BUS_0.22UF',
 PRIM_FILE='./archive_libs/logical/q_cap_diffbus/chips/chips.prt';

PART_NAME
 C923 'Q_CAP_DIFFBUS_C0201-DIFF BUS_0A':;

SECTION_NUMBER 1
 '@S9S_MB_2U_LIB.S9S_MB_2U(SCH_1):PAGE164_I31@PURE_QUANTA.Q_CAP_DIFFBUS(CHIPS)':
 C_PATH='@s9s_mb_2u_lib.s9s_mb_2u(sch_1):page164_i31@pure_quanta.q_cap_diffbus(c~
hips)',
 P_PATH='@s9s_mb_2u_lib.s9s_mb_2u(sch_1):page173_i31@pure_quanta.q_cap_diffbus(c~
hips)',
 PATH='I31',
 DRAWING='@S9S_MB_2U_LIB.S9S_MB_2U(SCH_1):PAGE164',
 PIN_NAMES_ROTATE='TRUE',
 PHYS_PAGE='173',
 XY='(-575,1325)',
 ROT='2',
 VER='2',
 PACK_TYPE='C0201',
 CDS_LIB='pure_quanta',
 CDS_PART_NAME='Q_CAP_DIFFBUS_C0201-DIFF BUS_0A',
 TOLERANCE='20%',
 MATERIAL='X6S',
 VOLTAGE='6.3V',
 VALUE='DIFF BUS_0.22UF',
 PRIM_FILE='./archive_libs/logical/q_cap_diffbus/chips/chips.prt';

PART_NAME
 C924 'Q_CAP_DIFFBUS_C0201-DIFF BUS_0A':;

SECTION_NUMBER 1
 '@S9S_MB_2U_LIB.S9S_MB_2U(SCH_1):PAGE164_I30@PURE_QUANTA.Q_CAP_DIFFBUS(CHIPS)':
 C_PATH='@s9s_mb_2u_lib.s9s_mb_2u(sch_1):page164_i30@pure_quanta.q_cap_diffbus(c~
hips)',
 P_PATH='@s9s_mb_2u_lib.s9s_mb_2u(sch_1):page173_i30@pure_quanta.q_cap_diffbus(c~
hips)',
 PATH='I30',
 DRAWING='@S9S_MB_2U_LIB.S9S_MB_2U(SCH_1):PAGE164',
 PIN_NAMES_ROTATE='TRUE',
 PHYS_PAGE='173',
 XY='(-575,1175)',
 ROT='2',
 VER='2',
 PACK_TYPE='C0201',
 CDS_LIB='pure_quanta',
 CDS_PART_NAME='Q_CAP_DIFFBUS_C0201-DIFF BUS_0A',
 TOLERANCE='20%',
 MATERIAL='X6S',
 VOLTAGE='6.3V',
 VALUE='DIFF BUS_0.22UF',
 PRIM_FILE='./archive_libs/logical/q_cap_diffbus/chips/chips.prt';

PART_NAME
 C925 'Q_CAP_DIFFBUS_C0201-DIFF BUS_0A':;

SECTION_NUMBER 1
 '@S9S_MB_2U_LIB.S9S_MB_2U(SCH_1):PAGE164_I29@PURE_QUANTA.Q_CAP_DIFFBUS(CHIPS)':
 C_PATH='@s9s_mb_2u_lib.s9s_mb_2u(sch_1):page164_i29@pure_quanta.q_cap_diffbus(c~
hips)',
 P_PATH='@s9s_mb_2u_lib.s9s_mb_2u(sch_1):page173_i29@pure_quanta.q_cap_diffbus(c~
hips)',
 PATH='I29',
 DRAWING='@S9S_MB_2U_LIB.S9S_MB_2U(SCH_1):PAGE164',
 PIN_NAMES_ROTATE='TRUE',
 PHYS_PAGE='173',
 XY='(-575,1125)',
 ROT='2',
 VER='2',
 PACK_TYPE='C0201',
 CDS_LIB='pure_quanta',
 CDS_PART_NAME='Q_CAP_DIFFBUS_C0201-DIFF BUS_0A',
 TOLERANCE='20%',
 MATERIAL='X6S',
 VOLTAGE='6.3V',
 VALUE='DIFF BUS_0.22UF',
 PRIM_FILE='./archive_libs/logical/q_cap_diffbus/chips/chips.prt';

PART_NAME
 C926 'Q_CAP_DIFFBUS_C0201-DIFF BUS_0A':;

SECTION_NUMBER 1
 '@S9S_MB_2U_LIB.S9S_MB_2U(SCH_1):PAGE164_I28@PURE_QUANTA.Q_CAP_DIFFBUS(CHIPS)':
 C_PATH='@s9s_mb_2u_lib.s9s_mb_2u(sch_1):page164_i28@pure_quanta.q_cap_diffbus(c~
hips)',
 P_PATH='@s9s_mb_2u_lib.s9s_mb_2u(sch_1):page173_i28@pure_quanta.q_cap_diffbus(c~
hips)',
 PATH='I28',
 DRAWING='@S9S_MB_2U_LIB.S9S_MB_2U(SCH_1):PAGE164',
 PIN_NAMES_ROTATE='TRUE',
 PHYS_PAGE='173',
 XY='(-575,975)',
 ROT='2',
 VER='2',
 PACK_TYPE='C0201',
 CDS_LIB='pure_quanta',
 CDS_PART_NAME='Q_CAP_DIFFBUS_C0201-DIFF BUS_0A',
 TOLERANCE='20%',
 MATERIAL='X6S',
 VOLTAGE='6.3V',
 VALUE='DIFF BUS_0.22UF',
 PRIM_FILE='./archive_libs/logical/q_cap_diffbus/chips/chips.prt';

PART_NAME
 C927 'Q_CAP_DIFFBUS_C0201-DIFF BUS_0A':;

SECTION_NUMBER 1
 '@S9S_MB_2U_LIB.S9S_MB_2U(SCH_1):PAGE164_I27@PURE_QUANTA.Q_CAP_DIFFBUS(CHIPS)':
 C_PATH='@s9s_mb_2u_lib.s9s_mb_2u(sch_1):page164_i27@pure_quanta.q_cap_diffbus(c~
hips)',
 P_PATH='@s9s_mb_2u_lib.s9s_mb_2u(sch_1):page173_i27@pure_quanta.q_cap_diffbus(c~
hips)',
 PATH='I27',
 DRAWING='@S9S_MB_2U_LIB.S9S_MB_2U(SCH_1):PAGE164',
 PIN_NAMES_ROTATE='TRUE',
 PHYS_PAGE='173',
 XY='(-575,925)',
 ROT='2',
 VER='2',
 PACK_TYPE='C0201',
 CDS_LIB='pure_quanta',
 CDS_PART_NAME='Q_CAP_DIFFBUS_C0201-DIFF BUS_0A',
 TOLERANCE='20%',
 MATERIAL='X6S',
 VOLTAGE='6.3V',
 VALUE='DIFF BUS_0.22UF',
 PRIM_FILE='./archive_libs/logical/q_cap_diffbus/chips/chips.prt';

PART_NAME
 C928 'Q_CAP_DIFFBUS_C0201-DIFF BUS_0A':;

SECTION_NUMBER 1
 '@S9S_MB_2U_LIB.S9S_MB_2U(SCH_1):PAGE164_I25@PURE_QUANTA.Q_CAP_DIFFBUS(CHIPS)':
 C_PATH='@s9s_mb_2u_lib.s9s_mb_2u(sch_1):page164_i25@pure_quanta.q_cap_diffbus(c~
hips)',
 P_PATH='@s9s_mb_2u_lib.s9s_mb_2u(sch_1):page173_i25@pure_quanta.q_cap_diffbus(c~
hips)',
 PATH='I25',
 DRAWING='@S9S_MB_2U_LIB.S9S_MB_2U(SCH_1):PAGE164',
 PIN_NAMES_ROTATE='TRUE',
 PHYS_PAGE='173',
 XY='(-575,775)',
 ROT='2',
 VER='2',
 PACK_TYPE='C0201',
 CDS_LIB='pure_quanta',
 CDS_PART_NAME='Q_CAP_DIFFBUS_C0201-DIFF BUS_0A',
 TOLERANCE='20%',
 MATERIAL='X6S',
 VOLTAGE='6.3V',
 VALUE='DIFF BUS_0.22UF',
 PRIM_FILE='./archive_libs/logical/q_cap_diffbus/chips/chips.prt';

PART_NAME
 C929 'Q_CAP_DIFFBUS_C0201-DIFF BUS_0A':;

SECTION_NUMBER 1
 '@S9S_MB_2U_LIB.S9S_MB_2U(SCH_1):PAGE164_I26@PURE_QUANTA.Q_CAP_DIFFBUS(CHIPS)':
 C_PATH='@s9s_mb_2u_lib.s9s_mb_2u(sch_1):page164_i26@pure_quanta.q_cap_diffbus(c~
hips)',
 P_PATH='@s9s_mb_2u_lib.s9s_mb_2u(sch_1):page173_i26@pure_quanta.q_cap_diffbus(c~
hips)',
 PATH='I26',
 DRAWING='@S9S_MB_2U_LIB.S9S_MB_2U(SCH_1):PAGE164',
 PIN_NAMES_ROTATE='TRUE',
 PHYS_PAGE='173',
 XY='(-575,725)',
 ROT='2',
 VER='2',
 PACK_TYPE='C0201',
 CDS_LIB='pure_quanta',
 CDS_PART_NAME='Q_CAP_DIFFBUS_C0201-DIFF BUS_0A',
 TOLERANCE='20%',
 MATERIAL='X6S',
 VOLTAGE='6.3V',
 VALUE='DIFF BUS_0.22UF',
 PRIM_FILE='./archive_libs/logical/q_cap_diffbus/chips/chips.prt';

PART_NAME
 C930 'Q_CAP_DIFFBUS_C0201-DIFF BUS_0A':;

SECTION_NUMBER 1
 '@S9S_MB_2U_LIB.S9S_MB_2U(SCH_1):PAGE164_I24@PURE_QUANTA.Q_CAP_DIFFBUS(CHIPS)':
 C_PATH='@s9s_mb_2u_lib.s9s_mb_2u(sch_1):page164_i24@pure_quanta.q_cap_diffbus(c~
hips)',
 P_PATH='@s9s_mb_2u_lib.s9s_mb_2u(sch_1):page173_i24@pure_quanta.q_cap_diffbus(c~
hips)',
 PATH='I24',
 DRAWING='@S9S_MB_2U_LIB.S9S_MB_2U(SCH_1):PAGE164',
 PIN_NAMES_ROTATE='TRUE',
 PHYS_PAGE='173',
 XY='(-575,575)',
 ROT='2',
 VER='2',
 PACK_TYPE='C0201',
 CDS_LIB='pure_quanta',
 CDS_PART_NAME='Q_CAP_DIFFBUS_C0201-DIFF BUS_0A',
 TOLERANCE='20%',
 MATERIAL='X6S',
 VOLTAGE='6.3V',
 VALUE='DIFF BUS_0.22UF',
 PRIM_FILE='./archive_libs/logical/q_cap_diffbus/chips/chips.prt';

PART_NAME
 C931 'Q_CAP_DIFFBUS_C0201-DIFF BUS_0A':;

SECTION_NUMBER 1
 '@S9S_MB_2U_LIB.S9S_MB_2U(SCH_1):PAGE164_I23@PURE_QUANTA.Q_CAP_DIFFBUS(CHIPS)':
 C_PATH='@s9s_mb_2u_lib.s9s_mb_2u(sch_1):page164_i23@pure_quanta.q_cap_diffbus(c~
hips)',
 P_PATH='@s9s_mb_2u_lib.s9s_mb_2u(sch_1):page173_i23@pure_quanta.q_cap_diffbus(c~
hips)',
 PATH='I23',
 DRAWING='@S9S_MB_2U_LIB.S9S_MB_2U(SCH_1):PAGE164',
 PIN_NAMES_ROTATE='TRUE',
 PHYS_PAGE='173',
 XY='(-575,525)',
 ROT='2',
 VER='2',
 PACK_TYPE='C0201',
 CDS_LIB='pure_quanta',
 CDS_PART_NAME='Q_CAP_DIFFBUS_C0201-DIFF BUS_0A',
 TOLERANCE='20%',
 MATERIAL='X6S',
 VOLTAGE='6.3V',
 VALUE='DIFF BUS_0.22UF',
 PRIM_FILE='./archive_libs/logical/q_cap_diffbus/chips/chips.prt';

PART_NAME
 C932 'Q_CAP_DIFFBUS_C0201-DIFF BUS_0A':;

SECTION_NUMBER 1
 '@S9S_MB_2U_LIB.S9S_MB_2U(SCH_1):PAGE164_I21@PURE_QUANTA.Q_CAP_DIFFBUS(CHIPS)':
 C_PATH='@s9s_mb_2u_lib.s9s_mb_2u(sch_1):page164_i21@pure_quanta.q_cap_diffbus(c~
hips)',
 P_PATH='@s9s_mb_2u_lib.s9s_mb_2u(sch_1):page173_i21@pure_quanta.q_cap_diffbus(c~
hips)',
 PATH='I21',
 DRAWING='@S9S_MB_2U_LIB.S9S_MB_2U(SCH_1):PAGE164',
 PIN_NAMES_ROTATE='TRUE',
 PHYS_PAGE='173',
 XY='(-575,375)',
 ROT='2',
 VER='2',
 PACK_TYPE='C0201',
 CDS_LIB='pure_quanta',
 CDS_PART_NAME='Q_CAP_DIFFBUS_C0201-DIFF BUS_0A',
 TOLERANCE='20%',
 MATERIAL='X6S',
 VOLTAGE='6.3V',
 VALUE='DIFF BUS_0.22UF',
 PRIM_FILE='./archive_libs/logical/q_cap_diffbus/chips/chips.prt';

PART_NAME
 C933 'Q_CAP_DIFFBUS_C0201-DIFF BUS_0A':;

SECTION_NUMBER 1
 '@S9S_MB_2U_LIB.S9S_MB_2U(SCH_1):PAGE164_I22@PURE_QUANTA.Q_CAP_DIFFBUS(CHIPS)':
 C_PATH='@s9s_mb_2u_lib.s9s_mb_2u(sch_1):page164_i22@pure_quanta.q_cap_diffbus(c~
hips)',
 P_PATH='@s9s_mb_2u_lib.s9s_mb_2u(sch_1):page173_i22@pure_quanta.q_cap_diffbus(c~
hips)',
 PATH='I22',
 DRAWING='@S9S_MB_2U_LIB.S9S_MB_2U(SCH_1):PAGE164',
 PIN_NAMES_ROTATE='TRUE',
 PHYS_PAGE='173',
 XY='(-575,325)',
 ROT='2',
 VER='2',
 PACK_TYPE='C0201',
 CDS_LIB='pure_quanta',
 CDS_PART_NAME='Q_CAP_DIFFBUS_C0201-DIFF BUS_0A',
 TOLERANCE='20%',
 MATERIAL='X6S',
 VOLTAGE='6.3V',
 VALUE='DIFF BUS_0.22UF',
 PRIM_FILE='./archive_libs/logical/q_cap_diffbus/chips/chips.prt';

PART_NAME
 C934 'Q_CAP_DIFFBUS_C0201-DIFF BUS_0A':;

SECTION_NUMBER 1
 '@S9S_MB_2U_LIB.S9S_MB_2U(SCH_1):PAGE164_I169@PURE_QUANTA.Q_CAP_DIFFBUS(CHIPS)':
 C_PATH='@s9s_mb_2u_lib.s9s_mb_2u(sch_1):page164_i169@pure_quanta.q_cap_diffbus(~
chips)',
 P_PATH='@s9s_mb_2u_lib.s9s_mb_2u(sch_1):page173_i169@pure_quanta.q_cap_diffbus(~
chips)',
 PATH='I169',
 DRAWING='@S9S_MB_2U_LIB.S9S_MB_2U(SCH_1):PAGE164',
 PIN_NAMES_ROTATE='TRUE',
 PHYS_PAGE='173',
 XY='(3975,3750)',
 ROT='2',
 VER='2',
 PACK_TYPE='C0201',
 CDS_LIB='pure_quanta',
 CDS_PART_NAME='Q_CAP_DIFFBUS_C0201-DIFF BUS_0A',
 TOLERANCE='20%',
 MATERIAL='X6S',
 VOLTAGE='6.3V',
 VALUE='DIFF BUS_0.22UF',
 PRIM_FILE='./archive_libs/logical/q_cap_diffbus/chips/chips.prt';

PART_NAME
 C935 'Q_CAP_DIFFBUS_C0201-DIFF BUS_0A':;

SECTION_NUMBER 1
 '@S9S_MB_2U_LIB.S9S_MB_2U(SCH_1):PAGE164_I168@PURE_QUANTA.Q_CAP_DIFFBUS(CHIPS)':
 C_PATH='@s9s_mb_2u_lib.s9s_mb_2u(sch_1):page164_i168@pure_quanta.q_cap_diffbus(~
chips)',
 P_PATH='@s9s_mb_2u_lib.s9s_mb_2u(sch_1):page173_i168@pure_quanta.q_cap_diffbus(~
chips)',
 PATH='I168',
 DRAWING='@S9S_MB_2U_LIB.S9S_MB_2U(SCH_1):PAGE164',
 PIN_NAMES_ROTATE='TRUE',
 PHYS_PAGE='173',
 XY='(3975,3700)',
 ROT='2',
 VER='2',
 PACK_TYPE='C0201',
 CDS_LIB='pure_quanta',
 CDS_PART_NAME='Q_CAP_DIFFBUS_C0201-DIFF BUS_0A',
 TOLERANCE='20%',
 MATERIAL='X6S',
 VOLTAGE='6.3V',
 VALUE='DIFF BUS_0.22UF',
 PRIM_FILE='./archive_libs/logical/q_cap_diffbus/chips/chips.prt';

PART_NAME
 C936 'Q_CAP_DIFFBUS_C0201-DIFF BUS_0A':;

SECTION_NUMBER 1
 '@S9S_MB_2U_LIB.S9S_MB_2U(SCH_1):PAGE164_I167@PURE_QUANTA.Q_CAP_DIFFBUS(CHIPS)':
 C_PATH='@s9s_mb_2u_lib.s9s_mb_2u(sch_1):page164_i167@pure_quanta.q_cap_diffbus(~
chips)',
 P_PATH='@s9s_mb_2u_lib.s9s_mb_2u(sch_1):page173_i167@pure_quanta.q_cap_diffbus(~
chips)',
 PATH='I167',
 DRAWING='@S9S_MB_2U_LIB.S9S_MB_2U(SCH_1):PAGE164',
 PIN_NAMES_ROTATE='TRUE',
 PHYS_PAGE='173',
 XY='(3975,3550)',
 ROT='2',
 VER='2',
 PACK_TYPE='C0201',
 CDS_LIB='pure_quanta',
 CDS_PART_NAME='Q_CAP_DIFFBUS_C0201-DIFF BUS_0A',
 TOLERANCE='20%',
 MATERIAL='X6S',
 VOLTAGE='6.3V',
 VALUE='DIFF BUS_0.22UF',
 PRIM_FILE='./archive_libs/logical/q_cap_diffbus/chips/chips.prt';

PART_NAME
 C937 'Q_CAP_DIFFBUS_C0201-DIFF BUS_0A':;

SECTION_NUMBER 1
 '@S9S_MB_2U_LIB.S9S_MB_2U(SCH_1):PAGE164_I166@PURE_QUANTA.Q_CAP_DIFFBUS(CHIPS)':
 C_PATH='@s9s_mb_2u_lib.s9s_mb_2u(sch_1):page164_i166@pure_quanta.q_cap_diffbus(~
chips)',
 P_PATH='@s9s_mb_2u_lib.s9s_mb_2u(sch_1):page173_i166@pure_quanta.q_cap_diffbus(~
chips)',
 PATH='I166',
 DRAWING='@S9S_MB_2U_LIB.S9S_MB_2U(SCH_1):PAGE164',
 PIN_NAMES_ROTATE='TRUE',
 PHYS_PAGE='173',
 XY='(3975,3500)',
 ROT='2',
 VER='2',
 PACK_TYPE='C0201',
 CDS_LIB='pure_quanta',
 CDS_PART_NAME='Q_CAP_DIFFBUS_C0201-DIFF BUS_0A',
 TOLERANCE='20%',
 MATERIAL='X6S',
 VOLTAGE='6.3V',
 VALUE='DIFF BUS_0.22UF',
 PRIM_FILE='./archive_libs/logical/q_cap_diffbus/chips/chips.prt';

PART_NAME
 C938 'Q_CAP_DIFFBUS_C0201-DIFF BUS_0A':;

SECTION_NUMBER 1
 '@S9S_MB_2U_LIB.S9S_MB_2U(SCH_1):PAGE164_I165@PURE_QUANTA.Q_CAP_DIFFBUS(CHIPS)':
 C_PATH='@s9s_mb_2u_lib.s9s_mb_2u(sch_1):page164_i165@pure_quanta.q_cap_diffbus(~
chips)',
 P_PATH='@s9s_mb_2u_lib.s9s_mb_2u(sch_1):page173_i165@pure_quanta.q_cap_diffbus(~
chips)',
 PATH='I165',
 DRAWING='@S9S_MB_2U_LIB.S9S_MB_2U(SCH_1):PAGE164',
 PIN_NAMES_ROTATE='TRUE',
 PHYS_PAGE='173',
 XY='(3975,3350)',
 ROT='2',
 VER='2',
 PACK_TYPE='C0201',
 CDS_LIB='pure_quanta',
 CDS_PART_NAME='Q_CAP_DIFFBUS_C0201-DIFF BUS_0A',
 TOLERANCE='20%',
 MATERIAL='X6S',
 VOLTAGE='6.3V',
 VALUE='DIFF BUS_0.22UF',
 PRIM_FILE='./archive_libs/logical/q_cap_diffbus/chips/chips.prt';

PART_NAME
 C939 'Q_CAP_DIFFBUS_C0201-DIFF BUS_0A':;

SECTION_NUMBER 1
 '@S9S_MB_2U_LIB.S9S_MB_2U(SCH_1):PAGE164_I164@PURE_QUANTA.Q_CAP_DIFFBUS(CHIPS)':
 C_PATH='@s9s_mb_2u_lib.s9s_mb_2u(sch_1):page164_i164@pure_quanta.q_cap_diffbus(~
chips)',
 P_PATH='@s9s_mb_2u_lib.s9s_mb_2u(sch_1):page173_i164@pure_quanta.q_cap_diffbus(~
chips)',
 PATH='I164',
 DRAWING='@S9S_MB_2U_LIB.S9S_MB_2U(SCH_1):PAGE164',
 PIN_NAMES_ROTATE='TRUE',
 PHYS_PAGE='173',
 XY='(3975,3300)',
 ROT='2',
 VER='2',
 PACK_TYPE='C0201',
 CDS_LIB='pure_quanta',
 CDS_PART_NAME='Q_CAP_DIFFBUS_C0201-DIFF BUS_0A',
 TOLERANCE='20%',
 MATERIAL='X6S',
 VOLTAGE='6.3V',
 VALUE='DIFF BUS_0.22UF',
 PRIM_FILE='./archive_libs/logical/q_cap_diffbus/chips/chips.prt';

PART_NAME
 C940 'Q_CAP_DIFFBUS_C0201-DIFF BUS_0A':;

SECTION_NUMBER 1
 '@S9S_MB_2U_LIB.S9S_MB_2U(SCH_1):PAGE164_I160@PURE_QUANTA.Q_CAP_DIFFBUS(CHIPS)':
 C_PATH='@s9s_mb_2u_lib.s9s_mb_2u(sch_1):page164_i160@pure_quanta.q_cap_diffbus(~
chips)',
 P_PATH='@s9s_mb_2u_lib.s9s_mb_2u(sch_1):page173_i160@pure_quanta.q_cap_diffbus(~
chips)',
 PATH='I160',
 DRAWING='@S9S_MB_2U_LIB.S9S_MB_2U(SCH_1):PAGE164',
 PIN_NAMES_ROTATE='TRUE',
 PHYS_PAGE='173',
 XY='(3975,3150)',
 ROT='2',
 VER='2',
 PACK_TYPE='C0201',
 CDS_LIB='pure_quanta',
 CDS_PART_NAME='Q_CAP_DIFFBUS_C0201-DIFF BUS_0A',
 TOLERANCE='20%',
 MATERIAL='X6S',
 VOLTAGE='6.3V',
 VALUE='DIFF BUS_0.22UF',
 PRIM_FILE='./archive_libs/logical/q_cap_diffbus/chips/chips.prt';

PART_NAME
 C941 'Q_CAP_DIFFBUS_C0201-DIFF BUS_0A':;

SECTION_NUMBER 1
 '@S9S_MB_2U_LIB.S9S_MB_2U(SCH_1):PAGE164_I159@PURE_QUANTA.Q_CAP_DIFFBUS(CHIPS)':
 C_PATH='@s9s_mb_2u_lib.s9s_mb_2u(sch_1):page164_i159@pure_quanta.q_cap_diffbus(~
chips)',
 P_PATH='@s9s_mb_2u_lib.s9s_mb_2u(sch_1):page173_i159@pure_quanta.q_cap_diffbus(~
chips)',
 PATH='I159',
 DRAWING='@S9S_MB_2U_LIB.S9S_MB_2U(SCH_1):PAGE164',
 PIN_NAMES_ROTATE='TRUE',
 PHYS_PAGE='173',
 XY='(3975,3100)',
 ROT='2',
 VER='2',
 PACK_TYPE='C0201',
 CDS_LIB='pure_quanta',
 CDS_PART_NAME='Q_CAP_DIFFBUS_C0201-DIFF BUS_0A',
 TOLERANCE='20%',
 MATERIAL='X6S',
 VOLTAGE='6.3V',
 VALUE='DIFF BUS_0.22UF',
 PRIM_FILE='./archive_libs/logical/q_cap_diffbus/chips/chips.prt';

PART_NAME
 C942 'Q_CAP_DIFFBUS_C0201-DIFF BUS_0A':;

SECTION_NUMBER 1
 '@S9S_MB_2U_LIB.S9S_MB_2U(SCH_1):PAGE164_I158@PURE_QUANTA.Q_CAP_DIFFBUS(CHIPS)':
 C_PATH='@s9s_mb_2u_lib.s9s_mb_2u(sch_1):page164_i158@pure_quanta.q_cap_diffbus(~
chips)',
 P_PATH='@s9s_mb_2u_lib.s9s_mb_2u(sch_1):page173_i158@pure_quanta.q_cap_diffbus(~
chips)',
 PATH='I158',
 DRAWING='@S9S_MB_2U_LIB.S9S_MB_2U(SCH_1):PAGE164',
 PIN_NAMES_ROTATE='TRUE',
 PHYS_PAGE='173',
 XY='(3975,2950)',
 ROT='2',
 VER='2',
 PACK_TYPE='C0201',
 CDS_LIB='pure_quanta',
 CDS_PART_NAME='Q_CAP_DIFFBUS_C0201-DIFF BUS_0A',
 TOLERANCE='20%',
 MATERIAL='X6S',
 VOLTAGE='6.3V',
 VALUE='DIFF BUS_0.22UF',
 PRIM_FILE='./archive_libs/logical/q_cap_diffbus/chips/chips.prt';

PART_NAME
 C943 'Q_CAP_DIFFBUS_C0201-DIFF BUS_0A':;

SECTION_NUMBER 1
 '@S9S_MB_2U_LIB.S9S_MB_2U(SCH_1):PAGE164_I157@PURE_QUANTA.Q_CAP_DIFFBUS(CHIPS)':
 C_PATH='@s9s_mb_2u_lib.s9s_mb_2u(sch_1):page164_i157@pure_quanta.q_cap_diffbus(~
chips)',
 P_PATH='@s9s_mb_2u_lib.s9s_mb_2u(sch_1):page173_i157@pure_quanta.q_cap_diffbus(~
chips)',
 PATH='I157',
 DRAWING='@S9S_MB_2U_LIB.S9S_MB_2U(SCH_1):PAGE164',
 PIN_NAMES_ROTATE='TRUE',
 PHYS_PAGE='173',
 XY='(3975,2900)',
 ROT='2',
 VER='2',
 PACK_TYPE='C0201',
 CDS_LIB='pure_quanta',
 CDS_PART_NAME='Q_CAP_DIFFBUS_C0201-DIFF BUS_0A',
 TOLERANCE='20%',
 MATERIAL='X6S',
 VOLTAGE='6.3V',
 VALUE='DIFF BUS_0.22UF',
 PRIM_FILE='./archive_libs/logical/q_cap_diffbus/chips/chips.prt';

PART_NAME
 C944 'Q_CAP_DIFFBUS_C0201-DIFF BUS_0A':;

SECTION_NUMBER 1
 '@S9S_MB_2U_LIB.S9S_MB_2U(SCH_1):PAGE164_I156@PURE_QUANTA.Q_CAP_DIFFBUS(CHIPS)':
 C_PATH='@s9s_mb_2u_lib.s9s_mb_2u(sch_1):page164_i156@pure_quanta.q_cap_diffbus(~
chips)',
 P_PATH='@s9s_mb_2u_lib.s9s_mb_2u(sch_1):page173_i156@pure_quanta.q_cap_diffbus(~
chips)',
 PATH='I156',
 DRAWING='@S9S_MB_2U_LIB.S9S_MB_2U(SCH_1):PAGE164',
 PIN_NAMES_ROTATE='TRUE',
 PHYS_PAGE='173',
 XY='(3975,2750)',
 ROT='2',
 VER='2',
 PACK_TYPE='C0201',
 CDS_LIB='pure_quanta',
 CDS_PART_NAME='Q_CAP_DIFFBUS_C0201-DIFF BUS_0A',
 TOLERANCE='20%',
 MATERIAL='X6S',
 VOLTAGE='6.3V',
 VALUE='DIFF BUS_0.22UF',
 PRIM_FILE='./archive_libs/logical/q_cap_diffbus/chips/chips.prt';

PART_NAME
 C945 'Q_CAP_DIFFBUS_C0201-DIFF BUS_0A':;

SECTION_NUMBER 1
 '@S9S_MB_2U_LIB.S9S_MB_2U(SCH_1):PAGE164_I155@PURE_QUANTA.Q_CAP_DIFFBUS(CHIPS)':
 C_PATH='@s9s_mb_2u_lib.s9s_mb_2u(sch_1):page164_i155@pure_quanta.q_cap_diffbus(~
chips)',
 P_PATH='@s9s_mb_2u_lib.s9s_mb_2u(sch_1):page173_i155@pure_quanta.q_cap_diffbus(~
chips)',
 PATH='I155',
 DRAWING='@S9S_MB_2U_LIB.S9S_MB_2U(SCH_1):PAGE164',
 PIN_NAMES_ROTATE='TRUE',
 PHYS_PAGE='173',
 XY='(3975,2700)',
 ROT='2',
 VER='2',
 PACK_TYPE='C0201',
 CDS_LIB='pure_quanta',
 CDS_PART_NAME='Q_CAP_DIFFBUS_C0201-DIFF BUS_0A',
 TOLERANCE='20%',
 MATERIAL='X6S',
 VOLTAGE='6.3V',
 VALUE='DIFF BUS_0.22UF',
 PRIM_FILE='./archive_libs/logical/q_cap_diffbus/chips/chips.prt';

PART_NAME
 C946 'Q_CAP_DIFFBUS_C0201-DIFF BUS_0A':;

SECTION_NUMBER 1
 '@S9S_MB_2U_LIB.S9S_MB_2U(SCH_1):PAGE164_I154@PURE_QUANTA.Q_CAP_DIFFBUS(CHIPS)':
 C_PATH='@s9s_mb_2u_lib.s9s_mb_2u(sch_1):page164_i154@pure_quanta.q_cap_diffbus(~
chips)',
 P_PATH='@s9s_mb_2u_lib.s9s_mb_2u(sch_1):page173_i154@pure_quanta.q_cap_diffbus(~
chips)',
 PATH='I154',
 DRAWING='@S9S_MB_2U_LIB.S9S_MB_2U(SCH_1):PAGE164',
 PIN_NAMES_ROTATE='TRUE',
 PHYS_PAGE='173',
 XY='(3975,2550)',
 ROT='2',
 VER='2',
 PACK_TYPE='C0201',
 CDS_LIB='pure_quanta',
 CDS_PART_NAME='Q_CAP_DIFFBUS_C0201-DIFF BUS_0A',
 TOLERANCE='20%',
 MATERIAL='X6S',
 VOLTAGE='6.3V',
 VALUE='DIFF BUS_0.22UF',
 PRIM_FILE='./archive_libs/logical/q_cap_diffbus/chips/chips.prt';

PART_NAME
 C947 'Q_CAP_DIFFBUS_C0201-DIFF BUS_0A':;

SECTION_NUMBER 1
 '@S9S_MB_2U_LIB.S9S_MB_2U(SCH_1):PAGE164_I153@PURE_QUANTA.Q_CAP_DIFFBUS(CHIPS)':
 C_PATH='@s9s_mb_2u_lib.s9s_mb_2u(sch_1):page164_i153@pure_quanta.q_cap_diffbus(~
chips)',
 P_PATH='@s9s_mb_2u_lib.s9s_mb_2u(sch_1):page173_i153@pure_quanta.q_cap_diffbus(~
chips)',
 PATH='I153',
 DRAWING='@S9S_MB_2U_LIB.S9S_MB_2U(SCH_1):PAGE164',
 PIN_NAMES_ROTATE='TRUE',
 PHYS_PAGE='173',
 XY='(3975,2500)',
 ROT='2',
 VER='2',
 PACK_TYPE='C0201',
 CDS_LIB='pure_quanta',
 CDS_PART_NAME='Q_CAP_DIFFBUS_C0201-DIFF BUS_0A',
 TOLERANCE='20%',
 MATERIAL='X6S',
 VOLTAGE='6.3V',
 VALUE='DIFF BUS_0.22UF',
 PRIM_FILE='./archive_libs/logical/q_cap_diffbus/chips/chips.prt';

PART_NAME
 C948 'Q_CAP_DIFFBUS_C0201-DIFF BUS_0A':;

SECTION_NUMBER 1
 '@S9S_MB_2U_LIB.S9S_MB_2U(SCH_1):PAGE164_I152@PURE_QUANTA.Q_CAP_DIFFBUS(CHIPS)':
 C_PATH='@s9s_mb_2u_lib.s9s_mb_2u(sch_1):page164_i152@pure_quanta.q_cap_diffbus(~
chips)',
 P_PATH='@s9s_mb_2u_lib.s9s_mb_2u(sch_1):page173_i152@pure_quanta.q_cap_diffbus(~
chips)',
 PATH='I152',
 DRAWING='@S9S_MB_2U_LIB.S9S_MB_2U(SCH_1):PAGE164',
 PIN_NAMES_ROTATE='TRUE',
 PHYS_PAGE='173',
 XY='(3975,2350)',
 ROT='2',
 VER='2',
 PACK_TYPE='C0201',
 CDS_LIB='pure_quanta',
 CDS_PART_NAME='Q_CAP_DIFFBUS_C0201-DIFF BUS_0A',
 TOLERANCE='20%',
 MATERIAL='X6S',
 VOLTAGE='6.3V',
 VALUE='DIFF BUS_0.22UF',
 PRIM_FILE='./archive_libs/logical/q_cap_diffbus/chips/chips.prt';

PART_NAME
 C949 'Q_CAP_DIFFBUS_C0201-DIFF BUS_0A':;

SECTION_NUMBER 1
 '@S9S_MB_2U_LIB.S9S_MB_2U(SCH_1):PAGE164_I151@PURE_QUANTA.Q_CAP_DIFFBUS(CHIPS)':
 C_PATH='@s9s_mb_2u_lib.s9s_mb_2u(sch_1):page164_i151@pure_quanta.q_cap_diffbus(~
chips)',
 P_PATH='@s9s_mb_2u_lib.s9s_mb_2u(sch_1):page173_i151@pure_quanta.q_cap_diffbus(~
chips)',
 PATH='I151',
 DRAWING='@S9S_MB_2U_LIB.S9S_MB_2U(SCH_1):PAGE164',
 PIN_NAMES_ROTATE='TRUE',
 PHYS_PAGE='173',
 XY='(3975,2300)',
 ROT='2',
 VER='2',
 PACK_TYPE='C0201',
 CDS_LIB='pure_quanta',
 CDS_PART_NAME='Q_CAP_DIFFBUS_C0201-DIFF BUS_0A',
 TOLERANCE='20%',
 MATERIAL='X6S',
 VOLTAGE='6.3V',
 VALUE='DIFF BUS_0.22UF',
 PRIM_FILE='./archive_libs/logical/q_cap_diffbus/chips/chips.prt';

PART_NAME
 C950 'Q_CAP_DIFFBUS_C0201-DIFF BUS_0A':;

SECTION_NUMBER 1
 '@S9S_MB_2U_LIB.S9S_MB_2U(SCH_1):PAGE164_I137@PURE_QUANTA.Q_CAP_DIFFBUS(CHIPS)':
 C_PATH='@s9s_mb_2u_lib.s9s_mb_2u(sch_1):page164_i137@pure_quanta.q_cap_diffbus(~
chips)',
 P_PATH='@s9s_mb_2u_lib.s9s_mb_2u(sch_1):page173_i137@pure_quanta.q_cap_diffbus(~
chips)',
 PATH='I137',
 DRAWING='@S9S_MB_2U_LIB.S9S_MB_2U(SCH_1):PAGE164',
 PIN_NAMES_ROTATE='TRUE',
 PHYS_PAGE='173',
 XY='(3975,1775)',
 ROT='2',
 VER='2',
 PACK_TYPE='C0201',
 CDS_LIB='pure_quanta',
 CDS_PART_NAME='Q_CAP_DIFFBUS_C0201-DIFF BUS_0A',
 TOLERANCE='20%',
 MATERIAL='X6S',
 VOLTAGE='6.3V',
 VALUE='DIFF BUS_0.22UF',
 PRIM_FILE='./archive_libs/logical/q_cap_diffbus/chips/chips.prt';

PART_NAME
 C951 'Q_CAP_DIFFBUS_C0201-DIFF BUS_0A':;

SECTION_NUMBER 1
 '@S9S_MB_2U_LIB.S9S_MB_2U(SCH_1):PAGE164_I136@PURE_QUANTA.Q_CAP_DIFFBUS(CHIPS)':
 C_PATH='@s9s_mb_2u_lib.s9s_mb_2u(sch_1):page164_i136@pure_quanta.q_cap_diffbus(~
chips)',
 P_PATH='@s9s_mb_2u_lib.s9s_mb_2u(sch_1):page173_i136@pure_quanta.q_cap_diffbus(~
chips)',
 PATH='I136',
 DRAWING='@S9S_MB_2U_LIB.S9S_MB_2U(SCH_1):PAGE164',
 PIN_NAMES_ROTATE='TRUE',
 PHYS_PAGE='173',
 XY='(3975,1725)',
 ROT='2',
 VER='2',
 PACK_TYPE='C0201',
 CDS_LIB='pure_quanta',
 CDS_PART_NAME='Q_CAP_DIFFBUS_C0201-DIFF BUS_0A',
 TOLERANCE='20%',
 MATERIAL='X6S',
 VOLTAGE='6.3V',
 VALUE='DIFF BUS_0.22UF',
 PRIM_FILE='./archive_libs/logical/q_cap_diffbus/chips/chips.prt';

PART_NAME
 C952 'Q_CAP_DIFFBUS_C0201-DIFF BUS_0A':;

SECTION_NUMBER 1
 '@S9S_MB_2U_LIB.S9S_MB_2U(SCH_1):PAGE164_I135@PURE_QUANTA.Q_CAP_DIFFBUS(CHIPS)':
 C_PATH='@s9s_mb_2u_lib.s9s_mb_2u(sch_1):page164_i135@pure_quanta.q_cap_diffbus(~
chips)',
 P_PATH='@s9s_mb_2u_lib.s9s_mb_2u(sch_1):page173_i135@pure_quanta.q_cap_diffbus(~
chips)',
 PATH='I135',
 DRAWING='@S9S_MB_2U_LIB.S9S_MB_2U(SCH_1):PAGE164',
 PIN_NAMES_ROTATE='TRUE',
 PHYS_PAGE='173',
 XY='(3975,1575)',
 ROT='2',
 VER='2',
 PACK_TYPE='C0201',
 CDS_LIB='pure_quanta',
 CDS_PART_NAME='Q_CAP_DIFFBUS_C0201-DIFF BUS_0A',
 TOLERANCE='20%',
 MATERIAL='X6S',
 VOLTAGE='6.3V',
 VALUE='DIFF BUS_0.22UF',
 PRIM_FILE='./archive_libs/logical/q_cap_diffbus/chips/chips.prt';

PART_NAME
 C953 'Q_CAP_DIFFBUS_C0201-DIFF BUS_0A':;

SECTION_NUMBER 1
 '@S9S_MB_2U_LIB.S9S_MB_2U(SCH_1):PAGE164_I134@PURE_QUANTA.Q_CAP_DIFFBUS(CHIPS)':
 C_PATH='@s9s_mb_2u_lib.s9s_mb_2u(sch_1):page164_i134@pure_quanta.q_cap_diffbus(~
chips)',
 P_PATH='@s9s_mb_2u_lib.s9s_mb_2u(sch_1):page173_i134@pure_quanta.q_cap_diffbus(~
chips)',
 PATH='I134',
 DRAWING='@S9S_MB_2U_LIB.S9S_MB_2U(SCH_1):PAGE164',
 PIN_NAMES_ROTATE='TRUE',
 PHYS_PAGE='173',
 XY='(3975,1525)',
 ROT='2',
 VER='2',
 PACK_TYPE='C0201',
 CDS_LIB='pure_quanta',
 CDS_PART_NAME='Q_CAP_DIFFBUS_C0201-DIFF BUS_0A',
 TOLERANCE='20%',
 MATERIAL='X6S',
 VOLTAGE='6.3V',
 VALUE='DIFF BUS_0.22UF',
 PRIM_FILE='./archive_libs/logical/q_cap_diffbus/chips/chips.prt';

PART_NAME
 C954 'Q_CAP_DIFFBUS_C0201-DIFF BUS_0A':;

SECTION_NUMBER 1
 '@S9S_MB_2U_LIB.S9S_MB_2U(SCH_1):PAGE164_I133@PURE_QUANTA.Q_CAP_DIFFBUS(CHIPS)':
 C_PATH='@s9s_mb_2u_lib.s9s_mb_2u(sch_1):page164_i133@pure_quanta.q_cap_diffbus(~
chips)',
 P_PATH='@s9s_mb_2u_lib.s9s_mb_2u(sch_1):page173_i133@pure_quanta.q_cap_diffbus(~
chips)',
 PATH='I133',
 DRAWING='@S9S_MB_2U_LIB.S9S_MB_2U(SCH_1):PAGE164',
 PIN_NAMES_ROTATE='TRUE',
 PHYS_PAGE='173',
 XY='(3975,1375)',
 ROT='2',
 VER='2',
 PACK_TYPE='C0201',
 CDS_LIB='pure_quanta',
 CDS_PART_NAME='Q_CAP_DIFFBUS_C0201-DIFF BUS_0A',
 TOLERANCE='20%',
 MATERIAL='X6S',
 VOLTAGE='6.3V',
 VALUE='DIFF BUS_0.22UF',
 PRIM_FILE='./archive_libs/logical/q_cap_diffbus/chips/chips.prt';

PART_NAME
 C955 'Q_CAP_DIFFBUS_C0201-DIFF BUS_0A':;

SECTION_NUMBER 1
 '@S9S_MB_2U_LIB.S9S_MB_2U(SCH_1):PAGE164_I208@PURE_QUANTA.Q_CAP_DIFFBUS(CHIPS)':
 C_PATH='@s9s_mb_2u_lib.s9s_mb_2u(sch_1):page164_i208@pure_quanta.q_cap_diffbus(~
chips)',
 P_PATH='@s9s_mb_2u_lib.s9s_mb_2u(sch_1):page173_i208@pure_quanta.q_cap_diffbus(~
chips)',
 PATH='I208',
 DRAWING='@S9S_MB_2U_LIB.S9S_MB_2U(SCH_1):PAGE164',
 PIN_NAMES_ROTATE='TRUE',
 PHYS_PAGE='173',
 XY='(3975,1325)',
 ROT='2',
 VER='2',
 PACK_TYPE='C0201',
 CDS_LIB='pure_quanta',
 CDS_PART_NAME='Q_CAP_DIFFBUS_C0201-DIFF BUS_0A',
 TOLERANCE='20%',
 MATERIAL='X6S',
 VOLTAGE='6.3V',
 VALUE='DIFF BUS_0.22UF',
 PRIM_FILE='./archive_libs/logical/q_cap_diffbus/chips/chips.prt';

PART_NAME
 C956 'Q_CAP_DIFFBUS_C0201-DIFF BUS_0A':;

SECTION_NUMBER 1
 '@S9S_MB_2U_LIB.S9S_MB_2U(SCH_1):PAGE164_I207@PURE_QUANTA.Q_CAP_DIFFBUS(CHIPS)':
 C_PATH='@s9s_mb_2u_lib.s9s_mb_2u(sch_1):page164_i207@pure_quanta.q_cap_diffbus(~
chips)',
 P_PATH='@s9s_mb_2u_lib.s9s_mb_2u(sch_1):page173_i207@pure_quanta.q_cap_diffbus(~
chips)',
 PATH='I207',
 DRAWING='@S9S_MB_2U_LIB.S9S_MB_2U(SCH_1):PAGE164',
 PIN_NAMES_ROTATE='TRUE',
 PHYS_PAGE='173',
 XY='(3975,1175)',
 ROT='2',
 VER='2',
 PACK_TYPE='C0201',
 CDS_LIB='pure_quanta',
 CDS_PART_NAME='Q_CAP_DIFFBUS_C0201-DIFF BUS_0A',
 TOLERANCE='20%',
 MATERIAL='X6S',
 VOLTAGE='6.3V',
 VALUE='DIFF BUS_0.22UF',
 PRIM_FILE='./archive_libs/logical/q_cap_diffbus/chips/chips.prt';

PART_NAME
 C957 'Q_CAP_DIFFBUS_C0201-DIFF BUS_0A':;

SECTION_NUMBER 1
 '@S9S_MB_2U_LIB.S9S_MB_2U(SCH_1):PAGE164_I206@PURE_QUANTA.Q_CAP_DIFFBUS(CHIPS)':
 C_PATH='@s9s_mb_2u_lib.s9s_mb_2u(sch_1):page164_i206@pure_quanta.q_cap_diffbus(~
chips)',
 P_PATH='@s9s_mb_2u_lib.s9s_mb_2u(sch_1):page173_i206@pure_quanta.q_cap_diffbus(~
chips)',
 PATH='I206',
 DRAWING='@S9S_MB_2U_LIB.S9S_MB_2U(SCH_1):PAGE164',
 PIN_NAMES_ROTATE='TRUE',
 PHYS_PAGE='173',
 XY='(3975,1125)',
 ROT='2',
 VER='2',
 PACK_TYPE='C0201',
 CDS_LIB='pure_quanta',
 CDS_PART_NAME='Q_CAP_DIFFBUS_C0201-DIFF BUS_0A',
 TOLERANCE='20%',
 MATERIAL='X6S',
 VOLTAGE='6.3V',
 VALUE='DIFF BUS_0.22UF',
 PRIM_FILE='./archive_libs/logical/q_cap_diffbus/chips/chips.prt';

PART_NAME
 C958 'Q_CAP_DIFFBUS_C0201-DIFF BUS_0A':;

SECTION_NUMBER 1
 '@S9S_MB_2U_LIB.S9S_MB_2U(SCH_1):PAGE164_I128@PURE_QUANTA.Q_CAP_DIFFBUS(CHIPS)':
 C_PATH='@s9s_mb_2u_lib.s9s_mb_2u(sch_1):page164_i128@pure_quanta.q_cap_diffbus(~
chips)',
 P_PATH='@s9s_mb_2u_lib.s9s_mb_2u(sch_1):page173_i128@pure_quanta.q_cap_diffbus(~
chips)',
 PATH='I128',
 DRAWING='@S9S_MB_2U_LIB.S9S_MB_2U(SCH_1):PAGE164',
 PIN_NAMES_ROTATE='TRUE',
 PHYS_PAGE='173',
 XY='(3975,975)',
 ROT='2',
 VER='2',
 PACK_TYPE='C0201',
 CDS_LIB='pure_quanta',
 CDS_PART_NAME='Q_CAP_DIFFBUS_C0201-DIFF BUS_0A',
 TOLERANCE='20%',
 MATERIAL='X6S',
 VOLTAGE='6.3V',
 VALUE='DIFF BUS_0.22UF',
 PRIM_FILE='./archive_libs/logical/q_cap_diffbus/chips/chips.prt';

PART_NAME
 C959 'Q_CAP_DIFFBUS_C0201-DIFF BUS_0A':;

SECTION_NUMBER 1
 '@S9S_MB_2U_LIB.S9S_MB_2U(SCH_1):PAGE164_I127@PURE_QUANTA.Q_CAP_DIFFBUS(CHIPS)':
 C_PATH='@s9s_mb_2u_lib.s9s_mb_2u(sch_1):page164_i127@pure_quanta.q_cap_diffbus(~
chips)',
 P_PATH='@s9s_mb_2u_lib.s9s_mb_2u(sch_1):page173_i127@pure_quanta.q_cap_diffbus(~
chips)',
 PATH='I127',
 DRAWING='@S9S_MB_2U_LIB.S9S_MB_2U(SCH_1):PAGE164',
 PIN_NAMES_ROTATE='TRUE',
 PHYS_PAGE='173',
 XY='(3975,925)',
 ROT='2',
 VER='2',
 PACK_TYPE='C0201',
 CDS_LIB='pure_quanta',
 CDS_PART_NAME='Q_CAP_DIFFBUS_C0201-DIFF BUS_0A',
 TOLERANCE='20%',
 MATERIAL='X6S',
 VOLTAGE='6.3V',
 VALUE='DIFF BUS_0.22UF',
 PRIM_FILE='./archive_libs/logical/q_cap_diffbus/chips/chips.prt';

PART_NAME
 C960 'Q_CAP_DIFFBUS_C0201-DIFF BUS_0A':;

SECTION_NUMBER 1
 '@S9S_MB_2U_LIB.S9S_MB_2U(SCH_1):PAGE164_I126@PURE_QUANTA.Q_CAP_DIFFBUS(CHIPS)':
 C_PATH='@s9s_mb_2u_lib.s9s_mb_2u(sch_1):page164_i126@pure_quanta.q_cap_diffbus(~
chips)',
 P_PATH='@s9s_mb_2u_lib.s9s_mb_2u(sch_1):page173_i126@pure_quanta.q_cap_diffbus(~
chips)',
 PATH='I126',
 DRAWING='@S9S_MB_2U_LIB.S9S_MB_2U(SCH_1):PAGE164',
 PIN_NAMES_ROTATE='TRUE',
 PHYS_PAGE='173',
 XY='(3975,775)',
 ROT='2',
 VER='2',
 PACK_TYPE='C0201',
 CDS_LIB='pure_quanta',
 CDS_PART_NAME='Q_CAP_DIFFBUS_C0201-DIFF BUS_0A',
 TOLERANCE='20%',
 MATERIAL='X6S',
 VOLTAGE='6.3V',
 VALUE='DIFF BUS_0.22UF',
 PRIM_FILE='./archive_libs/logical/q_cap_diffbus/chips/chips.prt';

PART_NAME
 C961 'Q_CAP_DIFFBUS_C0201-DIFF BUS_0A':;

SECTION_NUMBER 1
 '@S9S_MB_2U_LIB.S9S_MB_2U(SCH_1):PAGE164_I125@PURE_QUANTA.Q_CAP_DIFFBUS(CHIPS)':
 C_PATH='@s9s_mb_2u_lib.s9s_mb_2u(sch_1):page164_i125@pure_quanta.q_cap_diffbus(~
chips)',
 P_PATH='@s9s_mb_2u_lib.s9s_mb_2u(sch_1):page173_i125@pure_quanta.q_cap_diffbus(~
chips)',
 PATH='I125',
 DRAWING='@S9S_MB_2U_LIB.S9S_MB_2U(SCH_1):PAGE164',
 PIN_NAMES_ROTATE='TRUE',
 PHYS_PAGE='173',
 XY='(3975,725)',
 ROT='2',
 VER='2',
 PACK_TYPE='C0201',
 CDS_LIB='pure_quanta',
 CDS_PART_NAME='Q_CAP_DIFFBUS_C0201-DIFF BUS_0A',
 TOLERANCE='20%',
 MATERIAL='X6S',
 VOLTAGE='6.3V',
 VALUE='DIFF BUS_0.22UF',
 PRIM_FILE='./archive_libs/logical/q_cap_diffbus/chips/chips.prt';

PART_NAME
 C962 'Q_CAP_DIFFBUS_C0201-DIFF BUS_0A':;

SECTION_NUMBER 1
 '@S9S_MB_2U_LIB.S9S_MB_2U(SCH_1):PAGE164_I124@PURE_QUANTA.Q_CAP_DIFFBUS(CHIPS)':
 C_PATH='@s9s_mb_2u_lib.s9s_mb_2u(sch_1):page164_i124@pure_quanta.q_cap_diffbus(~
chips)',
 P_PATH='@s9s_mb_2u_lib.s9s_mb_2u(sch_1):page173_i124@pure_quanta.q_cap_diffbus(~
chips)',
 PATH='I124',
 DRAWING='@S9S_MB_2U_LIB.S9S_MB_2U(SCH_1):PAGE164',
 PIN_NAMES_ROTATE='TRUE',
 PHYS_PAGE='173',
 XY='(3975,575)',
 ROT='2',
 VER='2',
 PACK_TYPE='C0201',
 CDS_LIB='pure_quanta',
 CDS_PART_NAME='Q_CAP_DIFFBUS_C0201-DIFF BUS_0A',
 TOLERANCE='20%',
 MATERIAL='X6S',
 VOLTAGE='6.3V',
 VALUE='DIFF BUS_0.22UF',
 PRIM_FILE='./archive_libs/logical/q_cap_diffbus/chips/chips.prt';

PART_NAME
 C963 'Q_CAP_DIFFBUS_C0201-DIFF BUS_0A':;

SECTION_NUMBER 1
 '@S9S_MB_2U_LIB.S9S_MB_2U(SCH_1):PAGE164_I123@PURE_QUANTA.Q_CAP_DIFFBUS(CHIPS)':
 C_PATH='@s9s_mb_2u_lib.s9s_mb_2u(sch_1):page164_i123@pure_quanta.q_cap_diffbus(~
chips)',
 P_PATH='@s9s_mb_2u_lib.s9s_mb_2u(sch_1):page173_i123@pure_quanta.q_cap_diffbus(~
chips)',
 PATH='I123',
 DRAWING='@S9S_MB_2U_LIB.S9S_MB_2U(SCH_1):PAGE164',
 PIN_NAMES_ROTATE='TRUE',
 PHYS_PAGE='173',
 XY='(3975,525)',
 ROT='2',
 VER='2',
 PACK_TYPE='C0201',
 CDS_LIB='pure_quanta',
 CDS_PART_NAME='Q_CAP_DIFFBUS_C0201-DIFF BUS_0A',
 TOLERANCE='20%',
 MATERIAL='X6S',
 VOLTAGE='6.3V',
 VALUE='DIFF BUS_0.22UF',
 PRIM_FILE='./archive_libs/logical/q_cap_diffbus/chips/chips.prt';

PART_NAME
 C964 'Q_CAP_DIFFBUS_C0201-DIFF BUS_0A':;

SECTION_NUMBER 1
 '@S9S_MB_2U_LIB.S9S_MB_2U(SCH_1):PAGE164_I122@PURE_QUANTA.Q_CAP_DIFFBUS(CHIPS)':
 C_PATH='@s9s_mb_2u_lib.s9s_mb_2u(sch_1):page164_i122@pure_quanta.q_cap_diffbus(~
chips)',
 P_PATH='@s9s_mb_2u_lib.s9s_mb_2u(sch_1):page173_i122@pure_quanta.q_cap_diffbus(~
chips)',
 PATH='I122',
 DRAWING='@S9S_MB_2U_LIB.S9S_MB_2U(SCH_1):PAGE164',
 PIN_NAMES_ROTATE='TRUE',
 PHYS_PAGE='173',
 XY='(3975,375)',
 ROT='2',
 VER='2',
 PACK_TYPE='C0201',
 CDS_LIB='pure_quanta',
 CDS_PART_NAME='Q_CAP_DIFFBUS_C0201-DIFF BUS_0A',
 TOLERANCE='20%',
 MATERIAL='X6S',
 VOLTAGE='6.3V',
 VALUE='DIFF BUS_0.22UF',
 PRIM_FILE='./archive_libs/logical/q_cap_diffbus/chips/chips.prt';

PART_NAME
 C965 'Q_CAP_DIFFBUS_C0201-DIFF BUS_0A':;

SECTION_NUMBER 1
 '@S9S_MB_2U_LIB.S9S_MB_2U(SCH_1):PAGE164_I121@PURE_QUANTA.Q_CAP_DIFFBUS(CHIPS)':
 C_PATH='@s9s_mb_2u_lib.s9s_mb_2u(sch_1):page164_i121@pure_quanta.q_cap_diffbus(~
chips)',
 P_PATH='@s9s_mb_2u_lib.s9s_mb_2u(sch_1):page173_i121@pure_quanta.q_cap_diffbus(~
chips)',
 PATH='I121',
 DRAWING='@S9S_MB_2U_LIB.S9S_MB_2U(SCH_1):PAGE164',
 PIN_NAMES_ROTATE='TRUE',
 PHYS_PAGE='173',
 XY='(3975,325)',
 ROT='2',
 VER='2',
 PACK_TYPE='C0201',
 CDS_LIB='pure_quanta',
 CDS_PART_NAME='Q_CAP_DIFFBUS_C0201-DIFF BUS_0A',
 TOLERANCE='20%',
 MATERIAL='X6S',
 VOLTAGE='6.3V',
 VALUE='DIFF BUS_0.22UF',
 PRIM_FILE='./archive_libs/logical/q_cap_diffbus/chips/chips.prt';

PART_NAME
 C966 'Q_CAP_C0402-10UF,6.3V,20%,X6S,B':;

SECTION_NUMBER 1
 '@S9S_MB_2U_LIB.S9S_MB_2U(SCH_1):PAGE74_I27@PURE_QUANTA.Q_CAP(CHIPS)':
 C_PATH='@s9s_mb_2u_lib.s9s_mb_2u(sch_1):page74_i27@pure_quanta.q_cap(chips)',
 P_PATH='@s9s_mb_2u_lib.s9s_mb_2u(sch_1):page74_i27@pure_quanta.q_cap(chips)',
 PATH='I27',
 DRAWING='@S9S_MB_2U_LIB.S9S_MB_2U(SCH_1):PAGE74',
 PHYS_PAGE='74',
 XY='(-4275,3025)',
 ROT='0',
 VER='1',
 PACK_TYPE='C0402',
 CDS_LIB='pure_quanta',
 CDS_PART_NAME='Q_CAP_C0402-10UF,6.3V,20%,X6S,B',
 TOLERANCE='20%',
 MATERIAL='X6S',
 VOLTAGE='6.3V',
 VALUE='10UF',
 PRIM_FILE='./archive_libs/logical/q_cap/chips/chips.prt';

PART_NAME
 C967 'Q_CAP_C0402-10UF,6.3V,20%,X6S,B':;

SECTION_NUMBER 1
 '@S9S_MB_2U_LIB.S9S_MB_2U(SCH_1):PAGE74_I25@PURE_QUANTA.Q_CAP(CHIPS)':
 C_PATH='@s9s_mb_2u_lib.s9s_mb_2u(sch_1):page74_i25@pure_quanta.q_cap(chips)',
 P_PATH='@s9s_mb_2u_lib.s9s_mb_2u(sch_1):page74_i25@pure_quanta.q_cap(chips)',
 PATH='I25',
 DRAWING='@S9S_MB_2U_LIB.S9S_MB_2U(SCH_1):PAGE74',
 PHYS_PAGE='74',
 XY='(-4275,2250)',
 ROT='0',
 VER='1',
 PACK_TYPE='C0402',
 CDS_LIB='pure_quanta',
 CDS_PART_NAME='Q_CAP_C0402-10UF,6.3V,20%,X6S,B',
 TOLERANCE='20%',
 MATERIAL='X6S',
 VOLTAGE='6.3V',
 VALUE='10UF',
 PRIM_FILE='./archive_libs/logical/q_cap/chips/chips.prt';

PART_NAME
 C968 'Q_CAP_C0402-10UF,6.3V,20%,X6S,B':;

SECTION_NUMBER 1
 '@S9S_MB_2U_LIB.S9S_MB_2U(SCH_1):PAGE74_I23@PURE_QUANTA.Q_CAP(CHIPS)':
 C_PATH='@s9s_mb_2u_lib.s9s_mb_2u(sch_1):page74_i23@pure_quanta.q_cap(chips)',
 P_PATH='@s9s_mb_2u_lib.s9s_mb_2u(sch_1):page74_i23@pure_quanta.q_cap(chips)',
 PATH='I23',
 DRAWING='@S9S_MB_2U_LIB.S9S_MB_2U(SCH_1):PAGE74',
 PHYS_PAGE='74',
 XY='(-4250,1500)',
 ROT='0',
 VER='1',
 PACK_TYPE='C0402',
 CDS_LIB='pure_quanta',
 CDS_PART_NAME='Q_CAP_C0402-10UF,6.3V,20%,X6S,B',
 TOLERANCE='20%',
 MATERIAL='X6S',
 VOLTAGE='6.3V',
 VALUE='10UF',
 PRIM_FILE='./archive_libs/logical/q_cap/chips/chips.prt';

PART_NAME
 C969 'Q_CAP_C0402-10UF,6.3V,20%,X6S,B':;

SECTION_NUMBER 1
 '@S9S_MB_2U_LIB.S9S_MB_2U(SCH_1):PAGE74_I15@PURE_QUANTA.Q_CAP(CHIPS)':
 C_PATH='@s9s_mb_2u_lib.s9s_mb_2u(sch_1):page74_i15@pure_quanta.q_cap(chips)',
 P_PATH='@s9s_mb_2u_lib.s9s_mb_2u(sch_1):page74_i15@pure_quanta.q_cap(chips)',
 PATH='I15',
 DRAWING='@S9S_MB_2U_LIB.S9S_MB_2U(SCH_1):PAGE74',
 PHYS_PAGE='74',
 XY='(-4250,725)',
 ROT='0',
 VER='1',
 PACK_TYPE='C0402',
 CDS_LIB='pure_quanta',
 CDS_PART_NAME='Q_CAP_C0402-10UF,6.3V,20%,X6S,B',
 TOLERANCE='20%',
 MATERIAL='X6S',
 VOLTAGE='6.3V',
 VALUE='10UF',
 PRIM_FILE='./archive_libs/logical/q_cap/chips/chips.prt';

PART_NAME
 C970 'Q_CAP_C0402-10UF,6.3V,20%,X6S,B':;

SECTION_NUMBER 1
 '@S9S_MB_2U_LIB.S9S_MB_2U(SCH_1):PAGE74_I31@PURE_QUANTA.Q_CAP(CHIPS)':
 C_PATH='@s9s_mb_2u_lib.s9s_mb_2u(sch_1):page74_i31@pure_quanta.q_cap(chips)',
 P_PATH='@s9s_mb_2u_lib.s9s_mb_2u(sch_1):page74_i31@pure_quanta.q_cap(chips)',
 PATH='I31',
 DRAWING='@S9S_MB_2U_LIB.S9S_MB_2U(SCH_1):PAGE74',
 PHYS_PAGE='74',
 XY='(-3825,3025)',
 ROT='0',
 VER='1',
 PACK_TYPE='C0402',
 CDS_LIB='pure_quanta',
 CDS_PART_NAME='Q_CAP_C0402-10UF,6.3V,20%,X6S,B',
 TOLERANCE='20%',
 MATERIAL='X6S',
 VOLTAGE='6.3V',
 VALUE='10UF',
 PRIM_FILE='./archive_libs/logical/q_cap/chips/chips.prt';

PART_NAME
 C971 'Q_CAP_C0402-10UF,6.3V,20%,X6S,B':;

SECTION_NUMBER 1
 '@S9S_MB_2U_LIB.S9S_MB_2U(SCH_1):PAGE74_I30@PURE_QUANTA.Q_CAP(CHIPS)':
 C_PATH='@s9s_mb_2u_lib.s9s_mb_2u(sch_1):page74_i30@pure_quanta.q_cap(chips)',
 P_PATH='@s9s_mb_2u_lib.s9s_mb_2u(sch_1):page74_i30@pure_quanta.q_cap(chips)',
 PATH='I30',
 DRAWING='@S9S_MB_2U_LIB.S9S_MB_2U(SCH_1):PAGE74',
 PHYS_PAGE='74',
 XY='(-3825,2250)',
 ROT='0',
 VER='1',
 PACK_TYPE='C0402',
 CDS_LIB='pure_quanta',
 CDS_PART_NAME='Q_CAP_C0402-10UF,6.3V,20%,X6S,B',
 TOLERANCE='20%',
 MATERIAL='X6S',
 VOLTAGE='6.3V',
 VALUE='10UF',
 PRIM_FILE='./archive_libs/logical/q_cap/chips/chips.prt';

PART_NAME
 C972 'Q_CAP_C0402-10UF,6.3V,20%,X6S,B':;

SECTION_NUMBER 1
 '@S9S_MB_2U_LIB.S9S_MB_2U(SCH_1):PAGE74_I28@PURE_QUANTA.Q_CAP(CHIPS)':
 C_PATH='@s9s_mb_2u_lib.s9s_mb_2u(sch_1):page74_i28@pure_quanta.q_cap(chips)',
 P_PATH='@s9s_mb_2u_lib.s9s_mb_2u(sch_1):page74_i28@pure_quanta.q_cap(chips)',
 PATH='I28',
 DRAWING='@S9S_MB_2U_LIB.S9S_MB_2U(SCH_1):PAGE74',
 PHYS_PAGE='74',
 XY='(-3800,1500)',
 ROT='0',
 VER='1',
 PACK_TYPE='C0402',
 CDS_LIB='pure_quanta',
 CDS_PART_NAME='Q_CAP_C0402-10UF,6.3V,20%,X6S,B',
 TOLERANCE='20%',
 MATERIAL='X6S',
 VOLTAGE='6.3V',
 VALUE='10UF',
 PRIM_FILE='./archive_libs/logical/q_cap/chips/chips.prt';

PART_NAME
 C973 'Q_CAP_C0402-10UF,6.3V,20%,X6S,B':;

SECTION_NUMBER 1
 '@S9S_MB_2U_LIB.S9S_MB_2U(SCH_1):PAGE74_I21@PURE_QUANTA.Q_CAP(CHIPS)':
 C_PATH='@s9s_mb_2u_lib.s9s_mb_2u(sch_1):page74_i21@pure_quanta.q_cap(chips)',
 P_PATH='@s9s_mb_2u_lib.s9s_mb_2u(sch_1):page74_i21@pure_quanta.q_cap(chips)',
 PATH='I21',
 DRAWING='@S9S_MB_2U_LIB.S9S_MB_2U(SCH_1):PAGE74',
 PHYS_PAGE='74',
 XY='(-3800,725)',
 ROT='0',
 VER='1',
 PACK_TYPE='C0402',
 CDS_LIB='pure_quanta',
 CDS_PART_NAME='Q_CAP_C0402-10UF,6.3V,20%,X6S,B',
 TOLERANCE='20%',
 MATERIAL='X6S',
 VOLTAGE='6.3V',
 VALUE='10UF',
 PRIM_FILE='./archive_libs/logical/q_cap/chips/chips.prt';

PART_NAME
 C974 'Q_CAP_C0402-10UF,6.3V,20%,X6S,B':;

SECTION_NUMBER 1
 '@S9S_MB_2U_LIB.S9S_MB_2U(SCH_1):PAGE74_I33@PURE_QUANTA.Q_CAP(CHIPS)':
 C_PATH='@s9s_mb_2u_lib.s9s_mb_2u(sch_1):page74_i33@pure_quanta.q_cap(chips)',
 P_PATH='@s9s_mb_2u_lib.s9s_mb_2u(sch_1):page74_i33@pure_quanta.q_cap(chips)',
 PATH='I33',
 DRAWING='@S9S_MB_2U_LIB.S9S_MB_2U(SCH_1):PAGE74',
 PHYS_PAGE='74',
 XY='(-3375,3025)',
 ROT='0',
 VER='1',
 PACK_TYPE='C0402',
 CDS_LIB='pure_quanta',
 CDS_PART_NAME='Q_CAP_C0402-10UF,6.3V,20%,X6S,B',
 TOLERANCE='20%',
 MATERIAL='X6S',
 VOLTAGE='6.3V',
 VALUE='10UF',
 PRIM_FILE='./archive_libs/logical/q_cap/chips/chips.prt';

PART_NAME
 C975 'Q_CAP_C0402-10UF,6.3V,20%,X6S,B':;

SECTION_NUMBER 1
 '@S9S_MB_2U_LIB.S9S_MB_2U(SCH_1):PAGE74_I32@PURE_QUANTA.Q_CAP(CHIPS)':
 C_PATH='@s9s_mb_2u_lib.s9s_mb_2u(sch_1):page74_i32@pure_quanta.q_cap(chips)',
 P_PATH='@s9s_mb_2u_lib.s9s_mb_2u(sch_1):page74_i32@pure_quanta.q_cap(chips)',
 PATH='I32',
 DRAWING='@S9S_MB_2U_LIB.S9S_MB_2U(SCH_1):PAGE74',
 PHYS_PAGE='74',
 XY='(-3375,2250)',
 ROT='0',
 VER='1',
 PACK_TYPE='C0402',
 CDS_LIB='pure_quanta',
 CDS_PART_NAME='Q_CAP_C0402-10UF,6.3V,20%,X6S,B',
 TOLERANCE='20%',
 MATERIAL='X6S',
 VOLTAGE='6.3V',
 VALUE='10UF',
 PRIM_FILE='./archive_libs/logical/q_cap/chips/chips.prt';

PART_NAME
 C976 'Q_CAP_C0402-10UF,6.3V,20%,X6S,B':;

SECTION_NUMBER 1
 '@S9S_MB_2U_LIB.S9S_MB_2U(SCH_1):PAGE74_I29@PURE_QUANTA.Q_CAP(CHIPS)':
 C_PATH='@s9s_mb_2u_lib.s9s_mb_2u(sch_1):page74_i29@pure_quanta.q_cap(chips)',
 P_PATH='@s9s_mb_2u_lib.s9s_mb_2u(sch_1):page74_i29@pure_quanta.q_cap(chips)',
 PATH='I29',
 DRAWING='@S9S_MB_2U_LIB.S9S_MB_2U(SCH_1):PAGE74',
 PHYS_PAGE='74',
 XY='(-3350,1500)',
 ROT='0',
 VER='1',
 PACK_TYPE='C0402',
 CDS_LIB='pure_quanta',
 CDS_PART_NAME='Q_CAP_C0402-10UF,6.3V,20%,X6S,B',
 TOLERANCE='20%',
 MATERIAL='X6S',
 VOLTAGE='6.3V',
 VALUE='10UF',
 PRIM_FILE='./archive_libs/logical/q_cap/chips/chips.prt';

PART_NAME
 C977 'Q_CAP_C0402-10UF,6.3V,20%,X6S,B':;

SECTION_NUMBER 1
 '@S9S_MB_2U_LIB.S9S_MB_2U(SCH_1):PAGE74_I22@PURE_QUANTA.Q_CAP(CHIPS)':
 C_PATH='@s9s_mb_2u_lib.s9s_mb_2u(sch_1):page74_i22@pure_quanta.q_cap(chips)',
 P_PATH='@s9s_mb_2u_lib.s9s_mb_2u(sch_1):page74_i22@pure_quanta.q_cap(chips)',
 PATH='I22',
 DRAWING='@S9S_MB_2U_LIB.S9S_MB_2U(SCH_1):PAGE74',
 PHYS_PAGE='74',
 XY='(-3350,725)',
 ROT='0',
 VER='1',
 PACK_TYPE='C0402',
 CDS_LIB='pure_quanta',
 CDS_PART_NAME='Q_CAP_C0402-10UF,6.3V,20%,X6S,B',
 TOLERANCE='20%',
 MATERIAL='X6S',
 VOLTAGE='6.3V',
 VALUE='10UF',
 PRIM_FILE='./archive_libs/logical/q_cap/chips/chips.prt';

PART_NAME
 C978 'Q_CAP_C0402-10UF,6.3V,20%,X6S,B':;

SECTION_NUMBER 1
 '@S9S_MB_2U_LIB.S9S_MB_2U(SCH_1):PAGE74_I51@PURE_QUANTA.Q_CAP(CHIPS)':
 C_PATH='@s9s_mb_2u_lib.s9s_mb_2u(sch_1):page74_i51@pure_quanta.q_cap(chips)',
 P_PATH='@s9s_mb_2u_lib.s9s_mb_2u(sch_1):page74_i51@pure_quanta.q_cap(chips)',
 PATH='I51',
 DRAWING='@S9S_MB_2U_LIB.S9S_MB_2U(SCH_1):PAGE74',
 PHYS_PAGE='74',
 XY='(-2925,3025)',
 ROT='0',
 VER='1',
 PACK_TYPE='C0402',
 CDS_LIB='pure_quanta',
 CDS_PART_NAME='Q_CAP_C0402-10UF,6.3V,20%,X6S,B',
 TOLERANCE='20%',
 MATERIAL='X6S',
 VOLTAGE='6.3V',
 VALUE='10UF',
 PRIM_FILE='./archive_libs/logical/q_cap/chips/chips.prt';

PART_NAME
 C979 'Q_CAP_C0402-10UF,6.3V,20%,X6S,B':;

SECTION_NUMBER 1
 '@S9S_MB_2U_LIB.S9S_MB_2U(SCH_1):PAGE74_I50@PURE_QUANTA.Q_CAP(CHIPS)':
 C_PATH='@s9s_mb_2u_lib.s9s_mb_2u(sch_1):page74_i50@pure_quanta.q_cap(chips)',
 P_PATH='@s9s_mb_2u_lib.s9s_mb_2u(sch_1):page74_i50@pure_quanta.q_cap(chips)',
 PATH='I50',
 DRAWING='@S9S_MB_2U_LIB.S9S_MB_2U(SCH_1):PAGE74',
 PHYS_PAGE='74',
 XY='(-2925,2250)',
 ROT='0',
 VER='1',
 PACK_TYPE='C0402',
 CDS_LIB='pure_quanta',
 CDS_PART_NAME='Q_CAP_C0402-10UF,6.3V,20%,X6S,B',
 TOLERANCE='20%',
 MATERIAL='X6S',
 VOLTAGE='6.3V',
 VALUE='10UF',
 PRIM_FILE='./archive_libs/logical/q_cap/chips/chips.prt';

PART_NAME
 C980 'Q_CAP_C0402-10UF,6.3V,20%,X6S,B':;

SECTION_NUMBER 1
 '@S9S_MB_2U_LIB.S9S_MB_2U(SCH_1):PAGE74_I48@PURE_QUANTA.Q_CAP(CHIPS)':
 C_PATH='@s9s_mb_2u_lib.s9s_mb_2u(sch_1):page74_i48@pure_quanta.q_cap(chips)',
 P_PATH='@s9s_mb_2u_lib.s9s_mb_2u(sch_1):page74_i48@pure_quanta.q_cap(chips)',
 PATH='I48',
 DRAWING='@S9S_MB_2U_LIB.S9S_MB_2U(SCH_1):PAGE74',
 PHYS_PAGE='74',
 XY='(-2900,1500)',
 ROT='0',
 VER='1',
 PACK_TYPE='C0402',
 CDS_LIB='pure_quanta',
 CDS_PART_NAME='Q_CAP_C0402-10UF,6.3V,20%,X6S,B',
 TOLERANCE='20%',
 MATERIAL='X6S',
 VOLTAGE='6.3V',
 VALUE='10UF',
 PRIM_FILE='./archive_libs/logical/q_cap/chips/chips.prt';

PART_NAME
 C981 'Q_CAP_C0402-10UF,6.3V,20%,X6S,B':;

SECTION_NUMBER 1
 '@S9S_MB_2U_LIB.S9S_MB_2U(SCH_1):PAGE74_I37@PURE_QUANTA.Q_CAP(CHIPS)':
 C_PATH='@s9s_mb_2u_lib.s9s_mb_2u(sch_1):page74_i37@pure_quanta.q_cap(chips)',
 P_PATH='@s9s_mb_2u_lib.s9s_mb_2u(sch_1):page74_i37@pure_quanta.q_cap(chips)',
 PATH='I37',
 DRAWING='@S9S_MB_2U_LIB.S9S_MB_2U(SCH_1):PAGE74',
 PHYS_PAGE='74',
 XY='(-2900,725)',
 ROT='0',
 VER='1',
 PACK_TYPE='C0402',
 CDS_LIB='pure_quanta',
 CDS_PART_NAME='Q_CAP_C0402-10UF,6.3V,20%,X6S,B',
 TOLERANCE='20%',
 MATERIAL='X6S',
 VOLTAGE='6.3V',
 VALUE='10UF',
 PRIM_FILE='./archive_libs/logical/q_cap/chips/chips.prt';

PART_NAME
 C982 'Q_CAP_C0402-10UF,6.3V,20%,X6S,B':;

SECTION_NUMBER 1
 '@S9S_MB_2U_LIB.S9S_MB_2U(SCH_1):PAGE74_I53@PURE_QUANTA.Q_CAP(CHIPS)':
 C_PATH='@s9s_mb_2u_lib.s9s_mb_2u(sch_1):page74_i53@pure_quanta.q_cap(chips)',
 P_PATH='@s9s_mb_2u_lib.s9s_mb_2u(sch_1):page74_i53@pure_quanta.q_cap(chips)',
 PATH='I53',
 DRAWING='@S9S_MB_2U_LIB.S9S_MB_2U(SCH_1):PAGE74',
 PHYS_PAGE='74',
 XY='(-2475,3025)',
 ROT='0',
 VER='1',
 PACK_TYPE='C0402',
 CDS_LIB='pure_quanta',
 CDS_PART_NAME='Q_CAP_C0402-10UF,6.3V,20%,X6S,B',
 TOLERANCE='20%',
 MATERIAL='X6S',
 VOLTAGE='6.3V',
 VALUE='10UF',
 PRIM_FILE='./archive_libs/logical/q_cap/chips/chips.prt';

PART_NAME
 C983 'Q_CAP_C0402-10UF,6.3V,20%,X6S,B':;

SECTION_NUMBER 1
 '@S9S_MB_2U_LIB.S9S_MB_2U(SCH_1):PAGE74_I52@PURE_QUANTA.Q_CAP(CHIPS)':
 C_PATH='@s9s_mb_2u_lib.s9s_mb_2u(sch_1):page74_i52@pure_quanta.q_cap(chips)',
 P_PATH='@s9s_mb_2u_lib.s9s_mb_2u(sch_1):page74_i52@pure_quanta.q_cap(chips)',
 PATH='I52',
 DRAWING='@S9S_MB_2U_LIB.S9S_MB_2U(SCH_1):PAGE74',
 PHYS_PAGE='74',
 XY='(-2475,2250)',
 ROT='0',
 VER='1',
 PACK_TYPE='C0402',
 CDS_LIB='pure_quanta',
 CDS_PART_NAME='Q_CAP_C0402-10UF,6.3V,20%,X6S,B',
 TOLERANCE='20%',
 MATERIAL='X6S',
 VOLTAGE='6.3V',
 VALUE='10UF',
 PRIM_FILE='./archive_libs/logical/q_cap/chips/chips.prt';

PART_NAME
 C984 'Q_CAP_C0402-10UF,6.3V,20%,X6S,B':;

SECTION_NUMBER 1
 '@S9S_MB_2U_LIB.S9S_MB_2U(SCH_1):PAGE74_I49@PURE_QUANTA.Q_CAP(CHIPS)':
 C_PATH='@s9s_mb_2u_lib.s9s_mb_2u(sch_1):page74_i49@pure_quanta.q_cap(chips)',
 P_PATH='@s9s_mb_2u_lib.s9s_mb_2u(sch_1):page74_i49@pure_quanta.q_cap(chips)',
 PATH='I49',
 DRAWING='@S9S_MB_2U_LIB.S9S_MB_2U(SCH_1):PAGE74',
 PHYS_PAGE='74',
 XY='(-2450,1500)',
 ROT='0',
 VER='1',
 PACK_TYPE='C0402',
 CDS_LIB='pure_quanta',
 CDS_PART_NAME='Q_CAP_C0402-10UF,6.3V,20%,X6S,B',
 TOLERANCE='20%',
 MATERIAL='X6S',
 VOLTAGE='6.3V',
 VALUE='10UF',
 PRIM_FILE='./archive_libs/logical/q_cap/chips/chips.prt';

PART_NAME
 C985 'Q_CAP_C0402-10UF,6.3V,20%,X6S,B':;

SECTION_NUMBER 1
 '@S9S_MB_2U_LIB.S9S_MB_2U(SCH_1):PAGE74_I38@PURE_QUANTA.Q_CAP(CHIPS)':
 C_PATH='@s9s_mb_2u_lib.s9s_mb_2u(sch_1):page74_i38@pure_quanta.q_cap(chips)',
 P_PATH='@s9s_mb_2u_lib.s9s_mb_2u(sch_1):page74_i38@pure_quanta.q_cap(chips)',
 PATH='I38',
 DRAWING='@S9S_MB_2U_LIB.S9S_MB_2U(SCH_1):PAGE74',
 PHYS_PAGE='74',
 XY='(-2450,725)',
 ROT='0',
 VER='1',
 PACK_TYPE='C0402',
 CDS_LIB='pure_quanta',
 CDS_PART_NAME='Q_CAP_C0402-10UF,6.3V,20%,X6S,B',
 TOLERANCE='20%',
 MATERIAL='X6S',
 VOLTAGE='6.3V',
 VALUE='10UF',
 PRIM_FILE='./archive_libs/logical/q_cap/chips/chips.prt';

PART_NAME
 C986 'Q_CAP_C0402-10UF,6.3V,20%,X6S,B':;

SECTION_NUMBER 1
 '@S9S_MB_2U_LIB.S9S_MB_2U(SCH_1):PAGE74_I58@PURE_QUANTA.Q_CAP(CHIPS)':
 C_PATH='@s9s_mb_2u_lib.s9s_mb_2u(sch_1):page74_i58@pure_quanta.q_cap(chips)',
 P_PATH='@s9s_mb_2u_lib.s9s_mb_2u(sch_1):page74_i58@pure_quanta.q_cap(chips)',
 PATH='I58',
 DRAWING='@S9S_MB_2U_LIB.S9S_MB_2U(SCH_1):PAGE74',
 PHYS_PAGE='74',
 XY='(-2025,3025)',
 ROT='0',
 VER='1',
 PACK_TYPE='C0402',
 CDS_LIB='pure_quanta',
 CDS_PART_NAME='Q_CAP_C0402-10UF,6.3V,20%,X6S,B',
 TOLERANCE='20%',
 MATERIAL='X6S',
 VOLTAGE='6.3V',
 VALUE='10UF',
 PRIM_FILE='./archive_libs/logical/q_cap/chips/chips.prt';

PART_NAME
 C987 'Q_CAP_C0402-10UF,6.3V,20%,X6S,B':;

SECTION_NUMBER 1
 '@S9S_MB_2U_LIB.S9S_MB_2U(SCH_1):PAGE74_I57@PURE_QUANTA.Q_CAP(CHIPS)':
 C_PATH='@s9s_mb_2u_lib.s9s_mb_2u(sch_1):page74_i57@pure_quanta.q_cap(chips)',
 P_PATH='@s9s_mb_2u_lib.s9s_mb_2u(sch_1):page74_i57@pure_quanta.q_cap(chips)',
 PATH='I57',
 DRAWING='@S9S_MB_2U_LIB.S9S_MB_2U(SCH_1):PAGE74',
 PHYS_PAGE='74',
 XY='(-2025,2250)',
 ROT='0',
 VER='1',
 PACK_TYPE='C0402',
 CDS_LIB='pure_quanta',
 CDS_PART_NAME='Q_CAP_C0402-10UF,6.3V,20%,X6S,B',
 TOLERANCE='20%',
 MATERIAL='X6S',
 VOLTAGE='6.3V',
 VALUE='10UF',
 PRIM_FILE='./archive_libs/logical/q_cap/chips/chips.prt';

PART_NAME
 C988 'Q_CAP_C0402-10UF,6.3V,20%,X6S,B':;

SECTION_NUMBER 1
 '@S9S_MB_2U_LIB.S9S_MB_2U(SCH_1):PAGE74_I54@PURE_QUANTA.Q_CAP(CHIPS)':
 C_PATH='@s9s_mb_2u_lib.s9s_mb_2u(sch_1):page74_i54@pure_quanta.q_cap(chips)',
 P_PATH='@s9s_mb_2u_lib.s9s_mb_2u(sch_1):page74_i54@pure_quanta.q_cap(chips)',
 PATH='I54',
 DRAWING='@S9S_MB_2U_LIB.S9S_MB_2U(SCH_1):PAGE74',
 PHYS_PAGE='74',
 XY='(-2000,1500)',
 ROT='0',
 VER='1',
 PACK_TYPE='C0402',
 CDS_LIB='pure_quanta',
 CDS_PART_NAME='Q_CAP_C0402-10UF,6.3V,20%,X6S,B',
 TOLERANCE='20%',
 MATERIAL='X6S',
 VOLTAGE='6.3V',
 VALUE='10UF',
 PRIM_FILE='./archive_libs/logical/q_cap/chips/chips.prt';

PART_NAME
 C989 'Q_CAP_C0402-10UF,6.3V,20%,X6S,B':;

SECTION_NUMBER 1
 '@S9S_MB_2U_LIB.S9S_MB_2U(SCH_1):PAGE74_I45@PURE_QUANTA.Q_CAP(CHIPS)':
 C_PATH='@s9s_mb_2u_lib.s9s_mb_2u(sch_1):page74_i45@pure_quanta.q_cap(chips)',
 P_PATH='@s9s_mb_2u_lib.s9s_mb_2u(sch_1):page74_i45@pure_quanta.q_cap(chips)',
 PATH='I45',
 DRAWING='@S9S_MB_2U_LIB.S9S_MB_2U(SCH_1):PAGE74',
 PHYS_PAGE='74',
 XY='(-2000,725)',
 ROT='0',
 VER='1',
 PACK_TYPE='C0402',
 CDS_LIB='pure_quanta',
 CDS_PART_NAME='Q_CAP_C0402-10UF,6.3V,20%,X6S,B',
 TOLERANCE='20%',
 MATERIAL='X6S',
 VOLTAGE='6.3V',
 VALUE='10UF',
 PRIM_FILE='./archive_libs/logical/q_cap/chips/chips.prt';

PART_NAME
 C990 'Q_CAP_C0402-10UF,6.3V,20%,X6S,B':;

SECTION_NUMBER 1
 '@S9S_MB_2U_LIB.S9S_MB_2U(SCH_1):PAGE74_I60@PURE_QUANTA.Q_CAP(CHIPS)':
 C_PATH='@s9s_mb_2u_lib.s9s_mb_2u(sch_1):page74_i60@pure_quanta.q_cap(chips)',
 P_PATH='@s9s_mb_2u_lib.s9s_mb_2u(sch_1):page74_i60@pure_quanta.q_cap(chips)',
 PATH='I60',
 DRAWING='@S9S_MB_2U_LIB.S9S_MB_2U(SCH_1):PAGE74',
 PHYS_PAGE='74',
 XY='(-1575,3025)',
 ROT='0',
 VER='1',
 PACK_TYPE='C0402',
 CDS_LIB='pure_quanta',
 CDS_PART_NAME='Q_CAP_C0402-10UF,6.3V,20%,X6S,B',
 TOLERANCE='20%',
 MATERIAL='X6S',
 VOLTAGE='6.3V',
 VALUE='10UF',
 PRIM_FILE='./archive_libs/logical/q_cap/chips/chips.prt';

PART_NAME
 C991 'Q_CAP_C0402-10UF,6.3V,20%,X6S,B':;

SECTION_NUMBER 1
 '@S9S_MB_2U_LIB.S9S_MB_2U(SCH_1):PAGE74_I59@PURE_QUANTA.Q_CAP(CHIPS)':
 C_PATH='@s9s_mb_2u_lib.s9s_mb_2u(sch_1):page74_i59@pure_quanta.q_cap(chips)',
 P_PATH='@s9s_mb_2u_lib.s9s_mb_2u(sch_1):page74_i59@pure_quanta.q_cap(chips)',
 PATH='I59',
 DRAWING='@S9S_MB_2U_LIB.S9S_MB_2U(SCH_1):PAGE74',
 PHYS_PAGE='74',
 XY='(-1575,2250)',
 ROT='0',
 VER='1',
 PACK_TYPE='C0402',
 CDS_LIB='pure_quanta',
 CDS_PART_NAME='Q_CAP_C0402-10UF,6.3V,20%,X6S,B',
 TOLERANCE='20%',
 MATERIAL='X6S',
 VOLTAGE='6.3V',
 VALUE='10UF',
 PRIM_FILE='./archive_libs/logical/q_cap/chips/chips.prt';

PART_NAME
 C992 'Q_CAP_C0402-10UF,6.3V,20%,X6S,B':;

SECTION_NUMBER 1
 '@S9S_MB_2U_LIB.S9S_MB_2U(SCH_1):PAGE74_I55@PURE_QUANTA.Q_CAP(CHIPS)':
 C_PATH='@s9s_mb_2u_lib.s9s_mb_2u(sch_1):page74_i55@pure_quanta.q_cap(chips)',
 P_PATH='@s9s_mb_2u_lib.s9s_mb_2u(sch_1):page74_i55@pure_quanta.q_cap(chips)',
 PATH='I55',
 DRAWING='@S9S_MB_2U_LIB.S9S_MB_2U(SCH_1):PAGE74',
 PHYS_PAGE='74',
 XY='(-1550,1500)',
 ROT='0',
 VER='1',
 PACK_TYPE='C0402',
 CDS_LIB='pure_quanta',
 CDS_PART_NAME='Q_CAP_C0402-10UF,6.3V,20%,X6S,B',
 TOLERANCE='20%',
 MATERIAL='X6S',
 VOLTAGE='6.3V',
 VALUE='10UF',
 PRIM_FILE='./archive_libs/logical/q_cap/chips/chips.prt';

PART_NAME
 C993 'Q_CAP_C0402-10UF,6.3V,20%,X6S,B':;

SECTION_NUMBER 1
 '@S9S_MB_2U_LIB.S9S_MB_2U(SCH_1):PAGE74_I46@PURE_QUANTA.Q_CAP(CHIPS)':
 C_PATH='@s9s_mb_2u_lib.s9s_mb_2u(sch_1):page74_i46@pure_quanta.q_cap(chips)',
 P_PATH='@s9s_mb_2u_lib.s9s_mb_2u(sch_1):page74_i46@pure_quanta.q_cap(chips)',
 PATH='I46',
 DRAWING='@S9S_MB_2U_LIB.S9S_MB_2U(SCH_1):PAGE74',
 PHYS_PAGE='74',
 XY='(-1550,725)',
 ROT='0',
 VER='1',
 PACK_TYPE='C0402',
 CDS_LIB='pure_quanta',
 CDS_PART_NAME='Q_CAP_C0402-10UF,6.3V,20%,X6S,B',
 TOLERANCE='20%',
 MATERIAL='X6S',
 VOLTAGE='6.3V',
 VALUE='10UF',
 PRIM_FILE='./archive_libs/logical/q_cap/chips/chips.prt';

PART_NAME
 C994 'Q_CAP_C0402-10UF,6.3V,20%,X6S,B':;

SECTION_NUMBER 1
 '@S9S_MB_2U_LIB.S9S_MB_2U(SCH_1):PAGE74_I62@PURE_QUANTA.Q_CAP(CHIPS)':
 C_PATH='@s9s_mb_2u_lib.s9s_mb_2u(sch_1):page74_i62@pure_quanta.q_cap(chips)',
 P_PATH='@s9s_mb_2u_lib.s9s_mb_2u(sch_1):page74_i62@pure_quanta.q_cap(chips)',
 PATH='I62',
 DRAWING='@S9S_MB_2U_LIB.S9S_MB_2U(SCH_1):PAGE74',
 PHYS_PAGE='74',
 XY='(-1125,3025)',
 ROT='0',
 VER='1',
 PACK_TYPE='C0402',
 CDS_LIB='pure_quanta',
 CDS_PART_NAME='Q_CAP_C0402-10UF,6.3V,20%,X6S,B',
 TOLERANCE='20%',
 MATERIAL='X6S',
 VOLTAGE='6.3V',
 VALUE='10UF',
 PRIM_FILE='./archive_libs/logical/q_cap/chips/chips.prt';

PART_NAME
 C995 'Q_CAP_C0402-10UF,6.3V,20%,X6S,B':;

SECTION_NUMBER 1
 '@S9S_MB_2U_LIB.S9S_MB_2U(SCH_1):PAGE74_I61@PURE_QUANTA.Q_CAP(CHIPS)':
 C_PATH='@s9s_mb_2u_lib.s9s_mb_2u(sch_1):page74_i61@pure_quanta.q_cap(chips)',
 P_PATH='@s9s_mb_2u_lib.s9s_mb_2u(sch_1):page74_i61@pure_quanta.q_cap(chips)',
 PATH='I61',
 DRAWING='@S9S_MB_2U_LIB.S9S_MB_2U(SCH_1):PAGE74',
 PHYS_PAGE='74',
 XY='(-1125,2250)',
 ROT='0',
 VER='1',
 PACK_TYPE='C0402',
 CDS_LIB='pure_quanta',
 CDS_PART_NAME='Q_CAP_C0402-10UF,6.3V,20%,X6S,B',
 TOLERANCE='20%',
 MATERIAL='X6S',
 VOLTAGE='6.3V',
 VALUE='10UF',
 PRIM_FILE='./archive_libs/logical/q_cap/chips/chips.prt';

PART_NAME
 C996 'Q_CAP_C0402-10UF,6.3V,20%,X6S,B':;

SECTION_NUMBER 1
 '@S9S_MB_2U_LIB.S9S_MB_2U(SCH_1):PAGE74_I56@PURE_QUANTA.Q_CAP(CHIPS)':
 C_PATH='@s9s_mb_2u_lib.s9s_mb_2u(sch_1):page74_i56@pure_quanta.q_cap(chips)',
 P_PATH='@s9s_mb_2u_lib.s9s_mb_2u(sch_1):page74_i56@pure_quanta.q_cap(chips)',
 PATH='I56',
 DRAWING='@S9S_MB_2U_LIB.S9S_MB_2U(SCH_1):PAGE74',
 PHYS_PAGE='74',
 XY='(-1100,1500)',
 ROT='0',
 VER='1',
 PACK_TYPE='C0402',
 CDS_LIB='pure_quanta',
 CDS_PART_NAME='Q_CAP_C0402-10UF,6.3V,20%,X6S,B',
 TOLERANCE='20%',
 MATERIAL='X6S',
 VOLTAGE='6.3V',
 VALUE='10UF',
 PRIM_FILE='./archive_libs/logical/q_cap/chips/chips.prt';

PART_NAME
 C997 'Q_CAP_C0402-10UF,6.3V,20%,X6S,B':;

SECTION_NUMBER 1
 '@S9S_MB_2U_LIB.S9S_MB_2U(SCH_1):PAGE74_I47@PURE_QUANTA.Q_CAP(CHIPS)':
 C_PATH='@s9s_mb_2u_lib.s9s_mb_2u(sch_1):page74_i47@pure_quanta.q_cap(chips)',
 P_PATH='@s9s_mb_2u_lib.s9s_mb_2u(sch_1):page74_i47@pure_quanta.q_cap(chips)',
 PATH='I47',
 DRAWING='@S9S_MB_2U_LIB.S9S_MB_2U(SCH_1):PAGE74',
 PHYS_PAGE='74',
 XY='(-1100,725)',
 ROT='0',
 VER='1',
 PACK_TYPE='C0402',
 CDS_LIB='pure_quanta',
 CDS_PART_NAME='Q_CAP_C0402-10UF,6.3V,20%,X6S,B',
 TOLERANCE='20%',
 MATERIAL='X6S',
 VOLTAGE='6.3V',
 VALUE='10UF',
 PRIM_FILE='./archive_libs/logical/q_cap/chips/chips.prt';

PART_NAME
 C998 'Q_CAP_C0402-10UF,6.3V,20%,X6S,B':;

SECTION_NUMBER 1
 '@S9S_MB_2U_LIB.S9S_MB_2U(SCH_1):PAGE74_I86@PURE_QUANTA.Q_CAP(CHIPS)':
 C_PATH='@s9s_mb_2u_lib.s9s_mb_2u(sch_1):page74_i86@pure_quanta.q_cap(chips)',
 P_PATH='@s9s_mb_2u_lib.s9s_mb_2u(sch_1):page74_i86@pure_quanta.q_cap(chips)',
 PATH='I86',
 DRAWING='@S9S_MB_2U_LIB.S9S_MB_2U(SCH_1):PAGE74',
 PHYS_PAGE='74',
 XY='(-675,3025)',
 ROT='0',
 VER='1',
 PACK_TYPE='C0402',
 CDS_LIB='pure_quanta',
 CDS_PART_NAME='Q_CAP_C0402-10UF,6.3V,20%,X6S,B',
 TOLERANCE='20%',
 MATERIAL='X6S',
 VOLTAGE='6.3V',
 VALUE='10UF',
 PRIM_FILE='./archive_libs/logical/q_cap/chips/chips.prt';

PART_NAME
 C999 'Q_CAP_C0402-10UF,6.3V,20%,X6S,B':;

SECTION_NUMBER 1
 '@S9S_MB_2U_LIB.S9S_MB_2U(SCH_1):PAGE74_I85@PURE_QUANTA.Q_CAP(CHIPS)':
 C_PATH='@s9s_mb_2u_lib.s9s_mb_2u(sch_1):page74_i85@pure_quanta.q_cap(chips)',
 P_PATH='@s9s_mb_2u_lib.s9s_mb_2u(sch_1):page74_i85@pure_quanta.q_cap(chips)',
 PATH='I85',
 DRAWING='@S9S_MB_2U_LIB.S9S_MB_2U(SCH_1):PAGE74',
 PHYS_PAGE='74',
 XY='(-675,2250)',
 ROT='0',
 VER='1',
 PACK_TYPE='C0402',
 CDS_LIB='pure_quanta',
 CDS_PART_NAME='Q_CAP_C0402-10UF,6.3V,20%,X6S,B',
 TOLERANCE='20%',
 MATERIAL='X6S',
 VOLTAGE='6.3V',
 VALUE='10UF',
 PRIM_FILE='./archive_libs/logical/q_cap/chips/chips.prt';

PART_NAME
 C1000 'Q_CAP_C0402-10UF,6.3V,20%,X6S,B':;

SECTION_NUMBER 1
 '@S9S_MB_2U_LIB.S9S_MB_2U(SCH_1):PAGE74_I81@PURE_QUANTA.Q_CAP(CHIPS)':
 C_PATH='@s9s_mb_2u_lib.s9s_mb_2u(sch_1):page74_i81@pure_quanta.q_cap(chips)',
 P_PATH='@s9s_mb_2u_lib.s9s_mb_2u(sch_1):page74_i81@pure_quanta.q_cap(chips)',
 PATH='I81',
 DRAWING='@S9S_MB_2U_LIB.S9S_MB_2U(SCH_1):PAGE74',
 PHYS_PAGE='74',
 XY='(-650,1500)',
 ROT='0',
 VER='1',
 PACK_TYPE='C0402',
 CDS_LIB='pure_quanta',
 CDS_PART_NAME='Q_CAP_C0402-10UF,6.3V,20%,X6S,B',
 TOLERANCE='20%',
 MATERIAL='X6S',
 VOLTAGE='6.3V',
 VALUE='10UF',
 PRIM_FILE='./archive_libs/logical/q_cap/chips/chips.prt';

PART_NAME
 C1001 'Q_CAP_C0402-10UF,6.3V,20%,X6S,B':;

SECTION_NUMBER 1
 '@S9S_MB_2U_LIB.S9S_MB_2U(SCH_1):PAGE74_I75@PURE_QUANTA.Q_CAP(CHIPS)':
 C_PATH='@s9s_mb_2u_lib.s9s_mb_2u(sch_1):page74_i75@pure_quanta.q_cap(chips)',
 P_PATH='@s9s_mb_2u_lib.s9s_mb_2u(sch_1):page74_i75@pure_quanta.q_cap(chips)',
 PATH='I75',
 DRAWING='@S9S_MB_2U_LIB.S9S_MB_2U(SCH_1):PAGE74',
 PHYS_PAGE='74',
 XY='(-650,725)',
 ROT='0',
 VER='1',
 PACK_TYPE='C0402',
 CDS_LIB='pure_quanta',
 CDS_PART_NAME='Q_CAP_C0402-10UF,6.3V,20%,X6S,B',
 TOLERANCE='20%',
 MATERIAL='X6S',
 VOLTAGE='6.3V',
 VALUE='10UF',
 PRIM_FILE='./archive_libs/logical/q_cap/chips/chips.prt';

PART_NAME
 C1002 'Q_CAP_C0402-10UF,6.3V,20%,X6S,B':;

SECTION_NUMBER 1
 '@S9S_MB_2U_LIB.S9S_MB_2U(SCH_1):PAGE74_I89@PURE_QUANTA.Q_CAP(CHIPS)':
 C_PATH='@s9s_mb_2u_lib.s9s_mb_2u(sch_1):page74_i89@pure_quanta.q_cap(chips)',
 P_PATH='@s9s_mb_2u_lib.s9s_mb_2u(sch_1):page74_i89@pure_quanta.q_cap(chips)',
 PATH='I89',
 DRAWING='@S9S_MB_2U_LIB.S9S_MB_2U(SCH_1):PAGE74',
 PHYS_PAGE='74',
 XY='(-225,3025)',
 ROT='0',
 VER='1',
 PACK_TYPE='C0402',
 CDS_LIB='pure_quanta',
 CDS_PART_NAME='Q_CAP_C0402-10UF,6.3V,20%,X6S,B',
 TOLERANCE='20%',
 MATERIAL='X6S',
 VOLTAGE='6.3V',
 VALUE='10UF',
 PRIM_FILE='./archive_libs/logical/q_cap/chips/chips.prt';

PART_NAME
 C1003 'Q_CAP_C0402-10UF,6.3V,20%,X6S,B':;

SECTION_NUMBER 1
 '@S9S_MB_2U_LIB.S9S_MB_2U(SCH_1):PAGE74_I87@PURE_QUANTA.Q_CAP(CHIPS)':
 C_PATH='@s9s_mb_2u_lib.s9s_mb_2u(sch_1):page74_i87@pure_quanta.q_cap(chips)',
 P_PATH='@s9s_mb_2u_lib.s9s_mb_2u(sch_1):page74_i87@pure_quanta.q_cap(chips)',
 PATH='I87',
 DRAWING='@S9S_MB_2U_LIB.S9S_MB_2U(SCH_1):PAGE74',
 PHYS_PAGE='74',
 XY='(-225,2250)',
 ROT='0',
 VER='1',
 PACK_TYPE='C0402',
 CDS_LIB='pure_quanta',
 CDS_PART_NAME='Q_CAP_C0402-10UF,6.3V,20%,X6S,B',
 TOLERANCE='20%',
 MATERIAL='X6S',
 VOLTAGE='6.3V',
 VALUE='10UF',
 PRIM_FILE='./archive_libs/logical/q_cap/chips/chips.prt';

PART_NAME
 C1004 'Q_CAP_C0402-10UF,6.3V,20%,X6S,B':;

SECTION_NUMBER 1
 '@S9S_MB_2U_LIB.S9S_MB_2U(SCH_1):PAGE74_I83@PURE_QUANTA.Q_CAP(CHIPS)':
 C_PATH='@s9s_mb_2u_lib.s9s_mb_2u(sch_1):page74_i83@pure_quanta.q_cap(chips)',
 P_PATH='@s9s_mb_2u_lib.s9s_mb_2u(sch_1):page74_i83@pure_quanta.q_cap(chips)',
 PATH='I83',
 DRAWING='@S9S_MB_2U_LIB.S9S_MB_2U(SCH_1):PAGE74',
 PHYS_PAGE='74',
 XY='(-200,1500)',
 ROT='0',
 VER='1',
 PACK_TYPE='C0402',
 CDS_LIB='pure_quanta',
 CDS_PART_NAME='Q_CAP_C0402-10UF,6.3V,20%,X6S,B',
 TOLERANCE='20%',
 MATERIAL='X6S',
 VOLTAGE='6.3V',
 VALUE='10UF',
 PRIM_FILE='./archive_libs/logical/q_cap/chips/chips.prt';

PART_NAME
 C1005 'Q_CAP_C0402-10UF,6.3V,20%,X6S,B':;

SECTION_NUMBER 1
 '@S9S_MB_2U_LIB.S9S_MB_2U(SCH_1):PAGE74_I77@PURE_QUANTA.Q_CAP(CHIPS)':
 C_PATH='@s9s_mb_2u_lib.s9s_mb_2u(sch_1):page74_i77@pure_quanta.q_cap(chips)',
 P_PATH='@s9s_mb_2u_lib.s9s_mb_2u(sch_1):page74_i77@pure_quanta.q_cap(chips)',
 PATH='I77',
 DRAWING='@S9S_MB_2U_LIB.S9S_MB_2U(SCH_1):PAGE74',
 PHYS_PAGE='74',
 XY='(-200,725)',
 ROT='0',
 VER='1',
 PACK_TYPE='C0402',
 CDS_LIB='pure_quanta',
 CDS_PART_NAME='Q_CAP_C0402-10UF,6.3V,20%,X6S,B',
 TOLERANCE='20%',
 MATERIAL='X6S',
 VOLTAGE='6.3V',
 VALUE='10UF',
 PRIM_FILE='./archive_libs/logical/q_cap/chips/chips.prt';

PART_NAME
 C1006 'Q_CAP_C0402-22UF,4V,20%,X6S,CHA':;

SECTION_NUMBER 1
 '@S9S_MB_2U_LIB.S9S_MB_2U(SCH_1):PAGE74_I95@PURE_QUANTA.Q_CAP(CHIPS)':
 C_PATH='@s9s_mb_2u_lib.s9s_mb_2u(sch_1):page74_i95@pure_quanta.q_cap(chips)',
 P_PATH='@s9s_mb_2u_lib.s9s_mb_2u(sch_1):page74_i95@pure_quanta.q_cap(chips)',
 PATH='I95',
 DRAWING='@S9S_MB_2U_LIB.S9S_MB_2U(SCH_1):PAGE74',
 PHYS_PAGE='74',
 XY='(250,3025)',
 ROT='0',
 VER='1',
 PACK_TYPE='C0402',
 CDS_LIB='pure_quanta',
 CDS_PART_NAME='Q_CAP_C0402-22UF,4V,20%,X6S,CHA',
 TOLERANCE='20%',
 MATERIAL='X6S',
 VOLTAGE='4V',
 VALUE='22UF',
 PRIM_FILE='./archive_libs/logical/q_cap/chips/chips.prt';

PART_NAME
 C1007 'Q_CAP_C0402-22UF,4V,20%,X6S,CHA':;

SECTION_NUMBER 1
 '@S9S_MB_2U_LIB.S9S_MB_2U(SCH_1):PAGE74_I93@PURE_QUANTA.Q_CAP(CHIPS)':
 C_PATH='@s9s_mb_2u_lib.s9s_mb_2u(sch_1):page74_i93@pure_quanta.q_cap(chips)',
 P_PATH='@s9s_mb_2u_lib.s9s_mb_2u(sch_1):page74_i93@pure_quanta.q_cap(chips)',
 PATH='I93',
 DRAWING='@S9S_MB_2U_LIB.S9S_MB_2U(SCH_1):PAGE74',
 PHYS_PAGE='74',
 XY='(250,2250)',
 ROT='0',
 VER='1',
 PACK_TYPE='C0402',
 CDS_LIB='pure_quanta',
 CDS_PART_NAME='Q_CAP_C0402-22UF,4V,20%,X6S,CHA',
 TOLERANCE='20%',
 MATERIAL='X6S',
 VOLTAGE='4V',
 VALUE='22UF',
 PRIM_FILE='./archive_libs/logical/q_cap/chips/chips.prt';

PART_NAME
 C1008 'Q_CAP_C0402-22UF,4V,20%,X6S,CHA':;

SECTION_NUMBER 1
 '@S9S_MB_2U_LIB.S9S_MB_2U(SCH_1):PAGE74_I90@PURE_QUANTA.Q_CAP(CHIPS)':
 C_PATH='@s9s_mb_2u_lib.s9s_mb_2u(sch_1):page74_i90@pure_quanta.q_cap(chips)',
 P_PATH='@s9s_mb_2u_lib.s9s_mb_2u(sch_1):page74_i90@pure_quanta.q_cap(chips)',
 PATH='I90',
 DRAWING='@S9S_MB_2U_LIB.S9S_MB_2U(SCH_1):PAGE74',
 PHYS_PAGE='74',
 XY='(275,1500)',
 ROT='0',
 VER='1',
 PACK_TYPE='C0402',
 CDS_LIB='pure_quanta',
 CDS_PART_NAME='Q_CAP_C0402-22UF,4V,20%,X6S,CHA',
 TOLERANCE='20%',
 MATERIAL='X6S',
 VOLTAGE='4V',
 VALUE='22UF',
 PRIM_FILE='./archive_libs/logical/q_cap/chips/chips.prt';

PART_NAME
 C1009 'Q_CAP_C0402-22UF,4V,20%,X6S,CHA':;

SECTION_NUMBER 1
 '@S9S_MB_2U_LIB.S9S_MB_2U(SCH_1):PAGE74_I78@PURE_QUANTA.Q_CAP(CHIPS)':
 C_PATH='@s9s_mb_2u_lib.s9s_mb_2u(sch_1):page74_i78@pure_quanta.q_cap(chips)',
 P_PATH='@s9s_mb_2u_lib.s9s_mb_2u(sch_1):page74_i78@pure_quanta.q_cap(chips)',
 PATH='I78',
 DRAWING='@S9S_MB_2U_LIB.S9S_MB_2U(SCH_1):PAGE74',
 PHYS_PAGE='74',
 XY='(275,725)',
 ROT='0',
 VER='1',
 PACK_TYPE='C0402',
 CDS_LIB='pure_quanta',
 CDS_PART_NAME='Q_CAP_C0402-22UF,4V,20%,X6S,CHA',
 TOLERANCE='20%',
 MATERIAL='X6S',
 VOLTAGE='4V',
 VALUE='22UF',
 PRIM_FILE='./archive_libs/logical/q_cap/chips/chips.prt';

PART_NAME
 C1010 'Q_CAP_C0402-22UF,4V,20%,X6S,CHA':;

SECTION_NUMBER 1
 '@S9S_MB_2U_LIB.S9S_MB_2U(SCH_1):PAGE74_I97@PURE_QUANTA.Q_CAP(CHIPS)':
 C_PATH='@s9s_mb_2u_lib.s9s_mb_2u(sch_1):page74_i97@pure_quanta.q_cap(chips)',
 P_PATH='@s9s_mb_2u_lib.s9s_mb_2u(sch_1):page74_i97@pure_quanta.q_cap(chips)',
 PATH='I97',
 DRAWING='@S9S_MB_2U_LIB.S9S_MB_2U(SCH_1):PAGE74',
 PHYS_PAGE='74',
 XY='(700,3025)',
 ROT='0',
 VER='1',
 PACK_TYPE='C0402',
 CDS_LIB='pure_quanta',
 CDS_PART_NAME='Q_CAP_C0402-22UF,4V,20%,X6S,CHA',
 TOLERANCE='20%',
 MATERIAL='X6S',
 VOLTAGE='4V',
 VALUE='22UF',
 PRIM_FILE='./archive_libs/logical/q_cap/chips/chips.prt';

PART_NAME
 C1011 'Q_CAP_C0402-22UF,4V,20%,X6S,CHA':;

SECTION_NUMBER 1
 '@S9S_MB_2U_LIB.S9S_MB_2U(SCH_1):PAGE74_I96@PURE_QUANTA.Q_CAP(CHIPS)':
 C_PATH='@s9s_mb_2u_lib.s9s_mb_2u(sch_1):page74_i96@pure_quanta.q_cap(chips)',
 P_PATH='@s9s_mb_2u_lib.s9s_mb_2u(sch_1):page74_i96@pure_quanta.q_cap(chips)',
 PATH='I96',
 DRAWING='@S9S_MB_2U_LIB.S9S_MB_2U(SCH_1):PAGE74',
 PHYS_PAGE='74',
 XY='(700,2250)',
 ROT='0',
 VER='1',
 PACK_TYPE='C0402',
 CDS_LIB='pure_quanta',
 CDS_PART_NAME='Q_CAP_C0402-22UF,4V,20%,X6S,CHA',
 TOLERANCE='20%',
 MATERIAL='X6S',
 VOLTAGE='4V',
 VALUE='22UF',
 PRIM_FILE='./archive_libs/logical/q_cap/chips/chips.prt';

PART_NAME
 C1012 'Q_CAP_C0402-22UF,4V,20%,X6S,CHA':;

SECTION_NUMBER 1
 '@S9S_MB_2U_LIB.S9S_MB_2U(SCH_1):PAGE74_I92@PURE_QUANTA.Q_CAP(CHIPS)':
 C_PATH='@s9s_mb_2u_lib.s9s_mb_2u(sch_1):page74_i92@pure_quanta.q_cap(chips)',
 P_PATH='@s9s_mb_2u_lib.s9s_mb_2u(sch_1):page74_i92@pure_quanta.q_cap(chips)',
 PATH='I92',
 DRAWING='@S9S_MB_2U_LIB.S9S_MB_2U(SCH_1):PAGE74',
 PHYS_PAGE='74',
 XY='(725,1500)',
 ROT='0',
 VER='1',
 PACK_TYPE='C0402',
 CDS_LIB='pure_quanta',
 CDS_PART_NAME='Q_CAP_C0402-22UF,4V,20%,X6S,CHA',
 TOLERANCE='20%',
 MATERIAL='X6S',
 VOLTAGE='4V',
 VALUE='22UF',
 PRIM_FILE='./archive_libs/logical/q_cap/chips/chips.prt';

PART_NAME
 C1013 'Q_CAP_C0402-22UF,4V,20%,X6S,CHA':;

SECTION_NUMBER 1
 '@S9S_MB_2U_LIB.S9S_MB_2U(SCH_1):PAGE74_I80@PURE_QUANTA.Q_CAP(CHIPS)':
 C_PATH='@s9s_mb_2u_lib.s9s_mb_2u(sch_1):page74_i80@pure_quanta.q_cap(chips)',
 P_PATH='@s9s_mb_2u_lib.s9s_mb_2u(sch_1):page74_i80@pure_quanta.q_cap(chips)',
 PATH='I80',
 DRAWING='@S9S_MB_2U_LIB.S9S_MB_2U(SCH_1):PAGE74',
 PHYS_PAGE='74',
 XY='(725,725)',
 ROT='0',
 VER='1',
 PACK_TYPE='C0402',
 CDS_LIB='pure_quanta',
 CDS_PART_NAME='Q_CAP_C0402-22UF,4V,20%,X6S,CHA',
 TOLERANCE='20%',
 MATERIAL='X6S',
 VOLTAGE='4V',
 VALUE='22UF',
 PRIM_FILE='./archive_libs/logical/q_cap/chips/chips.prt';

PART_NAME
 C1014 'Q_CAP_C0402-22UF,4V,20%,X6S,CHA':;

SECTION_NUMBER 1
 '@S9S_MB_2U_LIB.S9S_MB_2U(SCH_1):PAGE74_I114@PURE_QUANTA.Q_CAP(CHIPS)':
 C_PATH='@s9s_mb_2u_lib.s9s_mb_2u(sch_1):page74_i114@pure_quanta.q_cap(chips)',
 P_PATH='@s9s_mb_2u_lib.s9s_mb_2u(sch_1):page74_i114@pure_quanta.q_cap(chips)',
 PATH='I114',
 DRAWING='@S9S_MB_2U_LIB.S9S_MB_2U(SCH_1):PAGE74',
 PHYS_PAGE='74',
 XY='(1150,3025)',
 ROT='0',
 VER='1',
 PACK_TYPE='C0402',
 CDS_LIB='pure_quanta',
 CDS_PART_NAME='Q_CAP_C0402-22UF,4V,20%,X6S,CHA',
 TOLERANCE='20%',
 MATERIAL='X6S',
 VOLTAGE='4V',
 VALUE='22UF',
 PRIM_FILE='./archive_libs/logical/q_cap/chips/chips.prt';

PART_NAME
 C1015 'Q_CAP_C0402-22UF,4V,20%,X6S,CHA':;

SECTION_NUMBER 1
 '@S9S_MB_2U_LIB.S9S_MB_2U(SCH_1):PAGE74_I113@PURE_QUANTA.Q_CAP(CHIPS)':
 C_PATH='@s9s_mb_2u_lib.s9s_mb_2u(sch_1):page74_i113@pure_quanta.q_cap(chips)',
 P_PATH='@s9s_mb_2u_lib.s9s_mb_2u(sch_1):page74_i113@pure_quanta.q_cap(chips)',
 PATH='I113',
 DRAWING='@S9S_MB_2U_LIB.S9S_MB_2U(SCH_1):PAGE74',
 PHYS_PAGE='74',
 XY='(1150,2250)',
 ROT='0',
 VER='1',
 PACK_TYPE='C0402',
 CDS_LIB='pure_quanta',
 CDS_PART_NAME='Q_CAP_C0402-22UF,4V,20%,X6S,CHA',
 TOLERANCE='20%',
 MATERIAL='X6S',
 VOLTAGE='4V',
 VALUE='22UF',
 PRIM_FILE='./archive_libs/logical/q_cap/chips/chips.prt';

PART_NAME
 C1016 'Q_CAP_C0402-22UF,4V,20%,X6S,CHA':;

SECTION_NUMBER 1
 '@S9S_MB_2U_LIB.S9S_MB_2U(SCH_1):PAGE74_I111@PURE_QUANTA.Q_CAP(CHIPS)':
 C_PATH='@s9s_mb_2u_lib.s9s_mb_2u(sch_1):page74_i111@pure_quanta.q_cap(chips)',
 P_PATH='@s9s_mb_2u_lib.s9s_mb_2u(sch_1):page74_i111@pure_quanta.q_cap(chips)',
 PATH='I111',
 DRAWING='@S9S_MB_2U_LIB.S9S_MB_2U(SCH_1):PAGE74',
 PHYS_PAGE='74',
 XY='(1175,1500)',
 ROT='0',
 VER='1',
 PACK_TYPE='C0402',
 CDS_LIB='pure_quanta',
 CDS_PART_NAME='Q_CAP_C0402-22UF,4V,20%,X6S,CHA',
 TOLERANCE='20%',
 MATERIAL='X6S',
 VOLTAGE='4V',
 VALUE='22UF',
 PRIM_FILE='./archive_libs/logical/q_cap/chips/chips.prt';

PART_NAME
 C1017 'Q_CAP_C0402-22UF,4V,20%,X6S,CHA':;

SECTION_NUMBER 1
 '@S9S_MB_2U_LIB.S9S_MB_2U(SCH_1):PAGE74_I105@PURE_QUANTA.Q_CAP(CHIPS)':
 C_PATH='@s9s_mb_2u_lib.s9s_mb_2u(sch_1):page74_i105@pure_quanta.q_cap(chips)',
 P_PATH='@s9s_mb_2u_lib.s9s_mb_2u(sch_1):page74_i105@pure_quanta.q_cap(chips)',
 PATH='I105',
 DRAWING='@S9S_MB_2U_LIB.S9S_MB_2U(SCH_1):PAGE74',
 PHYS_PAGE='74',
 XY='(1175,725)',
 ROT='0',
 VER='1',
 PACK_TYPE='C0402',
 CDS_LIB='pure_quanta',
 CDS_PART_NAME='Q_CAP_C0402-22UF,4V,20%,X6S,CHA',
 TOLERANCE='20%',
 MATERIAL='X6S',
 VOLTAGE='4V',
 VALUE='22UF',
 PRIM_FILE='./archive_libs/logical/q_cap/chips/chips.prt';

PART_NAME
 C1018 'Q_CAP_C0402-22UF,4V,20%,X6S,CHA':;

SECTION_NUMBER 1
 '@S9S_MB_2U_LIB.S9S_MB_2U(SCH_1):PAGE74_I116@PURE_QUANTA.Q_CAP(CHIPS)':
 C_PATH='@s9s_mb_2u_lib.s9s_mb_2u(sch_1):page74_i116@pure_quanta.q_cap(chips)',
 P_PATH='@s9s_mb_2u_lib.s9s_mb_2u(sch_1):page74_i116@pure_quanta.q_cap(chips)',
 PATH='I116',
 DRAWING='@S9S_MB_2U_LIB.S9S_MB_2U(SCH_1):PAGE74',
 PHYS_PAGE='74',
 XY='(1600,3025)',
 ROT='0',
 VER='1',
 PACK_TYPE='C0402',
 CDS_LIB='pure_quanta',
 CDS_PART_NAME='Q_CAP_C0402-22UF,4V,20%,X6S,CHA',
 TOLERANCE='20%',
 MATERIAL='X6S',
 VOLTAGE='4V',
 VALUE='22UF',
 PRIM_FILE='./archive_libs/logical/q_cap/chips/chips.prt';

PART_NAME
 C1019 'Q_CAP_C0402-22UF,4V,20%,X6S,CHA':;

SECTION_NUMBER 1
 '@S9S_MB_2U_LIB.S9S_MB_2U(SCH_1):PAGE74_I115@PURE_QUANTA.Q_CAP(CHIPS)':
 C_PATH='@s9s_mb_2u_lib.s9s_mb_2u(sch_1):page74_i115@pure_quanta.q_cap(chips)',
 P_PATH='@s9s_mb_2u_lib.s9s_mb_2u(sch_1):page74_i115@pure_quanta.q_cap(chips)',
 PATH='I115',
 DRAWING='@S9S_MB_2U_LIB.S9S_MB_2U(SCH_1):PAGE74',
 PHYS_PAGE='74',
 XY='(1600,2250)',
 ROT='0',
 VER='1',
 PACK_TYPE='C0402',
 CDS_LIB='pure_quanta',
 CDS_PART_NAME='Q_CAP_C0402-22UF,4V,20%,X6S,CHA',
 TOLERANCE='20%',
 MATERIAL='X6S',
 VOLTAGE='4V',
 VALUE='22UF',
 PRIM_FILE='./archive_libs/logical/q_cap/chips/chips.prt';

PART_NAME
 C1020 'Q_CAP_C0402-22UF,4V,20%,X6S,CHA':;

SECTION_NUMBER 1
 '@S9S_MB_2U_LIB.S9S_MB_2U(SCH_1):PAGE74_I112@PURE_QUANTA.Q_CAP(CHIPS)':
 C_PATH='@s9s_mb_2u_lib.s9s_mb_2u(sch_1):page74_i112@pure_quanta.q_cap(chips)',
 P_PATH='@s9s_mb_2u_lib.s9s_mb_2u(sch_1):page74_i112@pure_quanta.q_cap(chips)',
 PATH='I112',
 DRAWING='@S9S_MB_2U_LIB.S9S_MB_2U(SCH_1):PAGE74',
 PHYS_PAGE='74',
 XY='(1625,1500)',
 ROT='0',
 VER='1',
 PACK_TYPE='C0402',
 CDS_LIB='pure_quanta',
 CDS_PART_NAME='Q_CAP_C0402-22UF,4V,20%,X6S,CHA',
 TOLERANCE='20%',
 MATERIAL='X6S',
 VOLTAGE='4V',
 VALUE='22UF',
 PRIM_FILE='./archive_libs/logical/q_cap/chips/chips.prt';

PART_NAME
 C1021 'Q_CAP_C0402-22UF,4V,20%,X6S,CHA':;

SECTION_NUMBER 1
 '@S9S_MB_2U_LIB.S9S_MB_2U(SCH_1):PAGE74_I106@PURE_QUANTA.Q_CAP(CHIPS)':
 C_PATH='@s9s_mb_2u_lib.s9s_mb_2u(sch_1):page74_i106@pure_quanta.q_cap(chips)',
 P_PATH='@s9s_mb_2u_lib.s9s_mb_2u(sch_1):page74_i106@pure_quanta.q_cap(chips)',
 PATH='I106',
 DRAWING='@S9S_MB_2U_LIB.S9S_MB_2U(SCH_1):PAGE74',
 PHYS_PAGE='74',
 XY='(1625,725)',
 ROT='0',
 VER='1',
 PACK_TYPE='C0402',
 CDS_LIB='pure_quanta',
 CDS_PART_NAME='Q_CAP_C0402-22UF,4V,20%,X6S,CHA',
 TOLERANCE='20%',
 MATERIAL='X6S',
 VOLTAGE='4V',
 VALUE='22UF',
 PRIM_FILE='./archive_libs/logical/q_cap/chips/chips.prt';

PART_NAME
 C1022 'Q_CAP_C0402-22UF,4V,20%,X6S,CHA':;

SECTION_NUMBER 1
 '@S9S_MB_2U_LIB.S9S_MB_2U(SCH_1):PAGE74_I122@PURE_QUANTA.Q_CAP(CHIPS)':
 C_PATH='@s9s_mb_2u_lib.s9s_mb_2u(sch_1):page74_i122@pure_quanta.q_cap(chips)',
 P_PATH='@s9s_mb_2u_lib.s9s_mb_2u(sch_1):page74_i122@pure_quanta.q_cap(chips)',
 PATH='I122',
 DRAWING='@S9S_MB_2U_LIB.S9S_MB_2U(SCH_1):PAGE74',
 PHYS_PAGE='74',
 XY='(2050,3025)',
 ROT='0',
 VER='1',
 PACK_TYPE='C0402',
 CDS_LIB='pure_quanta',
 CDS_PART_NAME='Q_CAP_C0402-22UF,4V,20%,X6S,CHA',
 TOLERANCE='20%',
 MATERIAL='X6S',
 VOLTAGE='4V',
 VALUE='22UF',
 PRIM_FILE='./archive_libs/logical/q_cap/chips/chips.prt';

PART_NAME
 C1023 'Q_CAP_C0402-22UF,4V,20%,X6S,CHA':;

SECTION_NUMBER 1
 '@S9S_MB_2U_LIB.S9S_MB_2U(SCH_1):PAGE74_I120@PURE_QUANTA.Q_CAP(CHIPS)':
 C_PATH='@s9s_mb_2u_lib.s9s_mb_2u(sch_1):page74_i120@pure_quanta.q_cap(chips)',
 P_PATH='@s9s_mb_2u_lib.s9s_mb_2u(sch_1):page74_i120@pure_quanta.q_cap(chips)',
 PATH='I120',
 DRAWING='@S9S_MB_2U_LIB.S9S_MB_2U(SCH_1):PAGE74',
 PHYS_PAGE='74',
 XY='(2050,2250)',
 ROT='0',
 VER='1',
 PACK_TYPE='C0402',
 CDS_LIB='pure_quanta',
 CDS_PART_NAME='Q_CAP_C0402-22UF,4V,20%,X6S,CHA',
 TOLERANCE='20%',
 MATERIAL='X6S',
 VOLTAGE='4V',
 VALUE='22UF',
 PRIM_FILE='./archive_libs/logical/q_cap/chips/chips.prt';

PART_NAME
 C1024 'Q_CAP_C0402-22UF,4V,20%,X6S,CHA':;

SECTION_NUMBER 1
 '@S9S_MB_2U_LIB.S9S_MB_2U(SCH_1):PAGE74_I117@PURE_QUANTA.Q_CAP(CHIPS)':
 C_PATH='@s9s_mb_2u_lib.s9s_mb_2u(sch_1):page74_i117@pure_quanta.q_cap(chips)',
 P_PATH='@s9s_mb_2u_lib.s9s_mb_2u(sch_1):page74_i117@pure_quanta.q_cap(chips)',
 PATH='I117',
 DRAWING='@S9S_MB_2U_LIB.S9S_MB_2U(SCH_1):PAGE74',
 PHYS_PAGE='74',
 XY='(2075,1500)',
 ROT='0',
 VER='1',
 PACK_TYPE='C0402',
 CDS_LIB='pure_quanta',
 CDS_PART_NAME='Q_CAP_C0402-22UF,4V,20%,X6S,CHA',
 TOLERANCE='20%',
 MATERIAL='X6S',
 VOLTAGE='4V',
 VALUE='22UF',
 PRIM_FILE='./archive_libs/logical/q_cap/chips/chips.prt';

PART_NAME
 C1025 'Q_CAP_C0402-22UF,4V,20%,X6S,CHA':;

SECTION_NUMBER 1
 '@S9S_MB_2U_LIB.S9S_MB_2U(SCH_1):PAGE74_I108@PURE_QUANTA.Q_CAP(CHIPS)':
 C_PATH='@s9s_mb_2u_lib.s9s_mb_2u(sch_1):page74_i108@pure_quanta.q_cap(chips)',
 P_PATH='@s9s_mb_2u_lib.s9s_mb_2u(sch_1):page74_i108@pure_quanta.q_cap(chips)',
 PATH='I108',
 DRAWING='@S9S_MB_2U_LIB.S9S_MB_2U(SCH_1):PAGE74',
 PHYS_PAGE='74',
 XY='(2075,725)',
 ROT='0',
 VER='1',
 PACK_TYPE='C0402',
 CDS_LIB='pure_quanta',
 CDS_PART_NAME='Q_CAP_C0402-22UF,4V,20%,X6S,CHA',
 TOLERANCE='20%',
 MATERIAL='X6S',
 VOLTAGE='4V',
 VALUE='22UF',
 PRIM_FILE='./archive_libs/logical/q_cap/chips/chips.prt';

PART_NAME
 C1026 'Q_CAP_C0402-22UF,4V,20%,X6S,CHA':;

SECTION_NUMBER 1
 '@S9S_MB_2U_LIB.S9S_MB_2U(SCH_1):PAGE74_I123@PURE_QUANTA.Q_CAP(CHIPS)':
 C_PATH='@s9s_mb_2u_lib.s9s_mb_2u(sch_1):page74_i123@pure_quanta.q_cap(chips)',
 P_PATH='@s9s_mb_2u_lib.s9s_mb_2u(sch_1):page74_i123@pure_quanta.q_cap(chips)',
 PATH='I123',
 DRAWING='@S9S_MB_2U_LIB.S9S_MB_2U(SCH_1):PAGE74',
 PHYS_PAGE='74',
 XY='(2500,3025)',
 ROT='0',
 VER='1',
 PACK_TYPE='C0402',
 CDS_LIB='pure_quanta',
 CDS_PART_NAME='Q_CAP_C0402-22UF,4V,20%,X6S,CHA',
 TOLERANCE='20%',
 MATERIAL='X6S',
 VOLTAGE='4V',
 VALUE='22UF',
 PRIM_FILE='./archive_libs/logical/q_cap/chips/chips.prt';

PART_NAME
 C1027 'Q_CAP_C0402-22UF,4V,20%,X6S,CHA':;

SECTION_NUMBER 1
 '@S9S_MB_2U_LIB.S9S_MB_2U(SCH_1):PAGE74_I121@PURE_QUANTA.Q_CAP(CHIPS)':
 C_PATH='@s9s_mb_2u_lib.s9s_mb_2u(sch_1):page74_i121@pure_quanta.q_cap(chips)',
 P_PATH='@s9s_mb_2u_lib.s9s_mb_2u(sch_1):page74_i121@pure_quanta.q_cap(chips)',
 PATH='I121',
 DRAWING='@S9S_MB_2U_LIB.S9S_MB_2U(SCH_1):PAGE74',
 PHYS_PAGE='74',
 XY='(2500,2250)',
 ROT='0',
 VER='1',
 PACK_TYPE='C0402',
 CDS_LIB='pure_quanta',
 CDS_PART_NAME='Q_CAP_C0402-22UF,4V,20%,X6S,CHA',
 TOLERANCE='20%',
 MATERIAL='X6S',
 VOLTAGE='4V',
 VALUE='22UF',
 PRIM_FILE='./archive_libs/logical/q_cap/chips/chips.prt';

PART_NAME
 C1028 'Q_CAP_C0402-22UF,4V,20%,X6S,CHA':;

SECTION_NUMBER 1
 '@S9S_MB_2U_LIB.S9S_MB_2U(SCH_1):PAGE74_I118@PURE_QUANTA.Q_CAP(CHIPS)':
 C_PATH='@s9s_mb_2u_lib.s9s_mb_2u(sch_1):page74_i118@pure_quanta.q_cap(chips)',
 P_PATH='@s9s_mb_2u_lib.s9s_mb_2u(sch_1):page74_i118@pure_quanta.q_cap(chips)',
 PATH='I118',
 DRAWING='@S9S_MB_2U_LIB.S9S_MB_2U(SCH_1):PAGE74',
 PHYS_PAGE='74',
 XY='(2525,1500)',
 ROT='0',
 VER='1',
 PACK_TYPE='C0402',
 CDS_LIB='pure_quanta',
 CDS_PART_NAME='Q_CAP_C0402-22UF,4V,20%,X6S,CHA',
 TOLERANCE='20%',
 MATERIAL='X6S',
 VOLTAGE='4V',
 VALUE='22UF',
 PRIM_FILE='./archive_libs/logical/q_cap/chips/chips.prt';

PART_NAME
 C1029 'Q_CAP_C0402-22UF,4V,20%,X6S,CHA':;

SECTION_NUMBER 1
 '@S9S_MB_2U_LIB.S9S_MB_2U(SCH_1):PAGE74_I109@PURE_QUANTA.Q_CAP(CHIPS)':
 C_PATH='@s9s_mb_2u_lib.s9s_mb_2u(sch_1):page74_i109@pure_quanta.q_cap(chips)',
 P_PATH='@s9s_mb_2u_lib.s9s_mb_2u(sch_1):page74_i109@pure_quanta.q_cap(chips)',
 PATH='I109',
 DRAWING='@S9S_MB_2U_LIB.S9S_MB_2U(SCH_1):PAGE74',
 PHYS_PAGE='74',
 XY='(2525,725)',
 ROT='0',
 VER='1',
 PACK_TYPE='C0402',
 CDS_LIB='pure_quanta',
 CDS_PART_NAME='Q_CAP_C0402-22UF,4V,20%,X6S,CHA',
 TOLERANCE='20%',
 MATERIAL='X6S',
 VOLTAGE='4V',
 VALUE='22UF',
 PRIM_FILE='./archive_libs/logical/q_cap/chips/chips.prt';

PART_NAME
 C1030 'Q_CAP_C0402-22UF,4V,20%,X6S,CHA':;

SECTION_NUMBER 1
 '@S9S_MB_2U_LIB.S9S_MB_2U(SCH_1):PAGE74_I125@PURE_QUANTA.Q_CAP(CHIPS)':
 C_PATH='@s9s_mb_2u_lib.s9s_mb_2u(sch_1):page74_i125@pure_quanta.q_cap(chips)',
 P_PATH='@s9s_mb_2u_lib.s9s_mb_2u(sch_1):page74_i125@pure_quanta.q_cap(chips)',
 PATH='I125',
 DRAWING='@S9S_MB_2U_LIB.S9S_MB_2U(SCH_1):PAGE74',
 PHYS_PAGE='74',
 XY='(2950,3025)',
 ROT='0',
 VER='1',
 PACK_TYPE='C0402',
 CDS_LIB='pure_quanta',
 CDS_PART_NAME='Q_CAP_C0402-22UF,4V,20%,X6S,CHA',
 TOLERANCE='20%',
 MATERIAL='X6S',
 VOLTAGE='4V',
 VALUE='22UF',
 PRIM_FILE='./archive_libs/logical/q_cap/chips/chips.prt';

PART_NAME
 C1031 'Q_CAP_C0402-22UF,4V,20%,X6S,CHA':;

SECTION_NUMBER 1
 '@S9S_MB_2U_LIB.S9S_MB_2U(SCH_1):PAGE74_I124@PURE_QUANTA.Q_CAP(CHIPS)':
 C_PATH='@s9s_mb_2u_lib.s9s_mb_2u(sch_1):page74_i124@pure_quanta.q_cap(chips)',
 P_PATH='@s9s_mb_2u_lib.s9s_mb_2u(sch_1):page74_i124@pure_quanta.q_cap(chips)',
 PATH='I124',
 DRAWING='@S9S_MB_2U_LIB.S9S_MB_2U(SCH_1):PAGE74',
 PHYS_PAGE='74',
 XY='(2950,2250)',
 ROT='0',
 VER='1',
 PACK_TYPE='C0402',
 CDS_LIB='pure_quanta',
 CDS_PART_NAME='Q_CAP_C0402-22UF,4V,20%,X6S,CHA',
 TOLERANCE='20%',
 MATERIAL='X6S',
 VOLTAGE='4V',
 VALUE='22UF',
 PRIM_FILE='./archive_libs/logical/q_cap/chips/chips.prt';

PART_NAME
 C1032 'Q_CAP_C0402-22UF,4V,20%,X6S,CHA':;

SECTION_NUMBER 1
 '@S9S_MB_2U_LIB.S9S_MB_2U(SCH_1):PAGE74_I119@PURE_QUANTA.Q_CAP(CHIPS)':
 C_PATH='@s9s_mb_2u_lib.s9s_mb_2u(sch_1):page74_i119@pure_quanta.q_cap(chips)',
 P_PATH='@s9s_mb_2u_lib.s9s_mb_2u(sch_1):page74_i119@pure_quanta.q_cap(chips)',
 PATH='I119',
 DRAWING='@S9S_MB_2U_LIB.S9S_MB_2U(SCH_1):PAGE74',
 PHYS_PAGE='74',
 XY='(2975,1500)',
 ROT='0',
 VER='1',
 PACK_TYPE='C0402',
 CDS_LIB='pure_quanta',
 CDS_PART_NAME='Q_CAP_C0402-22UF,4V,20%,X6S,CHA',
 TOLERANCE='20%',
 MATERIAL='X6S',
 VOLTAGE='4V',
 VALUE='22UF',
 PRIM_FILE='./archive_libs/logical/q_cap/chips/chips.prt';

PART_NAME
 C1033 'Q_CAP_C0402-22UF,4V,20%,X6S,CHA':;

SECTION_NUMBER 1
 '@S9S_MB_2U_LIB.S9S_MB_2U(SCH_1):PAGE74_I110@PURE_QUANTA.Q_CAP(CHIPS)':
 C_PATH='@s9s_mb_2u_lib.s9s_mb_2u(sch_1):page74_i110@pure_quanta.q_cap(chips)',
 P_PATH='@s9s_mb_2u_lib.s9s_mb_2u(sch_1):page74_i110@pure_quanta.q_cap(chips)',
 PATH='I110',
 DRAWING='@S9S_MB_2U_LIB.S9S_MB_2U(SCH_1):PAGE74',
 PHYS_PAGE='74',
 XY='(2975,725)',
 ROT='0',
 VER='1',
 PACK_TYPE='C0402',
 CDS_LIB='pure_quanta',
 CDS_PART_NAME='Q_CAP_C0402-22UF,4V,20%,X6S,CHA',
 TOLERANCE='20%',
 MATERIAL='X6S',
 VOLTAGE='4V',
 VALUE='22UF',
 PRIM_FILE='./archive_libs/logical/q_cap/chips/chips.prt';

PART_NAME
 C1034 'Q_CAP_C0402-22UF,4V,20%,X6S,CHA':;

SECTION_NUMBER 1
 '@S9S_MB_2U_LIB.S9S_MB_2U(SCH_1):PAGE74_I134@PURE_QUANTA.Q_CAP(CHIPS)':
 C_PATH='@s9s_mb_2u_lib.s9s_mb_2u(sch_1):page74_i134@pure_quanta.q_cap(chips)',
 P_PATH='@s9s_mb_2u_lib.s9s_mb_2u(sch_1):page74_i134@pure_quanta.q_cap(chips)',
 PATH='I134',
 DRAWING='@S9S_MB_2U_LIB.S9S_MB_2U(SCH_1):PAGE74',
 PHYS_PAGE='74',
 XY='(3400,3025)',
 ROT='0',
 VER='1',
 PACK_TYPE='C0402',
 CDS_LIB='pure_quanta',
 CDS_PART_NAME='Q_CAP_C0402-22UF,4V,20%,X6S,CHA',
 TOLERANCE='20%',
 MATERIAL='X6S',
 VOLTAGE='4V',
 VALUE='22UF',
 PRIM_FILE='./archive_libs/logical/q_cap/chips/chips.prt';

PART_NAME
 C1035 'Q_CAP_C0402-22UF,4V,20%,X6S,CHA':;

SECTION_NUMBER 1
 '@S9S_MB_2U_LIB.S9S_MB_2U(SCH_1):PAGE74_I133@PURE_QUANTA.Q_CAP(CHIPS)':
 C_PATH='@s9s_mb_2u_lib.s9s_mb_2u(sch_1):page74_i133@pure_quanta.q_cap(chips)',
 P_PATH='@s9s_mb_2u_lib.s9s_mb_2u(sch_1):page74_i133@pure_quanta.q_cap(chips)',
 PATH='I133',
 DRAWING='@S9S_MB_2U_LIB.S9S_MB_2U(SCH_1):PAGE74',
 PHYS_PAGE='74',
 XY='(3400,2250)',
 ROT='0',
 VER='1',
 PACK_TYPE='C0402',
 CDS_LIB='pure_quanta',
 CDS_PART_NAME='Q_CAP_C0402-22UF,4V,20%,X6S,CHA',
 TOLERANCE='20%',
 MATERIAL='X6S',
 VOLTAGE='4V',
 VALUE='22UF',
 PRIM_FILE='./archive_libs/logical/q_cap/chips/chips.prt';

PART_NAME
 C1036 'Q_CAP_C0402-22UF,4V,20%,X6S,CHA':;

SECTION_NUMBER 1
 '@S9S_MB_2U_LIB.S9S_MB_2U(SCH_1):PAGE74_I131@PURE_QUANTA.Q_CAP(CHIPS)':
 C_PATH='@s9s_mb_2u_lib.s9s_mb_2u(sch_1):page74_i131@pure_quanta.q_cap(chips)',
 P_PATH='@s9s_mb_2u_lib.s9s_mb_2u(sch_1):page74_i131@pure_quanta.q_cap(chips)',
 PATH='I131',
 DRAWING='@S9S_MB_2U_LIB.S9S_MB_2U(SCH_1):PAGE74',
 PHYS_PAGE='74',
 XY='(3425,1500)',
 ROT='0',
 VER='1',
 PACK_TYPE='C0402',
 CDS_LIB='pure_quanta',
 CDS_PART_NAME='Q_CAP_C0402-22UF,4V,20%,X6S,CHA',
 TOLERANCE='20%',
 MATERIAL='X6S',
 VOLTAGE='4V',
 VALUE='22UF',
 PRIM_FILE='./archive_libs/logical/q_cap/chips/chips.prt';

PART_NAME
 C1037 'Q_CAP_C0402-22UF,4V,20%,X6S,CHA':;

SECTION_NUMBER 1
 '@S9S_MB_2U_LIB.S9S_MB_2U(SCH_1):PAGE74_I127@PURE_QUANTA.Q_CAP(CHIPS)':
 C_PATH='@s9s_mb_2u_lib.s9s_mb_2u(sch_1):page74_i127@pure_quanta.q_cap(chips)',
 P_PATH='@s9s_mb_2u_lib.s9s_mb_2u(sch_1):page74_i127@pure_quanta.q_cap(chips)',
 PATH='I127',
 DRAWING='@S9S_MB_2U_LIB.S9S_MB_2U(SCH_1):PAGE74',
 PHYS_PAGE='74',
 XY='(3425,725)',
 ROT='0',
 VER='1',
 PACK_TYPE='C0402',
 CDS_LIB='pure_quanta',
 CDS_PART_NAME='Q_CAP_C0402-22UF,4V,20%,X6S,CHA',
 TOLERANCE='20%',
 MATERIAL='X6S',
 VOLTAGE='4V',
 VALUE='22UF',
 PRIM_FILE='./archive_libs/logical/q_cap/chips/chips.prt';

PART_NAME
 C1038 'Q_CAP_C0402-22UF,4V,20%,X6S,CHA':;

SECTION_NUMBER 1
 '@S9S_MB_2U_LIB.S9S_MB_2U(SCH_1):PAGE74_I137@PURE_QUANTA.Q_CAP(CHIPS)':
 C_PATH='@s9s_mb_2u_lib.s9s_mb_2u(sch_1):page74_i137@pure_quanta.q_cap(chips)',
 P_PATH='@s9s_mb_2u_lib.s9s_mb_2u(sch_1):page74_i137@pure_quanta.q_cap(chips)',
 PATH='I137',
 DRAWING='@S9S_MB_2U_LIB.S9S_MB_2U(SCH_1):PAGE74',
 PHYS_PAGE='74',
 XY='(3850,3025)',
 ROT='0',
 VER='1',
 PACK_TYPE='C0402',
 CDS_LIB='pure_quanta',
 CDS_PART_NAME='Q_CAP_C0402-22UF,4V,20%,X6S,CHA',
 TOLERANCE='20%',
 MATERIAL='X6S',
 VOLTAGE='4V',
 VALUE='22UF',
 PRIM_FILE='./archive_libs/logical/q_cap/chips/chips.prt';

PART_NAME
 C1039 'Q_CAP_C0402-22UF,4V,20%,X6S,CHA':;

SECTION_NUMBER 1
 '@S9S_MB_2U_LIB.S9S_MB_2U(SCH_1):PAGE74_I135@PURE_QUANTA.Q_CAP(CHIPS)':
 C_PATH='@s9s_mb_2u_lib.s9s_mb_2u(sch_1):page74_i135@pure_quanta.q_cap(chips)',
 P_PATH='@s9s_mb_2u_lib.s9s_mb_2u(sch_1):page74_i135@pure_quanta.q_cap(chips)',
 PATH='I135',
 DRAWING='@S9S_MB_2U_LIB.S9S_MB_2U(SCH_1):PAGE74',
 PHYS_PAGE='74',
 XY='(3850,2250)',
 ROT='0',
 VER='1',
 PACK_TYPE='C0402',
 CDS_LIB='pure_quanta',
 CDS_PART_NAME='Q_CAP_C0402-22UF,4V,20%,X6S,CHA',
 TOLERANCE='20%',
 MATERIAL='X6S',
 VOLTAGE='4V',
 VALUE='22UF',
 PRIM_FILE='./archive_libs/logical/q_cap/chips/chips.prt';

PART_NAME
 C1040 'Q_CAP_C0402-22UF,4V,20%,X6S,CHA':;

SECTION_NUMBER 1
 '@S9S_MB_2U_LIB.S9S_MB_2U(SCH_1):PAGE74_I132@PURE_QUANTA.Q_CAP(CHIPS)':
 C_PATH='@s9s_mb_2u_lib.s9s_mb_2u(sch_1):page74_i132@pure_quanta.q_cap(chips)',
 P_PATH='@s9s_mb_2u_lib.s9s_mb_2u(sch_1):page74_i132@pure_quanta.q_cap(chips)',
 PATH='I132',
 DRAWING='@S9S_MB_2U_LIB.S9S_MB_2U(SCH_1):PAGE74',
 PHYS_PAGE='74',
 XY='(3875,1500)',
 ROT='0',
 VER='1',
 PACK_TYPE='C0402',
 CDS_LIB='pure_quanta',
 CDS_PART_NAME='Q_CAP_C0402-22UF,4V,20%,X6S,CHA',
 TOLERANCE='20%',
 MATERIAL='X6S',
 VOLTAGE='4V',
 VALUE='22UF',
 PRIM_FILE='./archive_libs/logical/q_cap/chips/chips.prt';

PART_NAME
 C1041 'Q_CAP_C0402-22UF,4V,20%,X6S,CHA':;

SECTION_NUMBER 1
 '@S9S_MB_2U_LIB.S9S_MB_2U(SCH_1):PAGE74_I128@PURE_QUANTA.Q_CAP(CHIPS)':
 C_PATH='@s9s_mb_2u_lib.s9s_mb_2u(sch_1):page74_i128@pure_quanta.q_cap(chips)',
 P_PATH='@s9s_mb_2u_lib.s9s_mb_2u(sch_1):page74_i128@pure_quanta.q_cap(chips)',
 PATH='I128',
 DRAWING='@S9S_MB_2U_LIB.S9S_MB_2U(SCH_1):PAGE74',
 PHYS_PAGE='74',
 XY='(3875,725)',
 ROT='0',
 VER='1',
 PACK_TYPE='C0402',
 CDS_LIB='pure_quanta',
 CDS_PART_NAME='Q_CAP_C0402-22UF,4V,20%,X6S,CHA',
 TOLERANCE='20%',
 MATERIAL='X6S',
 VOLTAGE='4V',
 VALUE='22UF',
 PRIM_FILE='./archive_libs/logical/q_cap/chips/chips.prt';

PART_NAME
 C1042 'Q_CAP_C0402-100NF,50V,10%,X7R,A':
 REUSE_ID='81';

SECTION_NUMBER 1
 '@S9S_MB_2U_LIB.S9S_MB_2U(SCH_1):PAGE246_I11@PURE_QUANTA.Q_CAP(CHIPS)':
 C_PATH='@s9s_mb_2u_lib.s9s_mb_2u(sch_1):page246_i11@pure_quanta.q_cap(chips)',
 P_PATH='@s9s_mb_2u_lib.s9s_mb_2u(sch_1):page260_i11@pure_quanta.q_cap(chips)',
 PATH='I11',
 DRAWING='@S9S_MB_2U_LIB.S9S_MB_2U(SCH_1):PAGE246',
 BOM_COST='VR_SYSTEM ',
 PHYS_PAGE='260',
 XY='(-5975,7550)',
 ROT='2',
 VER='1',
 PACK_TYPE='C0402',
 CDS_LIB='pure_quanta',
 CDS_PART_NAME='Q_CAP_C0402-100NF,50V,10%,X7R,A',
 TOLERANCE='10%',
 MATERIAL='X7R',
 REUSE_ID='81',
 VOLTAGE='50V',
 VALUE='100NF',
 PRIM_FILE='./archive_libs/logical/q_cap/chips/chips.prt';

PART_NAME
 C1043 'Q_CAP_C0402-22UF,4V,20%,X6S,CHA':;

SECTION_NUMBER 1
 '@S9S_MB_2U_LIB.S9S_MB_2U(SCH_1):PAGE74_I141@PURE_QUANTA.Q_CAP(CHIPS)':
 C_PATH='@s9s_mb_2u_lib.s9s_mb_2u(sch_1):page74_i141@pure_quanta.q_cap(chips)',
 P_PATH='@s9s_mb_2u_lib.s9s_mb_2u(sch_1):page74_i141@pure_quanta.q_cap(chips)',
 PATH='I141',
 DRAWING='@S9S_MB_2U_LIB.S9S_MB_2U(SCH_1):PAGE74',
 PHYS_PAGE='74',
 XY='(4300,2250)',
 ROT='0',
 VER='1',
 PACK_TYPE='C0402',
 CDS_LIB='pure_quanta',
 CDS_PART_NAME='Q_CAP_C0402-22UF,4V,20%,X6S,CHA',
 TOLERANCE='20%',
 MATERIAL='X6S',
 VOLTAGE='4V',
 VALUE='22UF',
 PRIM_FILE='./archive_libs/logical/q_cap/chips/chips.prt';

PART_NAME
 C1044 'Q_CAP_C0402-22UF,4V,20%,X6S,CHA':;

SECTION_NUMBER 1
 '@S9S_MB_2U_LIB.S9S_MB_2U(SCH_1):PAGE74_I139@PURE_QUANTA.Q_CAP(CHIPS)':
 C_PATH='@s9s_mb_2u_lib.s9s_mb_2u(sch_1):page74_i139@pure_quanta.q_cap(chips)',
 P_PATH='@s9s_mb_2u_lib.s9s_mb_2u(sch_1):page74_i139@pure_quanta.q_cap(chips)',
 PATH='I139',
 DRAWING='@S9S_MB_2U_LIB.S9S_MB_2U(SCH_1):PAGE74',
 PHYS_PAGE='74',
 XY='(4325,1500)',
 ROT='0',
 VER='1',
 PACK_TYPE='C0402',
 CDS_LIB='pure_quanta',
 CDS_PART_NAME='Q_CAP_C0402-22UF,4V,20%,X6S,CHA',
 TOLERANCE='20%',
 MATERIAL='X6S',
 VOLTAGE='4V',
 VALUE='22UF',
 PRIM_FILE='./archive_libs/logical/q_cap/chips/chips.prt';

PART_NAME
 C1045 'Q_CAP_C0402-22UF,4V,20%,X6S,CHA':;

SECTION_NUMBER 1
 '@S9S_MB_2U_LIB.S9S_MB_2U(SCH_1):PAGE74_I130@PURE_QUANTA.Q_CAP(CHIPS)':
 C_PATH='@s9s_mb_2u_lib.s9s_mb_2u(sch_1):page74_i130@pure_quanta.q_cap(chips)',
 P_PATH='@s9s_mb_2u_lib.s9s_mb_2u(sch_1):page74_i130@pure_quanta.q_cap(chips)',
 PATH='I130',
 DRAWING='@S9S_MB_2U_LIB.S9S_MB_2U(SCH_1):PAGE74',
 PHYS_PAGE='74',
 XY='(4325,725)',
 ROT='0',
 VER='1',
 PACK_TYPE='C0402',
 CDS_LIB='pure_quanta',
 CDS_PART_NAME='Q_CAP_C0402-22UF,4V,20%,X6S,CHA',
 TOLERANCE='20%',
 MATERIAL='X6S',
 VOLTAGE='4V',
 VALUE='22UF',
 PRIM_FILE='./archive_libs/logical/q_cap/chips/chips.prt';

PART_NAME
 C1096 'Q_CAP_C0201-0.1UF,6.3V,10%,X6SA':;

SECTION_NUMBER 1
 '@S9S_MB_2U_LIB.S9S_MB_2U(SCH_1):PAGE173_I80@PURE_QUANTA.Q_CAP(CHIPS)':
 C_PATH='@s9s_mb_2u_lib.s9s_mb_2u(sch_1):page173_i80@pure_quanta.q_cap(chips)',
 P_PATH='@s9s_mb_2u_lib.s9s_mb_2u(sch_1):page181_i80@pure_quanta.q_cap(chips)',
 PATH='I80',
 DRAWING='@S9S_MB_2U_LIB.S9S_MB_2U(SCH_1):PAGE173',
 PHYS_PAGE='181',
 XY='(3025,1875)',
 ROT='0',
 VER='2',
 PACK_TYPE='C0201',
 CDS_LIB='pure_quanta',
 CDS_PART_NAME='Q_CAP_C0201-0.1UF,6.3V,10%,X6SA',
 TOLERANCE='10%',
 MATERIAL='X6S',
 VOLTAGE='6.3V',
 VALUE='0.1UF',
 PRIM_FILE='./archive_libs/logical/q_cap/chips/chips.prt';

PART_NAME
 C1097 'Q_CAP_C0201-0.1UF,6.3V,10%,X6SA':;

SECTION_NUMBER 1
 '@S9S_MB_2U_LIB.S9S_MB_2U(SCH_1):PAGE173_I78@PURE_QUANTA.Q_CAP(CHIPS)':
 C_PATH='@s9s_mb_2u_lib.s9s_mb_2u(sch_1):page173_i78@pure_quanta.q_cap(chips)',
 P_PATH='@s9s_mb_2u_lib.s9s_mb_2u(sch_1):page181_i78@pure_quanta.q_cap(chips)',
 PATH='I78',
 DRAWING='@S9S_MB_2U_LIB.S9S_MB_2U(SCH_1):PAGE173',
 PHYS_PAGE='181',
 XY='(3025,1825)',
 ROT='0',
 VER='2',
 PACK_TYPE='C0201',
 LOCATION='C1097',
 CDS_LIB='pure_quanta',
 CDS_PART_NAME='Q_CAP_C0201-0.1UF,6.3V,10%,X6SA',
 TOLERANCE='10%',
 MATERIAL='X6S',
 VOLTAGE='6.3V',
 VALUE='0.1UF',
 PRIM_FILE='./archive_libs/logical/q_cap/chips/chips.prt';

PART_NAME
 C1098 'Q_CAP_DIFFBUS_C0201-DIFF BUS_0A':;

SECTION_NUMBER 1
 '@S9S_MB_2U_LIB.S9S_MB_2U(SCH_1):PAGE173_I67@PURE_QUANTA.Q_CAP_DIFFBUS(CHIPS)':
 C_PATH='@s9s_mb_2u_lib.s9s_mb_2u(sch_1):page173_i67@pure_quanta.q_cap_diffbus(c~
hips)',
 P_PATH='@s9s_mb_2u_lib.s9s_mb_2u(sch_1):page181_i67@pure_quanta.q_cap_diffbus(c~
hips)',
 PATH='I67',
 DRAWING='@S9S_MB_2U_LIB.S9S_MB_2U(SCH_1):PAGE173',
 PIN_NAMES_ROTATE='TRUE',
 PHYS_PAGE='181',
 XY='(3025,1275)',
 ROT='0',
 VER='2',
 PACK_TYPE='C0201',
 CDS_LIB='pure_quanta',
 CDS_PART_NAME='Q_CAP_DIFFBUS_C0201-DIFF BUS_0A',
 TOLERANCE='20%',
 MATERIAL='X6S',
 VOLTAGE='6.3V',
 VALUE='DIFF BUS_0.22UF',
 PRIM_FILE='./archive_libs/logical/q_cap_diffbus/chips/chips.prt';

PART_NAME
 C1099 'Q_CAP_DIFFBUS_C0201-DIFF BUS_0A':;

SECTION_NUMBER 1
 '@S9S_MB_2U_LIB.S9S_MB_2U(SCH_1):PAGE173_I66@PURE_QUANTA.Q_CAP_DIFFBUS(CHIPS)':
 C_PATH='@s9s_mb_2u_lib.s9s_mb_2u(sch_1):page173_i66@pure_quanta.q_cap_diffbus(c~
hips)',
 P_PATH='@s9s_mb_2u_lib.s9s_mb_2u(sch_1):page181_i66@pure_quanta.q_cap_diffbus(c~
hips)',
 PATH='I66',
 DRAWING='@S9S_MB_2U_LIB.S9S_MB_2U(SCH_1):PAGE173',
 PIN_NAMES_ROTATE='TRUE',
 PHYS_PAGE='181',
 XY='(3025,1225)',
 ROT='0',
 VER='2',
 PACK_TYPE='C0201',
 CDS_LIB='pure_quanta',
 CDS_PART_NAME='Q_CAP_DIFFBUS_C0201-DIFF BUS_0A',
 TOLERANCE='20%',
 MATERIAL='X6S',
 VOLTAGE='6.3V',
 VALUE='DIFF BUS_0.22UF',
 PRIM_FILE='./archive_libs/logical/q_cap_diffbus/chips/chips.prt';

PART_NAME
 C1100 'Q_CAP_DIFFBUS_C0201-DIFF BUS_0A':;

SECTION_NUMBER 1
 '@S9S_MB_2U_LIB.S9S_MB_2U(SCH_1):PAGE173_I64@PURE_QUANTA.Q_CAP_DIFFBUS(CHIPS)':
 C_PATH='@s9s_mb_2u_lib.s9s_mb_2u(sch_1):page173_i64@pure_quanta.q_cap_diffbus(c~
hips)',
 P_PATH='@s9s_mb_2u_lib.s9s_mb_2u(sch_1):page181_i64@pure_quanta.q_cap_diffbus(c~
hips)',
 PATH='I64',
 DRAWING='@S9S_MB_2U_LIB.S9S_MB_2U(SCH_1):PAGE173',
 PIN_NAMES_ROTATE='TRUE',
 PHYS_PAGE='181',
 XY='(3025,1175)',
 ROT='0',
 VER='2',
 PACK_TYPE='C0201',
 CDS_LIB='pure_quanta',
 CDS_PART_NAME='Q_CAP_DIFFBUS_C0201-DIFF BUS_0A',
 TOLERANCE='20%',
 MATERIAL='X6S',
 VOLTAGE='6.3V',
 VALUE='DIFF BUS_0.22UF',
 PRIM_FILE='./archive_libs/logical/q_cap_diffbus/chips/chips.prt';

PART_NAME
 C1101 'Q_CAP_DIFFBUS_C0201-DIFF BUS_0A':;

SECTION_NUMBER 1
 '@S9S_MB_2U_LIB.S9S_MB_2U(SCH_1):PAGE173_I65@PURE_QUANTA.Q_CAP_DIFFBUS(CHIPS)':
 C_PATH='@s9s_mb_2u_lib.s9s_mb_2u(sch_1):page173_i65@pure_quanta.q_cap_diffbus(c~
hips)',
 P_PATH='@s9s_mb_2u_lib.s9s_mb_2u(sch_1):page181_i65@pure_quanta.q_cap_diffbus(c~
hips)',
 PATH='I65',
 DRAWING='@S9S_MB_2U_LIB.S9S_MB_2U(SCH_1):PAGE173',
 PIN_NAMES_ROTATE='TRUE',
 PHYS_PAGE='181',
 XY='(3025,1125)',
 ROT='0',
 VER='2',
 PACK_TYPE='C0201',
 CDS_LIB='pure_quanta',
 CDS_PART_NAME='Q_CAP_DIFFBUS_C0201-DIFF BUS_0A',
 TOLERANCE='20%',
 MATERIAL='X6S',
 VOLTAGE='6.3V',
 VALUE='DIFF BUS_0.22UF',
 PRIM_FILE='./archive_libs/logical/q_cap_diffbus/chips/chips.prt';

PART_NAME
 C1102 'Q_CAP_DIFFBUS_C0201-DIFF BUS_0A':;

SECTION_NUMBER 1
 '@S9S_MB_2U_LIB.S9S_MB_2U(SCH_1):PAGE173_I63@PURE_QUANTA.Q_CAP_DIFFBUS(CHIPS)':
 C_PATH='@s9s_mb_2u_lib.s9s_mb_2u(sch_1):page173_i63@pure_quanta.q_cap_diffbus(c~
hips)',
 P_PATH='@s9s_mb_2u_lib.s9s_mb_2u(sch_1):page181_i63@pure_quanta.q_cap_diffbus(c~
hips)',
 PATH='I63',
 DRAWING='@S9S_MB_2U_LIB.S9S_MB_2U(SCH_1):PAGE173',
 PIN_NAMES_ROTATE='TRUE',
 PHYS_PAGE='181',
 XY='(3025,1075)',
 ROT='0',
 VER='2',
 PACK_TYPE='C0201',
 CDS_LIB='pure_quanta',
 CDS_PART_NAME='Q_CAP_DIFFBUS_C0201-DIFF BUS_0A',
 TOLERANCE='20%',
 MATERIAL='X6S',
 VOLTAGE='6.3V',
 VALUE='DIFF BUS_0.22UF',
 PRIM_FILE='./archive_libs/logical/q_cap_diffbus/chips/chips.prt';

PART_NAME
 C1103 'Q_CAP_DIFFBUS_C0201-DIFF BUS_0A':;

SECTION_NUMBER 1
 '@S9S_MB_2U_LIB.S9S_MB_2U(SCH_1):PAGE173_I62@PURE_QUANTA.Q_CAP_DIFFBUS(CHIPS)':
 C_PATH='@s9s_mb_2u_lib.s9s_mb_2u(sch_1):page173_i62@pure_quanta.q_cap_diffbus(c~
hips)',
 P_PATH='@s9s_mb_2u_lib.s9s_mb_2u(sch_1):page181_i62@pure_quanta.q_cap_diffbus(c~
hips)',
 PATH='I62',
 DRAWING='@S9S_MB_2U_LIB.S9S_MB_2U(SCH_1):PAGE173',
 PIN_NAMES_ROTATE='TRUE',
 PHYS_PAGE='181',
 XY='(3025,1025)',
 ROT='0',
 VER='2',
 PACK_TYPE='C0201',
 CDS_LIB='pure_quanta',
 CDS_PART_NAME='Q_CAP_DIFFBUS_C0201-DIFF BUS_0A',
 TOLERANCE='20%',
 MATERIAL='X6S',
 VOLTAGE='6.3V',
 VALUE='DIFF BUS_0.22UF',
 PRIM_FILE='./archive_libs/logical/q_cap_diffbus/chips/chips.prt';

PART_NAME
 C1104 'Q_CAP_DIFFBUS_C0201-DIFF BUS_0A':;

SECTION_NUMBER 1
 '@S9S_MB_2U_LIB.S9S_MB_2U(SCH_1):PAGE173_I61@PURE_QUANTA.Q_CAP_DIFFBUS(CHIPS)':
 C_PATH='@s9s_mb_2u_lib.s9s_mb_2u(sch_1):page173_i61@pure_quanta.q_cap_diffbus(c~
hips)',
 P_PATH='@s9s_mb_2u_lib.s9s_mb_2u(sch_1):page181_i61@pure_quanta.q_cap_diffbus(c~
hips)',
 PATH='I61',
 DRAWING='@S9S_MB_2U_LIB.S9S_MB_2U(SCH_1):PAGE173',
 PIN_NAMES_ROTATE='TRUE',
 PHYS_PAGE='181',
 XY='(3025,975)',
 ROT='0',
 VER='2',
 PACK_TYPE='C0201',
 CDS_LIB='pure_quanta',
 CDS_PART_NAME='Q_CAP_DIFFBUS_C0201-DIFF BUS_0A',
 TOLERANCE='20%',
 MATERIAL='X6S',
 VOLTAGE='6.3V',
 VALUE='DIFF BUS_0.22UF',
 PRIM_FILE='./archive_libs/logical/q_cap_diffbus/chips/chips.prt';

PART_NAME
 C1105 'Q_CAP_DIFFBUS_C0201-DIFF BUS_0A':;

SECTION_NUMBER 1
 '@S9S_MB_2U_LIB.S9S_MB_2U(SCH_1):PAGE173_I60@PURE_QUANTA.Q_CAP_DIFFBUS(CHIPS)':
 C_PATH='@s9s_mb_2u_lib.s9s_mb_2u(sch_1):page173_i60@pure_quanta.q_cap_diffbus(c~
hips)',
 P_PATH='@s9s_mb_2u_lib.s9s_mb_2u(sch_1):page181_i60@pure_quanta.q_cap_diffbus(c~
hips)',
 PATH='I60',
 DRAWING='@S9S_MB_2U_LIB.S9S_MB_2U(SCH_1):PAGE173',
 PIN_NAMES_ROTATE='TRUE',
 PHYS_PAGE='181',
 XY='(3025,925)',
 ROT='0',
 VER='2',
 PACK_TYPE='C0201',
 CDS_LIB='pure_quanta',
 CDS_PART_NAME='Q_CAP_DIFFBUS_C0201-DIFF BUS_0A',
 TOLERANCE='20%',
 MATERIAL='X6S',
 VOLTAGE='6.3V',
 VALUE='DIFF BUS_0.22UF',
 PRIM_FILE='./archive_libs/logical/q_cap_diffbus/chips/chips.prt';

PART_NAME
 C1113 'Q_CAP_C0402-0.01UF,50V,10%,X7RA':;

SECTION_NUMBER 1
 '@S9S_MB_2U_LIB.S9S_MB_2U(SCH_1):PAGE202_I99@PURE_QUANTA.Q_CAP(CHIPS)':
 C_PATH='@s9s_mb_2u_lib.s9s_mb_2u(sch_1):page202_i99@pure_quanta.q_cap(chips)',
 P_PATH='@s9s_mb_2u_lib.s9s_mb_2u(sch_1):page217_i99@pure_quanta.q_cap(chips)',
 PATH='I99',
 DRAWING='@S9S_MB_2U_LIB.S9S_MB_2U(SCH_1):PAGE202',
 PHYS_PAGE='217',
 XY='(-4225,-2125)',
 ROT='0',
 VER='1',
 PACK_TYPE='C0402',
 CDS_LIB='pure_quanta',
 CDS_PART_NAME='Q_CAP_C0402-0.01UF,50V,10%,X7RA',
 TOLERANCE='10%',
 MATERIAL='X7R',
 VOLTAGE='50V',
 VALUE='0.01UF',
 PRIM_FILE='./archive_libs/logical/q_cap/chips/chips.prt';

PART_NAME
 C1118 'Q_CAP_C0402-0.01UF,50V,10%,X7RA':;

SECTION_NUMBER 1
 '@S9S_MB_2U_LIB.S9S_MB_2U(SCH_1):PAGE202_I97@PURE_QUANTA.Q_CAP(CHIPS)':
 C_PATH='@s9s_mb_2u_lib.s9s_mb_2u(sch_1):page202_i97@pure_quanta.q_cap(chips)',
 P_PATH='@s9s_mb_2u_lib.s9s_mb_2u(sch_1):page217_i97@pure_quanta.q_cap(chips)',
 PATH='I97',
 DRAWING='@S9S_MB_2U_LIB.S9S_MB_2U(SCH_1):PAGE202',
 PHYS_PAGE='217',
 XY='(-3975,-2125)',
 ROT='0',
 VER='1',
 PACK_TYPE='C0402',
 CDS_LIB='pure_quanta',
 CDS_PART_NAME='Q_CAP_C0402-0.01UF,50V,10%,X7RA',
 TOLERANCE='10%',
 MATERIAL='X7R',
 VOLTAGE='50V',
 VALUE='0.01UF',
 PRIM_FILE='./archive_libs/logical/q_cap/chips/chips.prt';

PART_NAME
 C1122 'Q_CAP_0402-0.1UF,25V,10%,X7R,CA':;

SECTION_NUMBER 1
 '@S9S_MB_2U_LIB.S9S_MB_2U(SCH_1):PAGE202_I56@PURE_QUANTA.Q_CAP(CHIPS)':
 C_PATH='@s9s_mb_2u_lib.s9s_mb_2u(sch_1):page202_i56@pure_quanta.q_cap(chips)',
 P_PATH='@s9s_mb_2u_lib.s9s_mb_2u(sch_1):page217_i56@pure_quanta.q_cap(chips)',
 PATH='I56',
 DRAWING='@S9S_MB_2U_LIB.S9S_MB_2U(SCH_1):PAGE202',
 PHYS_PAGE='217',
 XY='(200,-1000)',
 ROT='0',
 VER='1',
 PACK_TYPE='0402',
 CDS_LIB='pure_quanta',
 CDS_PART_NAME='Q_CAP_0402-0.1UF,25V,10%,X7R,CA',
 TOLERANCE='10%',
 MATERIAL='X7R',
 VOLTAGE='25V',
 VALUE='0.1UF',
 PRIM_FILE='./archive_libs/logical/q_cap/chips/chips.prt';

PART_NAME
 C1124 'Q_CAP_C0402-0.01UF,50V,10%,X7RA':;

SECTION_NUMBER 1
 '@S9S_MB_2U_LIB.S9S_MB_2U(SCH_1):PAGE202_I100@PURE_QUANTA.Q_CAP(CHIPS)':
 C_PATH='@s9s_mb_2u_lib.s9s_mb_2u(sch_1):page202_i100@pure_quanta.q_cap(chips)',
 P_PATH='@s9s_mb_2u_lib.s9s_mb_2u(sch_1):page217_i100@pure_quanta.q_cap(chips)',
 PATH='I100',
 DRAWING='@S9S_MB_2U_LIB.S9S_MB_2U(SCH_1):PAGE202',
 PHYS_PAGE='217',
 XY='(-4500,-2125)',
 ROT='0',
 VER='1',
 PACK_TYPE='C0402',
 CDS_LIB='pure_quanta',
 CDS_PART_NAME='Q_CAP_C0402-0.01UF,50V,10%,X7RA',
 TOLERANCE='10%',
 MATERIAL='X7R',
 VOLTAGE='50V',
 VALUE='0.01UF',
 PRIM_FILE='./archive_libs/logical/q_cap/chips/chips.prt';

PART_NAME
 C1127 'Q_CAP_C0402-0.01UF,50V,10%,X7RA':;

SECTION_NUMBER 1
 '@S9S_MB_2U_LIB.S9S_MB_2U(SCH_1):PAGE202_I52@PURE_QUANTA.Q_CAP(CHIPS)':
 C_PATH='@s9s_mb_2u_lib.s9s_mb_2u(sch_1):page202_i52@pure_quanta.q_cap(chips)',
 P_PATH='@s9s_mb_2u_lib.s9s_mb_2u(sch_1):page217_i52@pure_quanta.q_cap(chips)',
 PATH='I52',
 DRAWING='@S9S_MB_2U_LIB.S9S_MB_2U(SCH_1):PAGE202',
 PHYS_PAGE='217',
 XY='(450,-1000)',
 ROT='0',
 VER='1',
 PACK_TYPE='C0402',
 CDS_LIB='pure_quanta',
 CDS_PART_NAME='Q_CAP_C0402-0.01UF,50V,10%,X7RA',
 TOLERANCE='10%',
 MATERIAL='X7R',
 VOLTAGE='50V',
 VALUE='0.01UF',
 PRIM_FILE='./archive_libs/logical/q_cap/chips/chips.prt';

PART_NAME
 C1133 'Q_CAP_C0402-0.01UF,50V,10%,X7RA':;

SECTION_NUMBER 1
 '@S9S_MB_2U_LIB.S9S_MB_2U(SCH_1):PAGE202_I51@PURE_QUANTA.Q_CAP(CHIPS)':
 C_PATH='@s9s_mb_2u_lib.s9s_mb_2u(sch_1):page202_i51@pure_quanta.q_cap(chips)',
 P_PATH='@s9s_mb_2u_lib.s9s_mb_2u(sch_1):page217_i51@pure_quanta.q_cap(chips)',
 PATH='I51',
 DRAWING='@S9S_MB_2U_LIB.S9S_MB_2U(SCH_1):PAGE202',
 PHYS_PAGE='217',
 XY='(700,-1000)',
 ROT='0',
 VER='1',
 PACK_TYPE='C0402',
 CDS_LIB='pure_quanta',
 CDS_PART_NAME='Q_CAP_C0402-0.01UF,50V,10%,X7RA',
 TOLERANCE='10%',
 MATERIAL='X7R',
 VOLTAGE='50V',
 VALUE='0.01UF',
 PRIM_FILE='./archive_libs/logical/q_cap/chips/chips.prt';

PART_NAME
 C1138 'Q_CAP_C0402-0.01UF,50V,10%,X7RA':;

SECTION_NUMBER 1
 '@S9S_MB_2U_LIB.S9S_MB_2U(SCH_1):PAGE202_I50@PURE_QUANTA.Q_CAP(CHIPS)':
 C_PATH='@s9s_mb_2u_lib.s9s_mb_2u(sch_1):page202_i50@pure_quanta.q_cap(chips)',
 P_PATH='@s9s_mb_2u_lib.s9s_mb_2u(sch_1):page217_i50@pure_quanta.q_cap(chips)',
 PATH='I50',
 DRAWING='@S9S_MB_2U_LIB.S9S_MB_2U(SCH_1):PAGE202',
 PHYS_PAGE='217',
 XY='(950,-1000)',
 ROT='0',
 VER='1',
 PACK_TYPE='C0402',
 CDS_LIB='pure_quanta',
 CDS_PART_NAME='Q_CAP_C0402-0.01UF,50V,10%,X7RA',
 TOLERANCE='10%',
 MATERIAL='X7R',
 VOLTAGE='50V',
 VALUE='0.01UF',
 PRIM_FILE='./archive_libs/logical/q_cap/chips/chips.prt';

PART_NAME
 C1142 'Q_CAP_C0402-0.01UF,50V,10%,X7RA':;

SECTION_NUMBER 1
 '@S9S_MB_2U_LIB.S9S_MB_2U(SCH_1):PAGE202_I49@PURE_QUANTA.Q_CAP(CHIPS)':
 C_PATH='@s9s_mb_2u_lib.s9s_mb_2u(sch_1):page202_i49@pure_quanta.q_cap(chips)',
 P_PATH='@s9s_mb_2u_lib.s9s_mb_2u(sch_1):page217_i49@pure_quanta.q_cap(chips)',
 PATH='I49',
 DRAWING='@S9S_MB_2U_LIB.S9S_MB_2U(SCH_1):PAGE202',
 PHYS_PAGE='217',
 XY='(1200,-1000)',
 ROT='0',
 VER='1',
 PACK_TYPE='C0402',
 CDS_LIB='pure_quanta',
 CDS_PART_NAME='Q_CAP_C0402-0.01UF,50V,10%,X7RA',
 TOLERANCE='10%',
 MATERIAL='X7R',
 VOLTAGE='50V',
 VALUE='0.01UF',
 PRIM_FILE='./archive_libs/logical/q_cap/chips/chips.prt';

PART_NAME
 C1146 'Q_CAP_C0402-0.01UF,50V,10%,X7RA':;

SECTION_NUMBER 1
 '@S9S_MB_2U_LIB.S9S_MB_2U(SCH_1):PAGE202_I15@PURE_QUANTA.Q_CAP(CHIPS)':
 C_PATH='@s9s_mb_2u_lib.s9s_mb_2u(sch_1):page202_i15@pure_quanta.q_cap(chips)',
 P_PATH='@s9s_mb_2u_lib.s9s_mb_2u(sch_1):page217_i15@pure_quanta.q_cap(chips)',
 PATH='I15',
 DRAWING='@S9S_MB_2U_LIB.S9S_MB_2U(SCH_1):PAGE202',
 PHYS_PAGE='217',
 XY='(1450,-1000)',
 ROT='0',
 VER='1',
 PACK_TYPE='C0402',
 CDS_LIB='pure_quanta',
 CDS_PART_NAME='Q_CAP_C0402-0.01UF,50V,10%,X7RA',
 TOLERANCE='10%',
 MATERIAL='X7R',
 VOLTAGE='50V',
 VALUE='0.01UF',
 PRIM_FILE='./archive_libs/logical/q_cap/chips/chips.prt';

PART_NAME
 C1150 'Q_CAP_0402-0.1UF,25V,10%,X7R,CA':;

SECTION_NUMBER 1
 '@S9S_MB_2U_LIB.S9S_MB_2U(SCH_1):PAGE202_I121@PURE_QUANTA.Q_CAP(CHIPS)':
 C_PATH='@s9s_mb_2u_lib.s9s_mb_2u(sch_1):page202_i121@pure_quanta.q_cap(chips)',
 P_PATH='@s9s_mb_2u_lib.s9s_mb_2u(sch_1):page217_i121@pure_quanta.q_cap(chips)',
 PATH='I121',
 DRAWING='@S9S_MB_2U_LIB.S9S_MB_2U(SCH_1):PAGE202',
 PHYS_PAGE='217',
 XY='(1450,2375)',
 ROT='0',
 VER='1',
 PACK_TYPE='0402',
 CDS_LIB='pure_quanta',
 CDS_PART_NAME='Q_CAP_0402-0.1UF,25V,10%,X7R,CA',
 TOLERANCE='10%',
 MATERIAL='X7R',
 VOLTAGE='25V',
 VALUE='0.1UF',
 PRIM_FILE='./archive_libs/logical/q_cap/chips/chips.prt';

PART_NAME
 C1152 'Q_CAP_C0402-0.01UF,50V,10%,X7RA':;

SECTION_NUMBER 1
 '@S9S_MB_2U_LIB.S9S_MB_2U(SCH_1):PAGE202_I5@PURE_QUANTA.Q_CAP(CHIPS)':
 C_PATH='@s9s_mb_2u_lib.s9s_mb_2u(sch_1):page202_i5@pure_quanta.q_cap(chips)',
 P_PATH='@s9s_mb_2u_lib.s9s_mb_2u(sch_1):page217_i5@pure_quanta.q_cap(chips)',
 PATH='I5',
 DRAWING='@S9S_MB_2U_LIB.S9S_MB_2U(SCH_1):PAGE202',
 PHYS_PAGE='217',
 XY='(1950,2375)',
 ROT='0',
 VER='1',
 PACK_TYPE='C0402',
 CDS_LIB='pure_quanta',
 CDS_PART_NAME='Q_CAP_C0402-0.01UF,50V,10%,X7RA',
 TOLERANCE='10%',
 MATERIAL='X7R',
 VOLTAGE='50V',
 VALUE='0.01UF',
 PRIM_FILE='./archive_libs/logical/q_cap/chips/chips.prt';

PART_NAME
 C1154 'Q_CAP_C0402-0.01UF,50V,10%,X7RA':;

SECTION_NUMBER 1
 '@S9S_MB_2U_LIB.S9S_MB_2U(SCH_1):PAGE202_I3@PURE_QUANTA.Q_CAP(CHIPS)':
 C_PATH='@s9s_mb_2u_lib.s9s_mb_2u(sch_1):page202_i3@pure_quanta.q_cap(chips)',
 P_PATH='@s9s_mb_2u_lib.s9s_mb_2u(sch_1):page217_i3@pure_quanta.q_cap(chips)',
 PATH='I3',
 DRAWING='@S9S_MB_2U_LIB.S9S_MB_2U(SCH_1):PAGE202',
 PHYS_PAGE='217',
 XY='(2200,2375)',
 ROT='0',
 VER='1',
 PACK_TYPE='C0402',
 CDS_LIB='pure_quanta',
 CDS_PART_NAME='Q_CAP_C0402-0.01UF,50V,10%,X7RA',
 TOLERANCE='10%',
 MATERIAL='X7R',
 VOLTAGE='50V',
 VALUE='0.01UF',
 PRIM_FILE='./archive_libs/logical/q_cap/chips/chips.prt';

PART_NAME
 C1170 'Q_CAP_C0805-10UF,16V,10%,X6S,CA':
 REUSE_ID='6';

SECTION_NUMBER 1
 '@S9S_MB_2U_LIB.S9S_MB_2U(SCH_1):PAGE246_I24@PURE_QUANTA.Q_CAP(CHIPS)':
 C_PATH='@s9s_mb_2u_lib.s9s_mb_2u(sch_1):page246_i24@pure_quanta.q_cap(chips)',
 P_PATH='@s9s_mb_2u_lib.s9s_mb_2u(sch_1):page260_i24@pure_quanta.q_cap(chips)',
 PATH='I24',
 DRAWING='@S9S_MB_2U_LIB.S9S_MB_2U(SCH_1):PAGE246',
 BOM_COST='VR_SYSTEM ',
 PHYS_PAGE='260',
 XY='(-5650,7550)',
 ROT='2',
 VER='1',
 PACK_TYPE='C0805',
 CDS_LIB='pure_quanta',
 CDS_PART_NAME='Q_CAP_C0805-10UF,16V,10%,X6S,CA',
 TOLERANCE='10%',
 MATERIAL='X6S',
 REUSE_ID='6',
 VOLTAGE='16V',
 VALUE='10UF',
 PRIM_FILE='./archive_libs/logical/q_cap/chips/chips.prt';

PART_NAME
 C1171 'Q_CAP_C0805-10UF,16V,10%,EMPTYA':
 REUSE_ID='8';

SECTION_NUMBER 1
 '@S9S_MB_2U_LIB.S9S_MB_2U(SCH_1):PAGE246_I25@PURE_QUANTA.Q_CAP(CHIPS)':
 C_PATH='@s9s_mb_2u_lib.s9s_mb_2u(sch_1):page246_i25@pure_quanta.q_cap(chips)',
 P_PATH='@s9s_mb_2u_lib.s9s_mb_2u(sch_1):page260_i25@pure_quanta.q_cap(chips)',
 PATH='I25',
 DRAWING='@S9S_MB_2U_LIB.S9S_MB_2U(SCH_1):PAGE246',
 BOM_COST='VR_SYSTEM ',
 PHYS_PAGE='260',
 XY='(-5325,7550)',
 ROT='2',
 VER='1',
 PACK_TYPE='C0805',
 CDS_LIB='pure_quanta',
 CDS_PART_NAME='Q_CAP_C0805-10UF,16V,10%,EMPTYA',
 TOLERANCE='10%',
 MATERIAL='EMPTY',
 REUSE_ID='8',
 VOLTAGE='16V',
 VALUE='10UF',
 PRIM_FILE='./archive_libs/logical/q_cap/chips/chips.prt';

PART_NAME
 C1172 'Q_CAP_C0402-100NF,50V,10%,X7R,A':;

SECTION_NUMBER 1
 '@S9S_MB_2U_LIB.S9S_MB_2U(SCH_1):PAGE246_I2@PURE_QUANTA.Q_CAP(CHIPS)':
 C_PATH='@s9s_mb_2u_lib.s9s_mb_2u(sch_1):page246_i2@pure_quanta.q_cap(chips)',
 P_PATH='@s9s_mb_2u_lib.s9s_mb_2u(sch_1):page260_i2@pure_quanta.q_cap(chips)',
 PATH='I2',
 DRAWING='@S9S_MB_2U_LIB.S9S_MB_2U(SCH_1):PAGE246',
 BOM_COST='VR_SYSTEM ',
 PHYS_PAGE='260',
 XY='(-4075,3375)',
 ROT='0',
 VER='1',
 PACK_TYPE='C0402',
 CDS_LIB='pure_quanta',
 CDS_PART_NAME='Q_CAP_C0402-100NF,50V,10%,X7R,A',
 TOLERANCE='10%',
 MATERIAL='X7R',
 VOLTAGE='50V',
 VALUE='100NF',
 PRIM_FILE='./archive_libs/logical/q_cap/chips/chips.prt';

PART_NAME
 C1173 'Q_CAP_0402-0.1UF,25V,10%,X7R,CA':;

SECTION_NUMBER 1
 '@S9S_MB_2U_LIB.S9S_MB_2U(SCH_1):PAGE152_I4@PURE_QUANTA.Q_CAP(CHIPS)':
 C_PATH='@s9s_mb_2u_lib.s9s_mb_2u(sch_1):page152_i4@pure_quanta.q_cap(chips)',
 P_PATH='@s9s_mb_2u_lib.s9s_mb_2u(sch_1):page155_i4@pure_quanta.q_cap(chips)',
 PATH='I4',
 DRAWING='@S9S_MB_2U_LIB.S9S_MB_2U(SCH_1):PAGE152',
 PHYS_PAGE='155',
 XY='(-8200,7550)',
 ROT='2',
 VER='1',
 PACK_TYPE='0402',
 CDS_LIB='pure_quanta',
 CDS_PART_NAME='Q_CAP_0402-0.1UF,25V,10%,X7R,CA',
 TOLERANCE='10%',
 MATERIAL='X7R',
 VOLTAGE='25V',
 VALUE='0.1UF',
 PRIM_FILE='./archive_libs/logical/q_cap/chips/chips.prt';

PART_NAME
 C1175 'Q_CAP_0402-0.1UF,25V,10%,X7R,CA':;

SECTION_NUMBER 1
 '@S9S_MB_2U_LIB.S9S_MB_2U(SCH_1):PAGE152_I24@PURE_QUANTA.Q_CAP(CHIPS)':
 C_PATH='@s9s_mb_2u_lib.s9s_mb_2u(sch_1):page152_i24@pure_quanta.q_cap(chips)',
 P_PATH='@s9s_mb_2u_lib.s9s_mb_2u(sch_1):page155_i24@pure_quanta.q_cap(chips)',
 PATH='I24',
 DRAWING='@S9S_MB_2U_LIB.S9S_MB_2U(SCH_1):PAGE152',
 PHYS_PAGE='155',
 XY='(-8075,4650)',
 ROT='0',
 VER='1',
 PACK_TYPE='0402',
 CDS_LIB='pure_quanta',
 CDS_PART_NAME='Q_CAP_0402-0.1UF,25V,10%,X7R,CA',
 TOLERANCE='10%',
 MATERIAL='X7R',
 VOLTAGE='25V',
 VALUE='0.1UF',
 PRIM_FILE='./archive_libs/logical/q_cap/chips/chips.prt';

PART_NAME
 C1177 'Q_CAP_C0402-1UF,25V,10%,X6S,CHA':;

SECTION_NUMBER 1
 '@S9S_MB_2U_LIB.S9S_MB_2U(SCH_1):PAGE189_I128@PURE_QUANTA.Q_CAP(CHIPS)':
 C_PATH='@s9s_mb_2u_lib.s9s_mb_2u(sch_1):page189_i128@pure_quanta.q_cap(chips)',
 P_PATH='@s9s_mb_2u_lib.s9s_mb_2u(sch_1):page201_i128@pure_quanta.q_cap(chips)',
 PATH='I128',
 DRAWING='@S9S_MB_2U_LIB.S9S_MB_2U(SCH_1):PAGE189',
 PHYS_PAGE='201',
 XY='(3000,1125)',
 ROT='0',
 VER='1',
 PACK_TYPE='C0402',
 CDS_LIB='pure_quanta',
 CDS_PART_NAME='Q_CAP_C0402-1UF,25V,10%,X6S,CHA',
 TOLERANCE='10%',
 MATERIAL='X6S',
 VOLTAGE='25V',
 VALUE='1UF',
 PRIM_FILE='./archive_libs/logical/q_cap/chips/chips.prt';

PART_NAME
 C1178 'Q_CAP_C0603-22UF,4V,20%,X6S,CHA':;

SECTION_NUMBER 1
 '@S9S_MB_2U_LIB.S9S_MB_2U(SCH_1):PAGE181_I6@PURE_QUANTA.Q_CAP(CHIPS)':
 C_PATH='@s9s_mb_2u_lib.s9s_mb_2u(sch_1):page181_i6@pure_quanta.q_cap(chips)',
 P_PATH='@s9s_mb_2u_lib.s9s_mb_2u(sch_1):page189_i6@pure_quanta.q_cap(chips)',
 PATH='I6',
 DRAWING='@S9S_MB_2U_LIB.S9S_MB_2U(SCH_1):PAGE181',
 PHYS_PAGE='189',
 XY='(-2250,3825)',
 ROT='0',
 VER='1',
 PACK_TYPE='C0603',
 CDS_LIB='pure_quanta',
 CDS_PART_NAME='Q_CAP_C0603-22UF,4V,20%,X6S,CHA',
 TOLERANCE='20%',
 MATERIAL='X6S',
 VOLTAGE='4V',
 VALUE='22UF',
 PRIM_FILE='./archive_libs/logical/q_cap/chips/chips.prt';

PART_NAME
 C1181 'Q_CAP_C0603-22UF,4V,20%,X6S,CHA':;

SECTION_NUMBER 1
 '@S9S_MB_2U_LIB.S9S_MB_2U(SCH_1):PAGE181_I27@PURE_QUANTA.Q_CAP(CHIPS)':
 C_PATH='@s9s_mb_2u_lib.s9s_mb_2u(sch_1):page181_i27@pure_quanta.q_cap(chips)',
 P_PATH='@s9s_mb_2u_lib.s9s_mb_2u(sch_1):page189_i27@pure_quanta.q_cap(chips)',
 PATH='I27',
 DRAWING='@S9S_MB_2U_LIB.S9S_MB_2U(SCH_1):PAGE181',
 PHYS_PAGE='189',
 XY='(-2250,2500)',
 ROT='0',
 VER='1',
 PACK_TYPE='C0603',
 CDS_LIB='pure_quanta',
 CDS_PART_NAME='Q_CAP_C0603-22UF,4V,20%,X6S,CHA',
 TOLERANCE='20%',
 MATERIAL='X6S',
 VOLTAGE='4V',
 VALUE='22UF',
 PRIM_FILE='./archive_libs/logical/q_cap/chips/chips.prt';

PART_NAME
 C1182 'Q_CAP_C0603-22UF,4V,20%,X6S,CHA':;

SECTION_NUMBER 1
 '@S9S_MB_2U_LIB.S9S_MB_2U(SCH_1):PAGE181_I42@PURE_QUANTA.Q_CAP(CHIPS)':
 C_PATH='@s9s_mb_2u_lib.s9s_mb_2u(sch_1):page181_i42@pure_quanta.q_cap(chips)',
 P_PATH='@s9s_mb_2u_lib.s9s_mb_2u(sch_1):page189_i42@pure_quanta.q_cap(chips)',
 PATH='I42',
 DRAWING='@S9S_MB_2U_LIB.S9S_MB_2U(SCH_1):PAGE181',
 PHYS_PAGE='189',
 XY='(-2250,1200)',
 ROT='0',
 VER='1',
 PACK_TYPE='C0603',
 CDS_LIB='pure_quanta',
 CDS_PART_NAME='Q_CAP_C0603-22UF,4V,20%,X6S,CHA',
 TOLERANCE='20%',
 MATERIAL='X6S',
 VOLTAGE='4V',
 VALUE='22UF',
 PRIM_FILE='./archive_libs/logical/q_cap/chips/chips.prt';

PART_NAME
 C1183 'Q_CAP_C0402-2.2UF,10V,10%,X6S,A':;

SECTION_NUMBER 1
 '@S9S_MB_2U_LIB.S9S_MB_2U(SCH_1):PAGE181_I51@PURE_QUANTA.Q_CAP(CHIPS)':
 C_PATH='@s9s_mb_2u_lib.s9s_mb_2u(sch_1):page181_i51@pure_quanta.q_cap(chips)',
 P_PATH='@s9s_mb_2u_lib.s9s_mb_2u(sch_1):page189_i51@pure_quanta.q_cap(chips)',
 PATH='I51',
 DRAWING='@S9S_MB_2U_LIB.S9S_MB_2U(SCH_1):PAGE181',
 PHYS_PAGE='189',
 XY='(-2250,475)',
 ROT='0',
 VER='1',
 PACK_TYPE='C0402',
 CDS_LIB='pure_quanta',
 CDS_PART_NAME='Q_CAP_C0402-2.2UF,10V,10%,X6S,A',
 TOLERANCE='10%',
 MATERIAL='X6S',
 VOLTAGE='10V',
 VALUE='2.2UF',
 PRIM_FILE='./archive_libs/logical/q_cap/chips/chips.prt';

PART_NAME
 C1184 'Q_CAP_C0603-22UF,6.3V,20%,X6S,A':;

SECTION_NUMBER 1
 '@S9S_MB_2U_LIB.S9S_MB_2U(SCH_1):PAGE181_I91@PURE_QUANTA.Q_CAP(CHIPS)':
 C_PATH='@s9s_mb_2u_lib.s9s_mb_2u(sch_1):page181_i91@pure_quanta.q_cap(chips)',
 P_PATH='@s9s_mb_2u_lib.s9s_mb_2u(sch_1):page189_i91@pure_quanta.q_cap(chips)',
 PATH='I91',
 DRAWING='@S9S_MB_2U_LIB.S9S_MB_2U(SCH_1):PAGE181',
 PHYS_PAGE='189',
 XY='(-2250,-725)',
 ROT='0',
 VER='1',
 PACK_TYPE='C0603',
 CDS_LIB='pure_quanta',
 CDS_PART_NAME='Q_CAP_C0603-22UF,6.3V,20%,X6S,A',
 TOLERANCE='20%',
 MATERIAL='X6S',
 VOLTAGE='6.3V',
 VALUE='22UF',
 PRIM_FILE='./archive_libs/logical/q_cap/chips/chips.prt';

PART_NAME
 C1185 'Q_CAP_C0603-22UF,4V,20%,X6S,CHA':;

SECTION_NUMBER 1
 '@S9S_MB_2U_LIB.S9S_MB_2U(SCH_1):PAGE181_I7@PURE_QUANTA.Q_CAP(CHIPS)':
 C_PATH='@s9s_mb_2u_lib.s9s_mb_2u(sch_1):page181_i7@pure_quanta.q_cap(chips)',
 P_PATH='@s9s_mb_2u_lib.s9s_mb_2u(sch_1):page189_i7@pure_quanta.q_cap(chips)',
 PATH='I7',
 DRAWING='@S9S_MB_2U_LIB.S9S_MB_2U(SCH_1):PAGE181',
 PHYS_PAGE='189',
 XY='(-1800,3825)',
 ROT='0',
 VER='1',
 PACK_TYPE='C0603',
 CDS_LIB='pure_quanta',
 CDS_PART_NAME='Q_CAP_C0603-22UF,4V,20%,X6S,CHA',
 TOLERANCE='20%',
 MATERIAL='X6S',
 VOLTAGE='4V',
 VALUE='22UF',
 PRIM_FILE='./archive_libs/logical/q_cap/chips/chips.prt';

PART_NAME
 C1186 'Q_CAP_C0603-22UF,4V,20%,X6S,CHA':;

SECTION_NUMBER 1
 '@S9S_MB_2U_LIB.S9S_MB_2U(SCH_1):PAGE181_I25@PURE_QUANTA.Q_CAP(CHIPS)':
 C_PATH='@s9s_mb_2u_lib.s9s_mb_2u(sch_1):page181_i25@pure_quanta.q_cap(chips)',
 P_PATH='@s9s_mb_2u_lib.s9s_mb_2u(sch_1):page189_i25@pure_quanta.q_cap(chips)',
 PATH='I25',
 DRAWING='@S9S_MB_2U_LIB.S9S_MB_2U(SCH_1):PAGE181',
 PHYS_PAGE='189',
 XY='(-1800,2500)',
 ROT='0',
 VER='1',
 PACK_TYPE='C0603',
 CDS_LIB='pure_quanta',
 CDS_PART_NAME='Q_CAP_C0603-22UF,4V,20%,X6S,CHA',
 TOLERANCE='20%',
 MATERIAL='X6S',
 VOLTAGE='4V',
 VALUE='22UF',
 PRIM_FILE='./archive_libs/logical/q_cap/chips/chips.prt';

PART_NAME
 C1187 'Q_CAP_C0603-22UF,4V,20%,X6S,CHA':;

SECTION_NUMBER 1
 '@S9S_MB_2U_LIB.S9S_MB_2U(SCH_1):PAGE181_I40@PURE_QUANTA.Q_CAP(CHIPS)':
 C_PATH='@s9s_mb_2u_lib.s9s_mb_2u(sch_1):page181_i40@pure_quanta.q_cap(chips)',
 P_PATH='@s9s_mb_2u_lib.s9s_mb_2u(sch_1):page189_i40@pure_quanta.q_cap(chips)',
 PATH='I40',
 DRAWING='@S9S_MB_2U_LIB.S9S_MB_2U(SCH_1):PAGE181',
 PHYS_PAGE='189',
 XY='(-1800,1200)',
 ROT='0',
 VER='1',
 PACK_TYPE='C0603',
 CDS_LIB='pure_quanta',
 CDS_PART_NAME='Q_CAP_C0603-22UF,4V,20%,X6S,CHA',
 TOLERANCE='20%',
 MATERIAL='X6S',
 VOLTAGE='4V',
 VALUE='22UF',
 PRIM_FILE='./archive_libs/logical/q_cap/chips/chips.prt';

PART_NAME
 C1189 'Q_CAP_C0402-2.2UF,10V,10%,X6S,A':;

SECTION_NUMBER 1
 '@S9S_MB_2U_LIB.S9S_MB_2U(SCH_1):PAGE181_I58@PURE_QUANTA.Q_CAP(CHIPS)':
 C_PATH='@s9s_mb_2u_lib.s9s_mb_2u(sch_1):page181_i58@pure_quanta.q_cap(chips)',
 P_PATH='@s9s_mb_2u_lib.s9s_mb_2u(sch_1):page189_i58@pure_quanta.q_cap(chips)',
 PATH='I58',
 DRAWING='@S9S_MB_2U_LIB.S9S_MB_2U(SCH_1):PAGE181',
 PHYS_PAGE='189',
 XY='(-1800,475)',
 ROT='0',
 VER='1',
 PACK_TYPE='C0402',
 CDS_LIB='pure_quanta',
 CDS_PART_NAME='Q_CAP_C0402-2.2UF,10V,10%,X6S,A',
 TOLERANCE='10%',
 MATERIAL='X6S',
 VOLTAGE='10V',
 VALUE='2.2UF',
 PRIM_FILE='./archive_libs/logical/q_cap/chips/chips.prt';

PART_NAME
 C1191 'Q_CAP_C0603-22UF,6.3V,20%,X6S,A':;

SECTION_NUMBER 1
 '@S9S_MB_2U_LIB.S9S_MB_2U(SCH_1):PAGE181_I89@PURE_QUANTA.Q_CAP(CHIPS)':
 C_PATH='@s9s_mb_2u_lib.s9s_mb_2u(sch_1):page181_i89@pure_quanta.q_cap(chips)',
 P_PATH='@s9s_mb_2u_lib.s9s_mb_2u(sch_1):page189_i89@pure_quanta.q_cap(chips)',
 PATH='I89',
 DRAWING='@S9S_MB_2U_LIB.S9S_MB_2U(SCH_1):PAGE181',
 PHYS_PAGE='189',
 XY='(-1800,-725)',
 ROT='0',
 VER='1',
 PACK_TYPE='C0603',
 CDS_LIB='pure_quanta',
 CDS_PART_NAME='Q_CAP_C0603-22UF,6.3V,20%,X6S,A',
 TOLERANCE='20%',
 MATERIAL='X6S',
 VOLTAGE='6.3V',
 VALUE='22UF',
 PRIM_FILE='./archive_libs/logical/q_cap/chips/chips.prt';

PART_NAME
 C1192 'Q_CAP_C0603-22UF,4V,20%,X6S,CHA':;

SECTION_NUMBER 1
 '@S9S_MB_2U_LIB.S9S_MB_2U(SCH_1):PAGE181_I8@PURE_QUANTA.Q_CAP(CHIPS)':
 C_PATH='@s9s_mb_2u_lib.s9s_mb_2u(sch_1):page181_i8@pure_quanta.q_cap(chips)',
 P_PATH='@s9s_mb_2u_lib.s9s_mb_2u(sch_1):page189_i8@pure_quanta.q_cap(chips)',
 PATH='I8',
 DRAWING='@S9S_MB_2U_LIB.S9S_MB_2U(SCH_1):PAGE181',
 PHYS_PAGE='189',
 XY='(-1350,3825)',
 ROT='0',
 VER='1',
 PACK_TYPE='C0603',
 CDS_LIB='pure_quanta',
 CDS_PART_NAME='Q_CAP_C0603-22UF,4V,20%,X6S,CHA',
 TOLERANCE='20%',
 MATERIAL='X6S',
 VOLTAGE='4V',
 VALUE='22UF',
 PRIM_FILE='./archive_libs/logical/q_cap/chips/chips.prt';

PART_NAME
 C1197 'Q_CAP_C0603-22UF,4V,20%,X6S,CHA':;

SECTION_NUMBER 1
 '@S9S_MB_2U_LIB.S9S_MB_2U(SCH_1):PAGE181_I30@PURE_QUANTA.Q_CAP(CHIPS)':
 C_PATH='@s9s_mb_2u_lib.s9s_mb_2u(sch_1):page181_i30@pure_quanta.q_cap(chips)',
 P_PATH='@s9s_mb_2u_lib.s9s_mb_2u(sch_1):page189_i30@pure_quanta.q_cap(chips)',
 PATH='I30',
 DRAWING='@S9S_MB_2U_LIB.S9S_MB_2U(SCH_1):PAGE181',
 PHYS_PAGE='189',
 XY='(-1350,2500)',
 ROT='0',
 VER='1',
 PACK_TYPE='C0603',
 CDS_LIB='pure_quanta',
 CDS_PART_NAME='Q_CAP_C0603-22UF,4V,20%,X6S,CHA',
 TOLERANCE='20%',
 MATERIAL='X6S',
 VOLTAGE='4V',
 VALUE='22UF',
 PRIM_FILE='./archive_libs/logical/q_cap/chips/chips.prt';

PART_NAME
 C1198 'Q_CAP_C0603-22UF,4V,20%,X6S,CHA':;

SECTION_NUMBER 1
 '@S9S_MB_2U_LIB.S9S_MB_2U(SCH_1):PAGE181_I43@PURE_QUANTA.Q_CAP(CHIPS)':
 C_PATH='@s9s_mb_2u_lib.s9s_mb_2u(sch_1):page181_i43@pure_quanta.q_cap(chips)',
 P_PATH='@s9s_mb_2u_lib.s9s_mb_2u(sch_1):page189_i43@pure_quanta.q_cap(chips)',
 PATH='I43',
 DRAWING='@S9S_MB_2U_LIB.S9S_MB_2U(SCH_1):PAGE181',
 PHYS_PAGE='189',
 XY='(-1350,1200)',
 ROT='0',
 VER='1',
 PACK_TYPE='C0603',
 CDS_LIB='pure_quanta',
 CDS_PART_NAME='Q_CAP_C0603-22UF,4V,20%,X6S,CHA',
 TOLERANCE='20%',
 MATERIAL='X6S',
 VOLTAGE='4V',
 VALUE='22UF',
 PRIM_FILE='./archive_libs/logical/q_cap/chips/chips.prt';

PART_NAME
 C1200 'Q_CAP_C0402-2.2UF,10V,10%,X6S,A':;

SECTION_NUMBER 1
 '@S9S_MB_2U_LIB.S9S_MB_2U(SCH_1):PAGE181_I59@PURE_QUANTA.Q_CAP(CHIPS)':
 C_PATH='@s9s_mb_2u_lib.s9s_mb_2u(sch_1):page181_i59@pure_quanta.q_cap(chips)',
 P_PATH='@s9s_mb_2u_lib.s9s_mb_2u(sch_1):page189_i59@pure_quanta.q_cap(chips)',
 PATH='I59',
 DRAWING='@S9S_MB_2U_LIB.S9S_MB_2U(SCH_1):PAGE181',
 PHYS_PAGE='189',
 XY='(-1350,475)',
 ROT='0',
 VER='1',
 PACK_TYPE='C0402',
 CDS_LIB='pure_quanta',
 CDS_PART_NAME='Q_CAP_C0402-2.2UF,10V,10%,X6S,A',
 TOLERANCE='10%',
 MATERIAL='X6S',
 VOLTAGE='10V',
 VALUE='2.2UF',
 PRIM_FILE='./archive_libs/logical/q_cap/chips/chips.prt';

PART_NAME
 C1201 'Q_CAP_C0603-22UF,6.3V,20%,X6S,A':;

SECTION_NUMBER 1
 '@S9S_MB_2U_LIB.S9S_MB_2U(SCH_1):PAGE181_I87@PURE_QUANTA.Q_CAP(CHIPS)':
 C_PATH='@s9s_mb_2u_lib.s9s_mb_2u(sch_1):page181_i87@pure_quanta.q_cap(chips)',
 P_PATH='@s9s_mb_2u_lib.s9s_mb_2u(sch_1):page189_i87@pure_quanta.q_cap(chips)',
 PATH='I87',
 DRAWING='@S9S_MB_2U_LIB.S9S_MB_2U(SCH_1):PAGE181',
 PHYS_PAGE='189',
 XY='(-1350,-725)',
 ROT='0',
 VER='1',
 PACK_TYPE='C0603',
 CDS_LIB='pure_quanta',
 CDS_PART_NAME='Q_CAP_C0603-22UF,6.3V,20%,X6S,A',
 TOLERANCE='20%',
 MATERIAL='X6S',
 VOLTAGE='6.3V',
 VALUE='22UF',
 PRIM_FILE='./archive_libs/logical/q_cap/chips/chips.prt';

PART_NAME
 C1202 'Q_CAP_C0603-22UF,4V,20%,X6S,CHA':;

SECTION_NUMBER 1
 '@S9S_MB_2U_LIB.S9S_MB_2U(SCH_1):PAGE181_I29@PURE_QUANTA.Q_CAP(CHIPS)':
 C_PATH='@s9s_mb_2u_lib.s9s_mb_2u(sch_1):page181_i29@pure_quanta.q_cap(chips)',
 P_PATH='@s9s_mb_2u_lib.s9s_mb_2u(sch_1):page189_i29@pure_quanta.q_cap(chips)',
 PATH='I29',
 DRAWING='@S9S_MB_2U_LIB.S9S_MB_2U(SCH_1):PAGE181',
 PHYS_PAGE='189',
 XY='(-900,2500)',
 ROT='0',
 VER='1',
 PACK_TYPE='C0603',
 CDS_LIB='pure_quanta',
 CDS_PART_NAME='Q_CAP_C0603-22UF,4V,20%,X6S,CHA',
 TOLERANCE='20%',
 MATERIAL='X6S',
 VOLTAGE='4V',
 VALUE='22UF',
 PRIM_FILE='./archive_libs/logical/q_cap/chips/chips.prt';

PART_NAME
 C1203 'Q_CAP_C0402-10UF,6.3V,20%,X6S,A':;

SECTION_NUMBER 1
 '@S9S_MB_2U_LIB.S9S_MB_2U(SCH_1):PAGE181_I48@PURE_QUANTA.Q_CAP(CHIPS)':
 C_PATH='@s9s_mb_2u_lib.s9s_mb_2u(sch_1):page181_i48@pure_quanta.q_cap(chips)',
 P_PATH='@s9s_mb_2u_lib.s9s_mb_2u(sch_1):page189_i48@pure_quanta.q_cap(chips)',
 PATH='I48',
 DRAWING='@S9S_MB_2U_LIB.S9S_MB_2U(SCH_1):PAGE181',
 PHYS_PAGE='189',
 XY='(-900,1200)',
 ROT='0',
 VER='1',
 PACK_TYPE='C0402',
 CDS_LIB='pure_quanta',
 CDS_PART_NAME='Q_CAP_C0402-10UF,6.3V,20%,X6S,A',
 TOLERANCE='20%',
 MATERIAL='X6S',
 VOLTAGE='6.3V',
 VALUE='10UF',
 PRIM_FILE='./archive_libs/logical/q_cap/chips/chips.prt';

PART_NAME
 C1204 'Q_CAP_C0402-2.2UF,10V,10%,X6S,A':;

SECTION_NUMBER 1
 '@S9S_MB_2U_LIB.S9S_MB_2U(SCH_1):PAGE181_I60@PURE_QUANTA.Q_CAP(CHIPS)':
 C_PATH='@s9s_mb_2u_lib.s9s_mb_2u(sch_1):page181_i60@pure_quanta.q_cap(chips)',
 P_PATH='@s9s_mb_2u_lib.s9s_mb_2u(sch_1):page189_i60@pure_quanta.q_cap(chips)',
 PATH='I60',
 DRAWING='@S9S_MB_2U_LIB.S9S_MB_2U(SCH_1):PAGE181',
 PHYS_PAGE='189',
 XY='(-900,475)',
 ROT='0',
 VER='1',
 PACK_TYPE='C0402',
 CDS_LIB='pure_quanta',
 CDS_PART_NAME='Q_CAP_C0402-2.2UF,10V,10%,X6S,A',
 TOLERANCE='10%',
 MATERIAL='X6S',
 VOLTAGE='10V',
 VALUE='2.2UF',
 PRIM_FILE='./archive_libs/logical/q_cap/chips/chips.prt';

PART_NAME
 C1205 'Q_CAP_C0402-10UF,6.3V,20%,X6S,A':;

SECTION_NUMBER 1
 '@S9S_MB_2U_LIB.S9S_MB_2U(SCH_1):PAGE181_I12@PURE_QUANTA.Q_CAP(CHIPS)':
 C_PATH='@s9s_mb_2u_lib.s9s_mb_2u(sch_1):page181_i12@pure_quanta.q_cap(chips)',
 P_PATH='@s9s_mb_2u_lib.s9s_mb_2u(sch_1):page189_i12@pure_quanta.q_cap(chips)',
 PATH='I12',
 DRAWING='@S9S_MB_2U_LIB.S9S_MB_2U(SCH_1):PAGE181',
 PHYS_PAGE='189',
 XY='(-850,3825)',
 ROT='0',
 VER='1',
 PACK_TYPE='C0402',
 CDS_LIB='pure_quanta',
 CDS_PART_NAME='Q_CAP_C0402-10UF,6.3V,20%,X6S,A',
 TOLERANCE='20%',
 MATERIAL='X6S',
 VOLTAGE='6.3V',
 VALUE='10UF',
 PRIM_FILE='./archive_libs/logical/q_cap/chips/chips.prt';

PART_NAME
 C1206 'Q_CAP_C0402-10UF,6.3V,20%,X6S,A':;

SECTION_NUMBER 1
 '@S9S_MB_2U_LIB.S9S_MB_2U(SCH_1):PAGE181_I78@PURE_QUANTA.Q_CAP(CHIPS)':
 C_PATH='@s9s_mb_2u_lib.s9s_mb_2u(sch_1):page181_i78@pure_quanta.q_cap(chips)',
 P_PATH='@s9s_mb_2u_lib.s9s_mb_2u(sch_1):page189_i78@pure_quanta.q_cap(chips)',
 PATH='I78',
 DRAWING='@S9S_MB_2U_LIB.S9S_MB_2U(SCH_1):PAGE181',
 PHYS_PAGE='189',
 XY='(-850,-725)',
 ROT='0',
 VER='1',
 PACK_TYPE='C0402',
 CDS_LIB='pure_quanta',
 CDS_PART_NAME='Q_CAP_C0402-10UF,6.3V,20%,X6S,A',
 TOLERANCE='20%',
 MATERIAL='X6S',
 VOLTAGE='6.3V',
 VALUE='10UF',
 PRIM_FILE='./archive_libs/logical/q_cap/chips/chips.prt';

PART_NAME
 C1207 'Q_CAP_C0402-10UF,6.3V,20%,X6S,A':;

SECTION_NUMBER 1
 '@S9S_MB_2U_LIB.S9S_MB_2U(SCH_1):PAGE181_I32@PURE_QUANTA.Q_CAP(CHIPS)':
 C_PATH='@s9s_mb_2u_lib.s9s_mb_2u(sch_1):page181_i32@pure_quanta.q_cap(chips)',
 P_PATH='@s9s_mb_2u_lib.s9s_mb_2u(sch_1):page189_i32@pure_quanta.q_cap(chips)',
 PATH='I32',
 DRAWING='@S9S_MB_2U_LIB.S9S_MB_2U(SCH_1):PAGE181',
 PHYS_PAGE='189',
 XY='(-450,2500)',
 ROT='0',
 VER='1',
 PACK_TYPE='C0402',
 CDS_LIB='pure_quanta',
 CDS_PART_NAME='Q_CAP_C0402-10UF,6.3V,20%,X6S,A',
 TOLERANCE='20%',
 MATERIAL='X6S',
 VOLTAGE='6.3V',
 VALUE='10UF',
 PRIM_FILE='./archive_libs/logical/q_cap/chips/chips.prt';

PART_NAME
 C1209 'Q_CAP_0402-100PF,50V,5%,NPO,CHA':;

SECTION_NUMBER 1
 '@S9S_MB_2U_LIB.S9S_MB_2U(SCH_1):PAGE209_I3@PURE_QUANTA.Q_CAP(CHIPS)':
 C_PATH='@s9s_mb_2u_lib.s9s_mb_2u(sch_1):page209_i3@pure_quanta.q_cap(chips)',
 P_PATH='@s9s_mb_2u_lib.s9s_mb_2u(sch_1):page220_i3@pure_quanta.q_cap(chips)',
 PATH='I3',
 DRAWING='@S9S_MB_2U_LIB.S9S_MB_2U(SCH_1):PAGE209',
 PHYS_PAGE='220',
 XY='(-1525,-2325)',
 ROT='0',
 VER='2',
 PACK_TYPE='0402',
 LOCATION='C1209',
 CDS_LIB='pure_quanta',
 CDS_PART_NAME='Q_CAP_0402-100PF,50V,5%,NPO,CHA',
 TOLERANCE='5%',
 MATERIAL='NPO',
 VOLTAGE='50V',
 VALUE='100PF',
 PRIM_FILE='./archive_libs/logical/q_cap/chips/chips.prt';

PART_NAME
 C1210 'Q_CAP_C0402-10UF,6.3V,20%,X6S,A':;

SECTION_NUMBER 1
 '@S9S_MB_2U_LIB.S9S_MB_2U(SCH_1):PAGE181_I45@PURE_QUANTA.Q_CAP(CHIPS)':
 C_PATH='@s9s_mb_2u_lib.s9s_mb_2u(sch_1):page181_i45@pure_quanta.q_cap(chips)',
 P_PATH='@s9s_mb_2u_lib.s9s_mb_2u(sch_1):page189_i45@pure_quanta.q_cap(chips)',
 PATH='I45',
 DRAWING='@S9S_MB_2U_LIB.S9S_MB_2U(SCH_1):PAGE181',
 PHYS_PAGE='189',
 XY='(-450,1200)',
 ROT='0',
 VER='1',
 PACK_TYPE='C0402',
 CDS_LIB='pure_quanta',
 CDS_PART_NAME='Q_CAP_C0402-10UF,6.3V,20%,X6S,A',
 TOLERANCE='20%',
 MATERIAL='X6S',
 VOLTAGE='6.3V',
 VALUE='10UF',
 PRIM_FILE='./archive_libs/logical/q_cap/chips/chips.prt';

PART_NAME
 C1211 'Q_CAP_0402-100PF,50V,5%,NPO,CHA':;

SECTION_NUMBER 1
 '@S9S_MB_2U_LIB.S9S_MB_2U(SCH_1):PAGE209_I4@PURE_QUANTA.Q_CAP(CHIPS)':
 C_PATH='@s9s_mb_2u_lib.s9s_mb_2u(sch_1):page209_i4@pure_quanta.q_cap(chips)',
 P_PATH='@s9s_mb_2u_lib.s9s_mb_2u(sch_1):page220_i4@pure_quanta.q_cap(chips)',
 PATH='I4',
 DRAWING='@S9S_MB_2U_LIB.S9S_MB_2U(SCH_1):PAGE209',
 PHYS_PAGE='220',
 XY='(-1525,-2475)',
 ROT='0',
 VER='2',
 PACK_TYPE='0402',
 LOCATION='C1211',
 CDS_LIB='pure_quanta',
 CDS_PART_NAME='Q_CAP_0402-100PF,50V,5%,NPO,CHA',
 TOLERANCE='5%',
 MATERIAL='NPO',
 VOLTAGE='50V',
 VALUE='100PF',
 PRIM_FILE='./archive_libs/logical/q_cap/chips/chips.prt';

PART_NAME
 C1213 'Q_CAP_C0805-22UF,16V,20%,X6S,CB':;

SECTION_NUMBER 1
 '@S9S_MB_2U_LIB.S9S_MB_2U(SCH_1):PAGE150_I89@PURE_QUANTA.Q_CAP(CHIPS)':
 C_PATH='@s9s_mb_2u_lib.s9s_mb_2u(sch_1):page150_i89@pure_quanta.q_cap(chips)',
 P_PATH='@s9s_mb_2u_lib.s9s_mb_2u(sch_1):page153_i89@pure_quanta.q_cap(chips)',
 PATH='I89',
 DRAWING='@S9S_MB_2U_LIB.S9S_MB_2U(SCH_1):PAGE150',
 PHYS_PAGE='153',
 XY='(800,1750)',
 ROT='0',
 VER='1',
 PACK_TYPE='C0805',
 CDS_LIB='pure_quanta',
 CDS_PART_NAME='Q_CAP_C0805-22UF,16V,20%,X6S,CB',
 TOLERANCE='20%',
 MATERIAL='X6S',
 VOLTAGE='16V',
 VALUE='22UF',
 PRIM_FILE='./archive_libs/logical/q_cap/chips/chips.prt';

PART_NAME
 C1214 'Q_CAP_C0402-2.2UF,10V,10%,X6S,A':;

SECTION_NUMBER 1
 '@S9S_MB_2U_LIB.S9S_MB_2U(SCH_1):PAGE181_I61@PURE_QUANTA.Q_CAP(CHIPS)':
 C_PATH='@s9s_mb_2u_lib.s9s_mb_2u(sch_1):page181_i61@pure_quanta.q_cap(chips)',
 P_PATH='@s9s_mb_2u_lib.s9s_mb_2u(sch_1):page189_i61@pure_quanta.q_cap(chips)',
 PATH='I61',
 DRAWING='@S9S_MB_2U_LIB.S9S_MB_2U(SCH_1):PAGE181',
 PHYS_PAGE='189',
 XY='(-450,475)',
 ROT='0',
 VER='1',
 PACK_TYPE='C0402',
 CDS_LIB='pure_quanta',
 CDS_PART_NAME='Q_CAP_C0402-2.2UF,10V,10%,X6S,A',
 TOLERANCE='10%',
 MATERIAL='X6S',
 VOLTAGE='10V',
 VALUE='2.2UF',
 PRIM_FILE='./archive_libs/logical/q_cap/chips/chips.prt';

PART_NAME
 C1226 'Q_CAP_C0402-0.22UF,25V,10%,X7RA':;

SECTION_NUMBER 1
 '@S9S_MB_2U_LIB.S9S_MB_2U(SCH_1):PAGE246_I68@PURE_QUANTA.Q_CAP(CHIPS)':
 C_PATH='@s9s_mb_2u_lib.s9s_mb_2u(sch_1):page246_i68@pure_quanta.q_cap(chips)',
 P_PATH='@s9s_mb_2u_lib.s9s_mb_2u(sch_1):page260_i68@pure_quanta.q_cap(chips)',
 PATH='I68',
 DRAWING='@S9S_MB_2U_LIB.S9S_MB_2U(SCH_1):PAGE246',
 PHYS_PAGE='260',
 XY='(-3950,6300)',
 ROT='0',
 VER='1',
 PACK_TYPE='C0402',
 LOCATION='C1226',
 CDS_LIB='pure_quanta',
 CDS_PART_NAME='Q_CAP_C0402-0.22UF,25V,10%,X7RA',
 TOLERANCE='10%',
 MATERIAL='X7R',
 VOLTAGE='25V',
 VALUE='0.22UF',
 PRIM_FILE='./archive_libs/logical/q_cap/chips/chips.prt';

PART_NAME
 C1227 'Q_CAP_C0402-100NF,50V,10%,X7R,A':
 REUSE_ID='81';

SECTION_NUMBER 1
 '@S9S_MB_2U_LIB.S9S_MB_2U(SCH_1):PAGE246_I44@PURE_QUANTA.Q_CAP(CHIPS)':
 C_PATH='@s9s_mb_2u_lib.s9s_mb_2u(sch_1):page246_i44@pure_quanta.q_cap(chips)',
 P_PATH='@s9s_mb_2u_lib.s9s_mb_2u(sch_1):page260_i44@pure_quanta.q_cap(chips)',
 PATH='I44',
 DRAWING='@S9S_MB_2U_LIB.S9S_MB_2U(SCH_1):PAGE246',
 BOM_COST='VR_SYSTEM ',
 PHYS_PAGE='260',
 XY='(-3375,7400)',
 ROT='0',
 VER='1',
 PACK_TYPE='C0402',
 CDS_LIB='pure_quanta',
 CDS_PART_NAME='Q_CAP_C0402-100NF,50V,10%,X7R,A',
 TOLERANCE='10%',
 MATERIAL='X7R',
 REUSE_ID='81',
 VOLTAGE='50V',
 VALUE='100NF',
 PRIM_FILE='./archive_libs/logical/q_cap/chips/chips.prt';

PART_NAME
 C1228 'Q_CAP_C0402-10UF,6.3V,20%,X6S,A':;

SECTION_NUMBER 1
 '@S9S_MB_2U_LIB.S9S_MB_2U(SCH_1):PAGE181_I13@PURE_QUANTA.Q_CAP(CHIPS)':
 C_PATH='@s9s_mb_2u_lib.s9s_mb_2u(sch_1):page181_i13@pure_quanta.q_cap(chips)',
 P_PATH='@s9s_mb_2u_lib.s9s_mb_2u(sch_1):page189_i13@pure_quanta.q_cap(chips)',
 PATH='I13',
 DRAWING='@S9S_MB_2U_LIB.S9S_MB_2U(SCH_1):PAGE181',
 PHYS_PAGE='189',
 XY='(-400,3825)',
 ROT='0',
 VER='1',
 PACK_TYPE='C0402',
 CDS_LIB='pure_quanta',
 CDS_PART_NAME='Q_CAP_C0402-10UF,6.3V,20%,X6S,A',
 TOLERANCE='20%',
 MATERIAL='X6S',
 VOLTAGE='6.3V',
 VALUE='10UF',
 PRIM_FILE='./archive_libs/logical/q_cap/chips/chips.prt';

PART_NAME
 C1231 'Q_CAP_C0402-10UF,6.3V,20%,X6S,A':;

SECTION_NUMBER 1
 '@S9S_MB_2U_LIB.S9S_MB_2U(SCH_1):PAGE181_I49@PURE_QUANTA.Q_CAP(CHIPS)':
 C_PATH='@s9s_mb_2u_lib.s9s_mb_2u(sch_1):page181_i49@pure_quanta.q_cap(chips)',
 P_PATH='@s9s_mb_2u_lib.s9s_mb_2u(sch_1):page189_i49@pure_quanta.q_cap(chips)',
 PATH='I49',
 DRAWING='@S9S_MB_2U_LIB.S9S_MB_2U(SCH_1):PAGE181',
 PHYS_PAGE='189',
 XY='(0,1200)',
 ROT='0',
 VER='1',
 PACK_TYPE='C0402',
 CDS_LIB='pure_quanta',
 CDS_PART_NAME='Q_CAP_C0402-10UF,6.3V,20%,X6S,A',
 TOLERANCE='20%',
 MATERIAL='X6S',
 VOLTAGE='6.3V',
 VALUE='10UF',
 PRIM_FILE='./archive_libs/logical/q_cap/chips/chips.prt';

PART_NAME
 C1232 'Q_CAP_C0805-22UF,16V,20%,X6S,CB':;

SECTION_NUMBER 1
 '@S9S_MB_2U_LIB.S9S_MB_2U(SCH_1):PAGE150_I90@PURE_QUANTA.Q_CAP(CHIPS)':
 C_PATH='@s9s_mb_2u_lib.s9s_mb_2u(sch_1):page150_i90@pure_quanta.q_cap(chips)',
 P_PATH='@s9s_mb_2u_lib.s9s_mb_2u(sch_1):page153_i90@pure_quanta.q_cap(chips)',
 PATH='I90',
 DRAWING='@S9S_MB_2U_LIB.S9S_MB_2U(SCH_1):PAGE150',
 PHYS_PAGE='153',
 XY='(1075,1750)',
 ROT='0',
 VER='1',
 PACK_TYPE='C0805',
 CDS_LIB='pure_quanta',
 CDS_PART_NAME='Q_CAP_C0805-22UF,16V,20%,X6S,CB',
 TOLERANCE='20%',
 MATERIAL='X6S',
 VOLTAGE='16V',
 VALUE='22UF',
 PRIM_FILE='./archive_libs/logical/q_cap/chips/chips.prt';

PART_NAME
 C1233 'Q_CAP_0402-0.1UF,25V,10%,X7R,CA':;

SECTION_NUMBER 1
 '@S9S_MB_2U_LIB.S9S_MB_2U(SCH_1):PAGE150_I91@PURE_QUANTA.Q_CAP(CHIPS)':
 C_PATH='@s9s_mb_2u_lib.s9s_mb_2u(sch_1):page150_i91@pure_quanta.q_cap(chips)',
 P_PATH='@s9s_mb_2u_lib.s9s_mb_2u(sch_1):page153_i91@pure_quanta.q_cap(chips)',
 PATH='I91',
 DRAWING='@S9S_MB_2U_LIB.S9S_MB_2U(SCH_1):PAGE150',
 PHYS_PAGE='153',
 XY='(1475,1750)',
 ROT='0',
 VER='1',
 PACK_TYPE='0402',
 CDS_LIB='pure_quanta',
 CDS_PART_NAME='Q_CAP_0402-0.1UF,25V,10%,X7R,CA',
 TOLERANCE='10%',
 MATERIAL='X7R',
 VOLTAGE='25V',
 VALUE='0.1UF',
 PRIM_FILE='./archive_libs/logical/q_cap/chips/chips.prt';

PART_NAME
 C1234 'Q_CAP_0402-0.1UF,25V,10%,X7R,CA':;

SECTION_NUMBER 1
 '@S9S_MB_2U_LIB.S9S_MB_2U(SCH_1):PAGE150_I110@PURE_QUANTA.Q_CAP(CHIPS)':
 C_PATH='@s9s_mb_2u_lib.s9s_mb_2u(sch_1):page150_i110@pure_quanta.q_cap(chips)',
 P_PATH='@s9s_mb_2u_lib.s9s_mb_2u(sch_1):page153_i110@pure_quanta.q_cap(chips)',
 PATH='I110',
 DRAWING='@S9S_MB_2U_LIB.S9S_MB_2U(SCH_1):PAGE150',
 PHYS_PAGE='153',
 XY='(1750,1750)',
 ROT='0',
 VER='1',
 PACK_TYPE='0402',
 CDS_LIB='pure_quanta',
 CDS_PART_NAME='Q_CAP_0402-0.1UF,25V,10%,X7R,CA',
 TOLERANCE='10%',
 MATERIAL='X7R',
 VOLTAGE='25V',
 VALUE='0.1UF',
 PRIM_FILE='./archive_libs/logical/q_cap/chips/chips.prt';

PART_NAME
 C1235 'Q_CAP_0402-0.1UF,25V,10%,X7R,CA':;

SECTION_NUMBER 1
 '@S9S_MB_2U_LIB.S9S_MB_2U(SCH_1):PAGE150_I111@PURE_QUANTA.Q_CAP(CHIPS)':
 C_PATH='@s9s_mb_2u_lib.s9s_mb_2u(sch_1):page150_i111@pure_quanta.q_cap(chips)',
 P_PATH='@s9s_mb_2u_lib.s9s_mb_2u(sch_1):page153_i111@pure_quanta.q_cap(chips)',
 PATH='I111',
 DRAWING='@S9S_MB_2U_LIB.S9S_MB_2U(SCH_1):PAGE150',
 PHYS_PAGE='153',
 XY='(2025,1750)',
 ROT='0',
 VER='1',
 PACK_TYPE='0402',
 CDS_LIB='pure_quanta',
 CDS_PART_NAME='Q_CAP_0402-0.1UF,25V,10%,X7R,CA',
 TOLERANCE='10%',
 MATERIAL='X7R',
 VOLTAGE='25V',
 VALUE='0.1UF',
 PRIM_FILE='./archive_libs/logical/q_cap/chips/chips.prt';

PART_NAME
 C1236 'Q_CAP_0402-0.1UF,25V,10%,X7R,CA':;

SECTION_NUMBER 1
 '@S9S_MB_2U_LIB.S9S_MB_2U(SCH_1):PAGE150_I113@PURE_QUANTA.Q_CAP(CHIPS)':
 C_PATH='@s9s_mb_2u_lib.s9s_mb_2u(sch_1):page150_i113@pure_quanta.q_cap(chips)',
 P_PATH='@s9s_mb_2u_lib.s9s_mb_2u(sch_1):page153_i113@pure_quanta.q_cap(chips)',
 PATH='I113',
 DRAWING='@S9S_MB_2U_LIB.S9S_MB_2U(SCH_1):PAGE150',
 PHYS_PAGE='153',
 XY='(2300,1750)',
 ROT='0',
 VER='1',
 PACK_TYPE='0402',
 CDS_LIB='pure_quanta',
 CDS_PART_NAME='Q_CAP_0402-0.1UF,25V,10%,X7R,CA',
 TOLERANCE='10%',
 MATERIAL='X7R',
 VOLTAGE='25V',
 VALUE='0.1UF',
 PRIM_FILE='./archive_libs/logical/q_cap/chips/chips.prt';

PART_NAME
 C1237 'Q_CAP_0402-0.1UF,25V,10%,X7R,CA':;

SECTION_NUMBER 1
 '@S9S_MB_2U_LIB.S9S_MB_2U(SCH_1):PAGE150_I114@PURE_QUANTA.Q_CAP(CHIPS)':
 C_PATH='@s9s_mb_2u_lib.s9s_mb_2u(sch_1):page150_i114@pure_quanta.q_cap(chips)',
 P_PATH='@s9s_mb_2u_lib.s9s_mb_2u(sch_1):page153_i114@pure_quanta.q_cap(chips)',
 PATH='I114',
 DRAWING='@S9S_MB_2U_LIB.S9S_MB_2U(SCH_1):PAGE150',
 PHYS_PAGE='153',
 XY='(2825,1900)',
 ROT='0',
 VER='1',
 PACK_TYPE='0402',
 CDS_LIB='pure_quanta',
 CDS_PART_NAME='Q_CAP_0402-0.1UF,25V,10%,X7R,CA',
 TOLERANCE='10%',
 MATERIAL='X7R',
 VOLTAGE='25V',
 VALUE='0.1UF',
 PRIM_FILE='./archive_libs/logical/q_cap/chips/chips.prt';

PART_NAME
 C1238 'Q_CAP_0402-0.1UF,25V,10%,X7R,CA':;

SECTION_NUMBER 1
 '@S9S_MB_2U_LIB.S9S_MB_2U(SCH_1):PAGE150_I115@PURE_QUANTA.Q_CAP(CHIPS)':
 C_PATH='@s9s_mb_2u_lib.s9s_mb_2u(sch_1):page150_i115@pure_quanta.q_cap(chips)',
 P_PATH='@s9s_mb_2u_lib.s9s_mb_2u(sch_1):page153_i115@pure_quanta.q_cap(chips)',
 PATH='I115',
 DRAWING='@S9S_MB_2U_LIB.S9S_MB_2U(SCH_1):PAGE150',
 PHYS_PAGE='153',
 XY='(3075,1900)',
 ROT='0',
 VER='1',
 PACK_TYPE='0402',
 CDS_LIB='pure_quanta',
 CDS_PART_NAME='Q_CAP_0402-0.1UF,25V,10%,X7R,CA',
 TOLERANCE='10%',
 MATERIAL='X7R',
 VOLTAGE='25V',
 VALUE='0.1UF',
 PRIM_FILE='./archive_libs/logical/q_cap/chips/chips.prt';

PART_NAME
 C1239 'Q_CAP_0402-0.1UF,25V,10%,X7R,CA':;

SECTION_NUMBER 1
 '@S9S_MB_2U_LIB.S9S_MB_2U(SCH_1):PAGE150_I116@PURE_QUANTA.Q_CAP(CHIPS)':
 C_PATH='@s9s_mb_2u_lib.s9s_mb_2u(sch_1):page150_i116@pure_quanta.q_cap(chips)',
 P_PATH='@s9s_mb_2u_lib.s9s_mb_2u(sch_1):page153_i116@pure_quanta.q_cap(chips)',
 PATH='I116',
 DRAWING='@S9S_MB_2U_LIB.S9S_MB_2U(SCH_1):PAGE150',
 PHYS_PAGE='153',
 XY='(3350,1900)',
 ROT='0',
 VER='1',
 PACK_TYPE='0402',
 CDS_LIB='pure_quanta',
 CDS_PART_NAME='Q_CAP_0402-0.1UF,25V,10%,X7R,CA',
 TOLERANCE='10%',
 MATERIAL='X7R',
 VOLTAGE='25V',
 VALUE='0.1UF',
 PRIM_FILE='./archive_libs/logical/q_cap/chips/chips.prt';

PART_NAME
 C1240 'Q_CAP_0402-0.1UF,25V,10%,X7R,CA':;

SECTION_NUMBER 1
 '@S9S_MB_2U_LIB.S9S_MB_2U(SCH_1):PAGE150_I168@PURE_QUANTA.Q_CAP(CHIPS)':
 C_PATH='@s9s_mb_2u_lib.s9s_mb_2u(sch_1):page150_i168@pure_quanta.q_cap(chips)',
 P_PATH='@s9s_mb_2u_lib.s9s_mb_2u(sch_1):page153_i168@pure_quanta.q_cap(chips)',
 PATH='I168',
 DRAWING='@S9S_MB_2U_LIB.S9S_MB_2U(SCH_1):PAGE150',
 PHYS_PAGE='153',
 XY='(3625,1900)',
 ROT='0',
 VER='1',
 PACK_TYPE='0402',
 CDS_LIB='pure_quanta',
 CDS_PART_NAME='Q_CAP_0402-0.1UF,25V,10%,X7R,CA',
 TOLERANCE='10%',
 MATERIAL='X7R',
 VOLTAGE='25V',
 VALUE='0.1UF',
 PRIM_FILE='./archive_libs/logical/q_cap/chips/chips.prt';

PART_NAME
 C1242 'Q_CAP_C0402-2.2UF,10V,10%,X6S,A':;

SECTION_NUMBER 1
 '@S9S_MB_2U_LIB.S9S_MB_2U(SCH_1):PAGE181_I63@PURE_QUANTA.Q_CAP(CHIPS)':
 C_PATH='@s9s_mb_2u_lib.s9s_mb_2u(sch_1):page181_i63@pure_quanta.q_cap(chips)',
 P_PATH='@s9s_mb_2u_lib.s9s_mb_2u(sch_1):page189_i63@pure_quanta.q_cap(chips)',
 PATH='I63',
 DRAWING='@S9S_MB_2U_LIB.S9S_MB_2U(SCH_1):PAGE181',
 PHYS_PAGE='189',
 XY='(0,475)',
 ROT='0',
 VER='1',
 PACK_TYPE='C0402',
 CDS_LIB='pure_quanta',
 CDS_PART_NAME='Q_CAP_C0402-2.2UF,10V,10%,X6S,A',
 TOLERANCE='10%',
 MATERIAL='X6S',
 VOLTAGE='10V',
 VALUE='2.2UF',
 PRIM_FILE='./archive_libs/logical/q_cap/chips/chips.prt';

PART_NAME
 C1243 'Q_CAP_C0805-47UF,6.3V,20%,X6S,A':;

SECTION_NUMBER 1
 '@S9S_MB_2U_LIB.S9S_MB_2U(SCH_1):PAGE181_I162@PURE_QUANTA.Q_CAP(CHIPS)':
 C_PATH='@s9s_mb_2u_lib.s9s_mb_2u(sch_1):page181_i162@pure_quanta.q_cap(chips)',
 P_PATH='@s9s_mb_2u_lib.s9s_mb_2u(sch_1):page189_i162@pure_quanta.q_cap(chips)',
 PATH='I162',
 DRAWING='@S9S_MB_2U_LIB.S9S_MB_2U(SCH_1):PAGE181',
 PHYS_PAGE='189',
 XY='(0,-725)',
 ROT='0',
 VER='1',
 PACK_TYPE='C0805',
 LOCATION='C1243',
 CDS_LIB='pure_quanta',
 CDS_PART_NAME='Q_CAP_C0805-47UF,6.3V,20%,X6S,A',
 TOLERANCE='20%',
 MATERIAL='X6S',
 VOLTAGE='6.3V',
 VALUE='47UF',
 PRIM_FILE='./archive_libs/logical/q_cap/chips/chips.prt';

PART_NAME
 C1244 'Q_CAP_C0805-47UF,4V,20%,X6S,CHA':;

SECTION_NUMBER 1
 '@S9S_MB_2U_LIB.S9S_MB_2U(SCH_1):PAGE181_I152@PURE_QUANTA.Q_CAP(CHIPS)':
 C_PATH='@s9s_mb_2u_lib.s9s_mb_2u(sch_1):page181_i152@pure_quanta.q_cap(chips)',
 P_PATH='@s9s_mb_2u_lib.s9s_mb_2u(sch_1):page189_i152@pure_quanta.q_cap(chips)',
 PATH='I152',
 DRAWING='@S9S_MB_2U_LIB.S9S_MB_2U(SCH_1):PAGE181',
 PHYS_PAGE='189',
 XY='(50,3825)',
 ROT='0',
 VER='1',
 PACK_TYPE='C0805',
 LOCATION='C1244',
 CDS_LIB='pure_quanta',
 CDS_PART_NAME='Q_CAP_C0805-47UF,4V,20%,X6S,CHA',
 TOLERANCE='20%',
 MATERIAL='X6S',
 VOLTAGE='4V',
 VALUE='47UF',
 PRIM_FILE='./archive_libs/logical/q_cap/chips/chips.prt';

PART_NAME
 C1245 'Q_CAP_C0805-47UF,6.3V,20%,X6S,A':;

SECTION_NUMBER 1
 '@S9S_MB_2U_LIB.S9S_MB_2U(SCH_1):PAGE181_I163@PURE_QUANTA.Q_CAP(CHIPS)':
 C_PATH='@s9s_mb_2u_lib.s9s_mb_2u(sch_1):page181_i163@pure_quanta.q_cap(chips)',
 P_PATH='@s9s_mb_2u_lib.s9s_mb_2u(sch_1):page189_i163@pure_quanta.q_cap(chips)',
 PATH='I163',
 DRAWING='@S9S_MB_2U_LIB.S9S_MB_2U(SCH_1):PAGE181',
 PHYS_PAGE='189',
 XY='(450,-725)',
 ROT='0',
 VER='1',
 PACK_TYPE='C0805',
 LOCATION='C1245',
 CDS_LIB='pure_quanta',
 CDS_PART_NAME='Q_CAP_C0805-47UF,6.3V,20%,X6S,A',
 TOLERANCE='20%',
 MATERIAL='X6S',
 VOLTAGE='6.3V',
 VALUE='47UF',
 PRIM_FILE='./archive_libs/logical/q_cap/chips/chips.prt';

PART_NAME
 C1246 'Q_CAP_C0805-47UF,4V,20%,X6S,CHA':;

SECTION_NUMBER 1
 '@S9S_MB_2U_LIB.S9S_MB_2U(SCH_1):PAGE181_I153@PURE_QUANTA.Q_CAP(CHIPS)':
 C_PATH='@s9s_mb_2u_lib.s9s_mb_2u(sch_1):page181_i153@pure_quanta.q_cap(chips)',
 P_PATH='@s9s_mb_2u_lib.s9s_mb_2u(sch_1):page189_i153@pure_quanta.q_cap(chips)',
 PATH='I153',
 DRAWING='@S9S_MB_2U_LIB.S9S_MB_2U(SCH_1):PAGE181',
 PHYS_PAGE='189',
 XY='(500,3825)',
 ROT='0',
 VER='1',
 PACK_TYPE='C0805',
 LOCATION='C1246',
 CDS_LIB='pure_quanta',
 CDS_PART_NAME='Q_CAP_C0805-47UF,4V,20%,X6S,CHA',
 TOLERANCE='20%',
 MATERIAL='X6S',
 VOLTAGE='4V',
 VALUE='47UF',
 PRIM_FILE='./archive_libs/logical/q_cap/chips/chips.prt';

PART_NAME
 C1247 'Q_CAP_C0805-47UF,4V,20%,X6S,CHA':;

SECTION_NUMBER 1
 '@S9S_MB_2U_LIB.S9S_MB_2U(SCH_1):PAGE181_I154@PURE_QUANTA.Q_CAP(CHIPS)':
 C_PATH='@s9s_mb_2u_lib.s9s_mb_2u(sch_1):page181_i154@pure_quanta.q_cap(chips)',
 P_PATH='@s9s_mb_2u_lib.s9s_mb_2u(sch_1):page189_i154@pure_quanta.q_cap(chips)',
 PATH='I154',
 DRAWING='@S9S_MB_2U_LIB.S9S_MB_2U(SCH_1):PAGE181',
 PHYS_PAGE='189',
 XY='(500,1175)',
 ROT='0',
 VER='1',
 PACK_TYPE='C0805',
 LOCATION='C1247',
 CDS_LIB='pure_quanta',
 CDS_PART_NAME='Q_CAP_C0805-47UF,4V,20%,X6S,CHA',
 TOLERANCE='20%',
 MATERIAL='X6S',
 VOLTAGE='4V',
 VALUE='47UF',
 PRIM_FILE='./archive_libs/logical/q_cap/chips/chips.prt';

PART_NAME
 C1248 'Q_CAP_C0805-47UF,4V,20%,X6S,CHA':;

SECTION_NUMBER 1
 '@S9S_MB_2U_LIB.S9S_MB_2U(SCH_1):PAGE181_I155@PURE_QUANTA.Q_CAP(CHIPS)':
 C_PATH='@s9s_mb_2u_lib.s9s_mb_2u(sch_1):page181_i155@pure_quanta.q_cap(chips)',
 P_PATH='@s9s_mb_2u_lib.s9s_mb_2u(sch_1):page189_i155@pure_quanta.q_cap(chips)',
 PATH='I155',
 DRAWING='@S9S_MB_2U_LIB.S9S_MB_2U(SCH_1):PAGE181',
 PHYS_PAGE='189',
 XY='(950,3825)',
 ROT='0',
 VER='1',
 PACK_TYPE='C0805',
 LOCATION='C1248',
 CDS_LIB='pure_quanta',
 CDS_PART_NAME='Q_CAP_C0805-47UF,4V,20%,X6S,CHA',
 TOLERANCE='20%',
 MATERIAL='X6S',
 VOLTAGE='4V',
 VALUE='47UF',
 PRIM_FILE='./archive_libs/logical/q_cap/chips/chips.prt';

PART_NAME
 C1249 'Q_CAP_C0805-47UF,4V,20%,X6S,CHA':;

SECTION_NUMBER 1
 '@S9S_MB_2U_LIB.S9S_MB_2U(SCH_1):PAGE181_I156@PURE_QUANTA.Q_CAP(CHIPS)':
 C_PATH='@s9s_mb_2u_lib.s9s_mb_2u(sch_1):page181_i156@pure_quanta.q_cap(chips)',
 P_PATH='@s9s_mb_2u_lib.s9s_mb_2u(sch_1):page189_i156@pure_quanta.q_cap(chips)',
 PATH='I156',
 DRAWING='@S9S_MB_2U_LIB.S9S_MB_2U(SCH_1):PAGE181',
 PHYS_PAGE='189',
 XY='(950,1175)',
 ROT='0',
 VER='1',
 PACK_TYPE='C0805',
 LOCATION='C1249',
 CDS_LIB='pure_quanta',
 CDS_PART_NAME='Q_CAP_C0805-47UF,4V,20%,X6S,CHA',
 TOLERANCE='20%',
 MATERIAL='X6S',
 VOLTAGE='4V',
 VALUE='47UF',
 PRIM_FILE='./archive_libs/logical/q_cap/chips/chips.prt';

PART_NAME
 C1250 'Q_CAP_0402-1UF,6.3V,10%,EMPTY,A':;

SECTION_NUMBER 1
 '@S9S_MB_2U_LIB.S9S_MB_2U(SCH_1):PAGE181_I137@PURE_QUANTA.Q_CAP(CHIPS)':
 C_PATH='@s9s_mb_2u_lib.s9s_mb_2u(sch_1):page181_i137@pure_quanta.q_cap(chips)',
 P_PATH='@s9s_mb_2u_lib.s9s_mb_2u(sch_1):page189_i137@pure_quanta.q_cap(chips)',
 PATH='I137',
 DRAWING='@S9S_MB_2U_LIB.S9S_MB_2U(SCH_1):PAGE181',
 PHYS_PAGE='189',
 XY='(2375,3575)',
 ROT='0',
 VER='1',
 PACK_TYPE='0402',
 CDS_LIB='pure_quanta',
 CDS_PART_NAME='Q_CAP_0402-1UF,6.3V,10%,EMPTY,A',
 TOLERANCE='10%',
 MATERIAL='EMPTY',
 VOLTAGE='6.3V',
 VALUE='1UF',
 PRIM_FILE='./archive_libs/logical/q_cap/chips/chips.prt';

PART_NAME
 C1251 'Q_CAP_C0603-10UF,6.3V,20%,X6S,A':;

SECTION_NUMBER 1
 '@S9S_MB_2U_LIB.S9S_MB_2U(SCH_1):PAGE181_I110@PURE_QUANTA.Q_CAP(CHIPS)':
 C_PATH='@s9s_mb_2u_lib.s9s_mb_2u(sch_1):page181_i110@pure_quanta.q_cap(chips)',
 P_PATH='@s9s_mb_2u_lib.s9s_mb_2u(sch_1):page189_i110@pure_quanta.q_cap(chips)',
 PATH='I110',
 DRAWING='@S9S_MB_2U_LIB.S9S_MB_2U(SCH_1):PAGE181',
 PHYS_PAGE='189',
 XY='(2375,2650)',
 ROT='0',
 VER='1',
 PACK_TYPE='C0603',
 CDS_LIB='pure_quanta',
 CDS_PART_NAME='Q_CAP_C0603-10UF,6.3V,20%,X6S,A',
 TOLERANCE='20%',
 MATERIAL='X6S',
 VOLTAGE='6.3V',
 VALUE='10UF',
 PRIM_FILE='./archive_libs/logical/q_cap/chips/chips.prt';

PART_NAME
 C1252 'Q_CAP_C0603-10UF,6.3V,20%,X6S,A':;

SECTION_NUMBER 1
 '@S9S_MB_2U_LIB.S9S_MB_2U(SCH_1):PAGE181_I125@PURE_QUANTA.Q_CAP(CHIPS)':
 C_PATH='@s9s_mb_2u_lib.s9s_mb_2u(sch_1):page181_i125@pure_quanta.q_cap(chips)',
 P_PATH='@s9s_mb_2u_lib.s9s_mb_2u(sch_1):page189_i125@pure_quanta.q_cap(chips)',
 PATH='I125',
 DRAWING='@S9S_MB_2U_LIB.S9S_MB_2U(SCH_1):PAGE181',
 PHYS_PAGE='189',
 XY='(2400,0)',
 ROT='0',
 VER='1',
 PACK_TYPE='C0603',
 CDS_LIB='pure_quanta',
 CDS_PART_NAME='Q_CAP_C0603-10UF,6.3V,20%,X6S,A',
 TOLERANCE='20%',
 MATERIAL='X6S',
 VOLTAGE='6.3V',
 VALUE='10UF',
 PRIM_FILE='./archive_libs/logical/q_cap/chips/chips.prt';

PART_NAME
 C1253 'Q_CAP_0402-1UF,6.3V,10%,EMPTY,A':;

SECTION_NUMBER 1
 '@S9S_MB_2U_LIB.S9S_MB_2U(SCH_1):PAGE181_I147@PURE_QUANTA.Q_CAP(CHIPS)':
 C_PATH='@s9s_mb_2u_lib.s9s_mb_2u(sch_1):page181_i147@pure_quanta.q_cap(chips)',
 P_PATH='@s9s_mb_2u_lib.s9s_mb_2u(sch_1):page189_i147@pure_quanta.q_cap(chips)',
 PATH='I147',
 DRAWING='@S9S_MB_2U_LIB.S9S_MB_2U(SCH_1):PAGE181',
 PHYS_PAGE='189',
 XY='(2425,900)',
 ROT='0',
 VER='1',
 PACK_TYPE='0402',
 CDS_LIB='pure_quanta',
 CDS_PART_NAME='Q_CAP_0402-1UF,6.3V,10%,EMPTY,A',
 TOLERANCE='10%',
 MATERIAL='EMPTY',
 VOLTAGE='6.3V',
 VALUE='1UF',
 PRIM_FILE='./archive_libs/logical/q_cap/chips/chips.prt';

PART_NAME
 C1254 'Q_CAP_C0603-10UF,6.3V,20%,X6S,A':;

SECTION_NUMBER 1
 '@S9S_MB_2U_LIB.S9S_MB_2U(SCH_1):PAGE181_I111@PURE_QUANTA.Q_CAP(CHIPS)':
 C_PATH='@s9s_mb_2u_lib.s9s_mb_2u(sch_1):page181_i111@pure_quanta.q_cap(chips)',
 P_PATH='@s9s_mb_2u_lib.s9s_mb_2u(sch_1):page189_i111@pure_quanta.q_cap(chips)',
 PATH='I111',
 DRAWING='@S9S_MB_2U_LIB.S9S_MB_2U(SCH_1):PAGE181',
 PHYS_PAGE='189',
 XY='(2825,2650)',
 ROT='0',
 VER='1',
 PACK_TYPE='C0603',
 CDS_LIB='pure_quanta',
 CDS_PART_NAME='Q_CAP_C0603-10UF,6.3V,20%,X6S,A',
 TOLERANCE='20%',
 MATERIAL='X6S',
 VOLTAGE='6.3V',
 VALUE='10UF',
 PRIM_FILE='./archive_libs/logical/q_cap/chips/chips.prt';

PART_NAME
 C1255 'Q_CAP_C0603-10UF,6.3V,20%,X6S,A':;

SECTION_NUMBER 1
 '@S9S_MB_2U_LIB.S9S_MB_2U(SCH_1):PAGE181_I123@PURE_QUANTA.Q_CAP(CHIPS)':
 C_PATH='@s9s_mb_2u_lib.s9s_mb_2u(sch_1):page181_i123@pure_quanta.q_cap(chips)',
 P_PATH='@s9s_mb_2u_lib.s9s_mb_2u(sch_1):page189_i123@pure_quanta.q_cap(chips)',
 PATH='I123',
 DRAWING='@S9S_MB_2U_LIB.S9S_MB_2U(SCH_1):PAGE181',
 PHYS_PAGE='189',
 XY='(2850,0)',
 ROT='0',
 VER='1',
 PACK_TYPE='C0603',
 CDS_LIB='pure_quanta',
 CDS_PART_NAME='Q_CAP_C0603-10UF,6.3V,20%,X6S,A',
 TOLERANCE='20%',
 MATERIAL='X6S',
 VOLTAGE='6.3V',
 VALUE='10UF',
 PRIM_FILE='./archive_libs/logical/q_cap/chips/chips.prt';

PART_NAME
 C1256 'Q_CAP_0402-1UF,6.3V,10%,EMPTY,A':;

SECTION_NUMBER 1
 '@S9S_MB_2U_LIB.S9S_MB_2U(SCH_1):PAGE181_I136@PURE_QUANTA.Q_CAP(CHIPS)':
 C_PATH='@s9s_mb_2u_lib.s9s_mb_2u(sch_1):page181_i136@pure_quanta.q_cap(chips)',
 P_PATH='@s9s_mb_2u_lib.s9s_mb_2u(sch_1):page189_i136@pure_quanta.q_cap(chips)',
 PATH='I136',
 DRAWING='@S9S_MB_2U_LIB.S9S_MB_2U(SCH_1):PAGE181',
 PHYS_PAGE='189',
 XY='(3025,3575)',
 ROT='0',
 VER='1',
 PACK_TYPE='0402',
 CDS_LIB='pure_quanta',
 CDS_PART_NAME='Q_CAP_0402-1UF,6.3V,10%,EMPTY,A',
 TOLERANCE='10%',
 MATERIAL='EMPTY',
 VOLTAGE='6.3V',
 VALUE='1UF',
 PRIM_FILE='./archive_libs/logical/q_cap/chips/chips.prt';

PART_NAME
 C1257 'Q_CAP_0402-1UF,6.3V,10%,EMPTY,A':;

SECTION_NUMBER 1
 '@S9S_MB_2U_LIB.S9S_MB_2U(SCH_1):PAGE181_I146@PURE_QUANTA.Q_CAP(CHIPS)':
 C_PATH='@s9s_mb_2u_lib.s9s_mb_2u(sch_1):page181_i146@pure_quanta.q_cap(chips)',
 P_PATH='@s9s_mb_2u_lib.s9s_mb_2u(sch_1):page189_i146@pure_quanta.q_cap(chips)',
 PATH='I146',
 DRAWING='@S9S_MB_2U_LIB.S9S_MB_2U(SCH_1):PAGE181',
 PHYS_PAGE='189',
 XY='(3075,900)',
 ROT='0',
 VER='1',
 PACK_TYPE='0402',
 CDS_LIB='pure_quanta',
 CDS_PART_NAME='Q_CAP_0402-1UF,6.3V,10%,EMPTY,A',
 TOLERANCE='10%',
 MATERIAL='EMPTY',
 VOLTAGE='6.3V',
 VALUE='1UF',
 PRIM_FILE='./archive_libs/logical/q_cap/chips/chips.prt';

PART_NAME
 C1258 'Q_CAP_C0805-47UF,4V,20%,X6S,CHA':;

SECTION_NUMBER 1
 '@S9S_MB_2U_LIB.S9S_MB_2U(SCH_1):PAGE181_I157@PURE_QUANTA.Q_CAP(CHIPS)':
 C_PATH='@s9s_mb_2u_lib.s9s_mb_2u(sch_1):page181_i157@pure_quanta.q_cap(chips)',
 P_PATH='@s9s_mb_2u_lib.s9s_mb_2u(sch_1):page189_i157@pure_quanta.q_cap(chips)',
 PATH='I157',
 DRAWING='@S9S_MB_2U_LIB.S9S_MB_2U(SCH_1):PAGE181',
 PHYS_PAGE='189',
 XY='(3275,2650)',
 ROT='0',
 VER='1',
 PACK_TYPE='C0805',
 LOCATION='C1258',
 CDS_LIB='pure_quanta',
 CDS_PART_NAME='Q_CAP_C0805-47UF,4V,20%,X6S,CHA',
 TOLERANCE='20%',
 MATERIAL='X6S',
 VOLTAGE='4V',
 VALUE='47UF',
 PRIM_FILE='./archive_libs/logical/q_cap/chips/chips.prt';

PART_NAME
 C1259 'Q_CAP_C0805-47UF,4V,20%,X6S,CHA':;

SECTION_NUMBER 1
 '@S9S_MB_2U_LIB.S9S_MB_2U(SCH_1):PAGE181_I158@PURE_QUANTA.Q_CAP(CHIPS)':
 C_PATH='@s9s_mb_2u_lib.s9s_mb_2u(sch_1):page181_i158@pure_quanta.q_cap(chips)',
 P_PATH='@s9s_mb_2u_lib.s9s_mb_2u(sch_1):page189_i158@pure_quanta.q_cap(chips)',
 PATH='I158',
 DRAWING='@S9S_MB_2U_LIB.S9S_MB_2U(SCH_1):PAGE181',
 PHYS_PAGE='189',
 XY='(3300,0)',
 ROT='0',
 VER='1',
 PACK_TYPE='C0805',
 LOCATION='C1259',
 CDS_LIB='pure_quanta',
 CDS_PART_NAME='Q_CAP_C0805-47UF,4V,20%,X6S,CHA',
 TOLERANCE='20%',
 MATERIAL='X6S',
 VOLTAGE='4V',
 VALUE='47UF',
 PRIM_FILE='./archive_libs/logical/q_cap/chips/chips.prt';

PART_NAME
 C1260 'Q_CAP_C0603-10UF,6.3V,20%,X6S,A':;

SECTION_NUMBER 1
 '@S9S_MB_2U_LIB.S9S_MB_2U(SCH_1):PAGE181_I131@PURE_QUANTA.Q_CAP(CHIPS)':
 C_PATH='@s9s_mb_2u_lib.s9s_mb_2u(sch_1):page181_i131@pure_quanta.q_cap(chips)',
 P_PATH='@s9s_mb_2u_lib.s9s_mb_2u(sch_1):page189_i131@pure_quanta.q_cap(chips)',
 PATH='I131',
 DRAWING='@S9S_MB_2U_LIB.S9S_MB_2U(SCH_1):PAGE181',
 PHYS_PAGE='189',
 XY='(3550,3575)',
 ROT='0',
 VER='1',
 PACK_TYPE='C0603',
 CDS_LIB='pure_quanta',
 CDS_PART_NAME='Q_CAP_C0603-10UF,6.3V,20%,X6S,A',
 TOLERANCE='20%',
 MATERIAL='X6S',
 VOLTAGE='6.3V',
 VALUE='10UF',
 PRIM_FILE='./archive_libs/logical/q_cap/chips/chips.prt';

PART_NAME
 C1261 'Q_CAP_C0603-10UF,6.3V,20%,X6S,A':;

SECTION_NUMBER 1
 '@S9S_MB_2U_LIB.S9S_MB_2U(SCH_1):PAGE181_I142@PURE_QUANTA.Q_CAP(CHIPS)':
 C_PATH='@s9s_mb_2u_lib.s9s_mb_2u(sch_1):page181_i142@pure_quanta.q_cap(chips)',
 P_PATH='@s9s_mb_2u_lib.s9s_mb_2u(sch_1):page189_i142@pure_quanta.q_cap(chips)',
 PATH='I142',
 DRAWING='@S9S_MB_2U_LIB.S9S_MB_2U(SCH_1):PAGE181',
 PHYS_PAGE='189',
 XY='(3600,900)',
 ROT='0',
 VER='1',
 PACK_TYPE='C0603',
 CDS_LIB='pure_quanta',
 CDS_PART_NAME='Q_CAP_C0603-10UF,6.3V,20%,X6S,A',
 TOLERANCE='20%',
 MATERIAL='X6S',
 VOLTAGE='6.3V',
 VALUE='10UF',
 PRIM_FILE='./archive_libs/logical/q_cap/chips/chips.prt';

PART_NAME
 C1262 'Q_CAP_C0402-10UF,6.3V,20%,X6S,A':;

SECTION_NUMBER 1
 '@S9S_MB_2U_LIB.S9S_MB_2U(SCH_1):PAGE181_I104@PURE_QUANTA.Q_CAP(CHIPS)':
 C_PATH='@s9s_mb_2u_lib.s9s_mb_2u(sch_1):page181_i104@pure_quanta.q_cap(chips)',
 P_PATH='@s9s_mb_2u_lib.s9s_mb_2u(sch_1):page189_i104@pure_quanta.q_cap(chips)',
 PATH='I104',
 DRAWING='@S9S_MB_2U_LIB.S9S_MB_2U(SCH_1):PAGE181',
 PHYS_PAGE='189',
 XY='(3800,2650)',
 ROT='0',
 VER='1',
 PACK_TYPE='C0402',
 CDS_LIB='pure_quanta',
 CDS_PART_NAME='Q_CAP_C0402-10UF,6.3V,20%,X6S,A',
 TOLERANCE='20%',
 MATERIAL='X6S',
 VOLTAGE='6.3V',
 VALUE='10UF',
 PRIM_FILE='./archive_libs/logical/q_cap/chips/chips.prt';

PART_NAME
 C1263 'Q_CAP_C0402-10UF,6.3V,20%,X6S,A':;

SECTION_NUMBER 1
 '@S9S_MB_2U_LIB.S9S_MB_2U(SCH_1):PAGE181_I119@PURE_QUANTA.Q_CAP(CHIPS)':
 C_PATH='@s9s_mb_2u_lib.s9s_mb_2u(sch_1):page181_i119@pure_quanta.q_cap(chips)',
 P_PATH='@s9s_mb_2u_lib.s9s_mb_2u(sch_1):page189_i119@pure_quanta.q_cap(chips)',
 PATH='I119',
 DRAWING='@S9S_MB_2U_LIB.S9S_MB_2U(SCH_1):PAGE181',
 PHYS_PAGE='189',
 XY='(3800,0)',
 ROT='0',
 VER='1',
 PACK_TYPE='C0402',
 CDS_LIB='pure_quanta',
 CDS_PART_NAME='Q_CAP_C0402-10UF,6.3V,20%,X6S,A',
 TOLERANCE='20%',
 MATERIAL='X6S',
 VOLTAGE='6.3V',
 VALUE='10UF',
 PRIM_FILE='./archive_libs/logical/q_cap/chips/chips.prt';

PART_NAME
 C1264 'Q_CAP_0402-1UF,6.3V,10%,EMPTY,A':;

SECTION_NUMBER 1
 '@S9S_MB_2U_LIB.S9S_MB_2U(SCH_1):PAGE181_I133@PURE_QUANTA.Q_CAP(CHIPS)':
 C_PATH='@s9s_mb_2u_lib.s9s_mb_2u(sch_1):page181_i133@pure_quanta.q_cap(chips)',
 P_PATH='@s9s_mb_2u_lib.s9s_mb_2u(sch_1):page189_i133@pure_quanta.q_cap(chips)',
 PATH='I133',
 DRAWING='@S9S_MB_2U_LIB.S9S_MB_2U(SCH_1):PAGE181',
 PHYS_PAGE='189',
 XY='(3950,3575)',
 ROT='0',
 VER='1',
 PACK_TYPE='0402',
 CDS_LIB='pure_quanta',
 CDS_PART_NAME='Q_CAP_0402-1UF,6.3V,10%,EMPTY,A',
 TOLERANCE='10%',
 MATERIAL='EMPTY',
 VOLTAGE='6.3V',
 VALUE='1UF',
 PRIM_FILE='./archive_libs/logical/q_cap/chips/chips.prt';

PART_NAME
 C1265 'Q_CAP_0402-1UF,6.3V,10%,EMPTY,A':;

SECTION_NUMBER 1
 '@S9S_MB_2U_LIB.S9S_MB_2U(SCH_1):PAGE181_I140@PURE_QUANTA.Q_CAP(CHIPS)':
 C_PATH='@s9s_mb_2u_lib.s9s_mb_2u(sch_1):page181_i140@pure_quanta.q_cap(chips)',
 P_PATH='@s9s_mb_2u_lib.s9s_mb_2u(sch_1):page189_i140@pure_quanta.q_cap(chips)',
 PATH='I140',
 DRAWING='@S9S_MB_2U_LIB.S9S_MB_2U(SCH_1):PAGE181',
 PHYS_PAGE='189',
 XY='(4000,900)',
 ROT='0',
 VER='1',
 PACK_TYPE='0402',
 CDS_LIB='pure_quanta',
 CDS_PART_NAME='Q_CAP_0402-1UF,6.3V,10%,EMPTY,A',
 TOLERANCE='10%',
 MATERIAL='EMPTY',
 VOLTAGE='6.3V',
 VALUE='1UF',
 PRIM_FILE='./archive_libs/logical/q_cap/chips/chips.prt';

PART_NAME
 C1266 'Q_CAP_C0402-10UF,6.3V,20%,X6S,A':;

SECTION_NUMBER 1
 '@S9S_MB_2U_LIB.S9S_MB_2U(SCH_1):PAGE181_I127@PURE_QUANTA.Q_CAP(CHIPS)':
 C_PATH='@s9s_mb_2u_lib.s9s_mb_2u(sch_1):page181_i127@pure_quanta.q_cap(chips)',
 P_PATH='@s9s_mb_2u_lib.s9s_mb_2u(sch_1):page189_i127@pure_quanta.q_cap(chips)',
 PATH='I127',
 DRAWING='@S9S_MB_2U_LIB.S9S_MB_2U(SCH_1):PAGE181',
 PHYS_PAGE='189',
 XY='(4250,0)',
 ROT='0',
 VER='1',
 PACK_TYPE='C0402',
 CDS_LIB='pure_quanta',
 CDS_PART_NAME='Q_CAP_C0402-10UF,6.3V,20%,X6S,A',
 TOLERANCE='20%',
 MATERIAL='X6S',
 VOLTAGE='6.3V',
 VALUE='10UF',
 PRIM_FILE='./archive_libs/logical/q_cap/chips/chips.prt';

PART_NAME
 C1272 'Q_CAP_C0805-47UF,4V,20%,X6S,CHA':;

SECTION_NUMBER 1
 '@S9S_MB_2U_LIB.S9S_MB_2U(SCH_1):PAGE181_I159@PURE_QUANTA.Q_CAP(CHIPS)':
 C_PATH='@s9s_mb_2u_lib.s9s_mb_2u(sch_1):page181_i159@pure_quanta.q_cap(chips)',
 P_PATH='@s9s_mb_2u_lib.s9s_mb_2u(sch_1):page189_i159@pure_quanta.q_cap(chips)',
 PATH='I159',
 DRAWING='@S9S_MB_2U_LIB.S9S_MB_2U(SCH_1):PAGE181',
 PHYS_PAGE='189',
 XY='(4700,2650)',
 ROT='0',
 VER='1',
 PACK_TYPE='C0805',
 LOCATION='C1272',
 CDS_LIB='pure_quanta',
 CDS_PART_NAME='Q_CAP_C0805-47UF,4V,20%,X6S,CHA',
 TOLERANCE='20%',
 MATERIAL='X6S',
 VOLTAGE='4V',
 VALUE='47UF',
 PRIM_FILE='./archive_libs/logical/q_cap/chips/chips.prt';

PART_NAME
 C1273 'Q_CAP_C0805-47UF,4V,20%,X6S,CHA':;

SECTION_NUMBER 1
 '@S9S_MB_2U_LIB.S9S_MB_2U(SCH_1):PAGE181_I151@PURE_QUANTA.Q_CAP(CHIPS)':
 C_PATH='@s9s_mb_2u_lib.s9s_mb_2u(sch_1):page181_i151@pure_quanta.q_cap(chips)',
 P_PATH='@s9s_mb_2u_lib.s9s_mb_2u(sch_1):page189_i151@pure_quanta.q_cap(chips)',
 PATH='I151',
 DRAWING='@S9S_MB_2U_LIB.S9S_MB_2U(SCH_1):PAGE181',
 PHYS_PAGE='189',
 XY='(4700,0)',
 ROT='0',
 VER='1',
 PACK_TYPE='C0805',
 LOCATION='C1273',
 CDS_LIB='pure_quanta',
 CDS_PART_NAME='Q_CAP_C0805-47UF,4V,20%,X6S,CHA',
 TOLERANCE='20%',
 MATERIAL='X6S',
 VOLTAGE='4V',
 VALUE='47UF',
 PRIM_FILE='./archive_libs/logical/q_cap/chips/chips.prt';

PART_NAME
 C1274 'Q_CAP_0402-0.1UF,25V,10%,X7R,CA':;

SECTION_NUMBER 1
 '@S9S_MB_2U_LIB.S9S_MB_2U(SCH_1):PAGE152_I59@PURE_QUANTA.Q_CAP(CHIPS)':
 C_PATH='@s9s_mb_2u_lib.s9s_mb_2u(sch_1):page152_i59@pure_quanta.q_cap(chips)',
 P_PATH='@s9s_mb_2u_lib.s9s_mb_2u(sch_1):page155_i59@pure_quanta.q_cap(chips)',
 PATH='I59',
 DRAWING='@S9S_MB_2U_LIB.S9S_MB_2U(SCH_1):PAGE152',
 PHYS_PAGE='155',
 XY='(-10050,2600)',
 ROT='2',
 VER='1',
 PACK_TYPE='0402',
 CDS_LIB='pure_quanta',
 CDS_PART_NAME='Q_CAP_0402-0.1UF,25V,10%,X7R,CA',
 TOLERANCE='10%',
 MATERIAL='X7R',
 VOLTAGE='25V',
 VALUE='0.1UF',
 PRIM_FILE='./archive_libs/logical/q_cap/chips/chips.prt';

PART_NAME
 C1275 'Q_CAP_0402-0.1UF,25V,10%,X7R,CA':;

SECTION_NUMBER 1
 '@S9S_MB_2U_LIB.S9S_MB_2U(SCH_1):PAGE152_I49@PURE_QUANTA.Q_CAP(CHIPS)':
 C_PATH='@s9s_mb_2u_lib.s9s_mb_2u(sch_1):page152_i49@pure_quanta.q_cap(chips)',
 P_PATH='@s9s_mb_2u_lib.s9s_mb_2u(sch_1):page155_i49@pure_quanta.q_cap(chips)',
 PATH='I49',
 DRAWING='@S9S_MB_2U_LIB.S9S_MB_2U(SCH_1):PAGE152',
 PHYS_PAGE='155',
 XY='(-6425,2700)',
 ROT='0',
 VER='1',
 PACK_TYPE='0402',
 CDS_LIB='pure_quanta',
 CDS_PART_NAME='Q_CAP_0402-0.1UF,25V,10%,X7R,CA',
 TOLERANCE='10%',
 MATERIAL='X7R',
 VOLTAGE='25V',
 VALUE='0.1UF',
 PRIM_FILE='./archive_libs/logical/q_cap/chips/chips.prt';

PART_NAME
 C1276 'Q_CAP_C0805-22UF,16V,20%,X6S,CA':;

SECTION_NUMBER 1
 '@S9S_MB_2U_LIB.S9S_MB_2U(SCH_1):PAGE297_I260@PURE_QUANTA.Q_CAP(CHIPS)':
 C_PATH='@s9s_mb_2u_lib.s9s_mb_2u(sch_1):page297_i260@pure_quanta.q_cap(chips)',
 P_PATH='@s9s_mb_2u_lib.s9s_mb_2u(sch_1):page191_i260@pure_quanta.q_cap(chips)',
 PATH='I260',
 DRAWING='@S9S_MB_2U_LIB.S9S_MB_2U(SCH_1):PAGE297',
 PHYS_PAGE='191',
 XY='(2325,2825)',
 ROT='0',
 VER='1',
 PACK_TYPE='C0805',
 CDS_LIB='pure_quanta',
 CDS_PART_NAME='Q_CAP_C0805-22UF,16V,20%,X6S,CA',
 TOLERANCE='20%',
 MATERIAL='X6S',
 VOLTAGE='16V',
 VALUE='22UF',
 PRIM_FILE='./archive_libs/logical/q_cap/chips/chips.prt';

PART_NAME
 C1277 'Q_CAP_C0805-22UF,16V,20%,X6S,CA':;

SECTION_NUMBER 1
 '@S9S_MB_2U_LIB.S9S_MB_2U(SCH_1):PAGE297_I237@PURE_QUANTA.Q_CAP(CHIPS)':
 C_PATH='@s9s_mb_2u_lib.s9s_mb_2u(sch_1):page297_i237@pure_quanta.q_cap(chips)',
 P_PATH='@s9s_mb_2u_lib.s9s_mb_2u(sch_1):page191_i237@pure_quanta.q_cap(chips)',
 PATH='I237',
 DRAWING='@S9S_MB_2U_LIB.S9S_MB_2U(SCH_1):PAGE297',
 PHYS_PAGE='191',
 XY='(2600,2825)',
 ROT='0',
 VER='1',
 PACK_TYPE='C0805',
 CDS_LIB='pure_quanta',
 CDS_PART_NAME='Q_CAP_C0805-22UF,16V,20%,X6S,CA',
 TOLERANCE='20%',
 MATERIAL='X6S',
 VOLTAGE='16V',
 VALUE='22UF',
 PRIM_FILE='./archive_libs/logical/q_cap/chips/chips.prt';

PART_NAME
 C1278 'Q_CAP_0402-0.1UF,25V,10%,X7R,CA':;

SECTION_NUMBER 1
 '@S9S_MB_2U_LIB.S9S_MB_2U(SCH_1):PAGE297_I258@PURE_QUANTA.Q_CAP(CHIPS)':
 C_PATH='@s9s_mb_2u_lib.s9s_mb_2u(sch_1):page297_i258@pure_quanta.q_cap(chips)',
 P_PATH='@s9s_mb_2u_lib.s9s_mb_2u(sch_1):page191_i258@pure_quanta.q_cap(chips)',
 PATH='I258',
 DRAWING='@S9S_MB_2U_LIB.S9S_MB_2U(SCH_1):PAGE297',
 PHYS_PAGE='191',
 XY='(3000,2825)',
 ROT='0',
 VER='1',
 PACK_TYPE='0402',
 CDS_LIB='pure_quanta',
 CDS_PART_NAME='Q_CAP_0402-0.1UF,25V,10%,X7R,CA',
 TOLERANCE='10%',
 MATERIAL='X7R',
 VOLTAGE='25V',
 VALUE='0.1UF',
 PRIM_FILE='./archive_libs/logical/q_cap/chips/chips.prt';

PART_NAME
 C1279 'Q_CAP_0402-0.1UF,25V,10%,X7R,CA':;

SECTION_NUMBER 1
 '@S9S_MB_2U_LIB.S9S_MB_2U(SCH_1):PAGE297_I252@PURE_QUANTA.Q_CAP(CHIPS)':
 C_PATH='@s9s_mb_2u_lib.s9s_mb_2u(sch_1):page297_i252@pure_quanta.q_cap(chips)',
 P_PATH='@s9s_mb_2u_lib.s9s_mb_2u(sch_1):page191_i252@pure_quanta.q_cap(chips)',
 PATH='I252',
 DRAWING='@S9S_MB_2U_LIB.S9S_MB_2U(SCH_1):PAGE297',
 PHYS_PAGE='191',
 XY='(3275,2825)',
 ROT='0',
 VER='1',
 PACK_TYPE='0402',
 CDS_LIB='pure_quanta',
 CDS_PART_NAME='Q_CAP_0402-0.1UF,25V,10%,X7R,CA',
 TOLERANCE='10%',
 MATERIAL='X7R',
 VOLTAGE='25V',
 VALUE='0.1UF',
 PRIM_FILE='./archive_libs/logical/q_cap/chips/chips.prt';

PART_NAME
 C1282 'Q_CAP_0402-0.1UF,25V,10%,X7R,CA':;

SECTION_NUMBER 1
 '@S9S_MB_2U_LIB.S9S_MB_2U(SCH_1):PAGE297_I247@PURE_QUANTA.Q_CAP(CHIPS)':
 C_PATH='@s9s_mb_2u_lib.s9s_mb_2u(sch_1):page297_i247@pure_quanta.q_cap(chips)',
 P_PATH='@s9s_mb_2u_lib.s9s_mb_2u(sch_1):page191_i247@pure_quanta.q_cap(chips)',
 PATH='I247',
 DRAWING='@S9S_MB_2U_LIB.S9S_MB_2U(SCH_1):PAGE297',
 PHYS_PAGE='191',
 XY='(4350,2825)',
 ROT='0',
 VER='1',
 PACK_TYPE='0402',
 CDS_LIB='pure_quanta',
 CDS_PART_NAME='Q_CAP_0402-0.1UF,25V,10%,X7R,CA',
 TOLERANCE='10%',
 MATERIAL='X7R',
 VOLTAGE='25V',
 VALUE='0.1UF',
 PRIM_FILE='./archive_libs/logical/q_cap/chips/chips.prt';

PART_NAME
 C1283 'Q_CAP_0402-0.1UF,25V,10%,X7R,CA':;

SECTION_NUMBER 1
 '@S9S_MB_2U_LIB.S9S_MB_2U(SCH_1):PAGE297_I245@PURE_QUANTA.Q_CAP(CHIPS)':
 C_PATH='@s9s_mb_2u_lib.s9s_mb_2u(sch_1):page297_i245@pure_quanta.q_cap(chips)',
 P_PATH='@s9s_mb_2u_lib.s9s_mb_2u(sch_1):page191_i245@pure_quanta.q_cap(chips)',
 PATH='I245',
 DRAWING='@S9S_MB_2U_LIB.S9S_MB_2U(SCH_1):PAGE297',
 PHYS_PAGE='191',
 XY='(4600,2825)',
 ROT='0',
 VER='1',
 PACK_TYPE='0402',
 CDS_LIB='pure_quanta',
 CDS_PART_NAME='Q_CAP_0402-0.1UF,25V,10%,X7R,CA',
 TOLERANCE='10%',
 MATERIAL='X7R',
 VOLTAGE='25V',
 VALUE='0.1UF',
 PRIM_FILE='./archive_libs/logical/q_cap/chips/chips.prt';

PART_NAME
 C1288 'Q_CAP_0402-0.1UF,25V,10%,X7R,CA':;

SECTION_NUMBER 1
 '@S9S_MB_2U_LIB.S9S_MB_2U(SCH_1):PAGE137_I112@PURE_QUANTA.Q_CAP(CHIPS)':
 C_PATH='@s9s_mb_2u_lib.s9s_mb_2u(sch_1):page137_i112@pure_quanta.q_cap(chips)',
 P_PATH='@s9s_mb_2u_lib.s9s_mb_2u(sch_1):page134_i112@pure_quanta.q_cap(chips)',
 PATH='I112',
 DRAWING='@S9S_MB_2U_LIB.S9S_MB_2U(SCH_1):PAGE137',
 PHYS_PAGE='134',
 XY='(-9525,-2075)',
 ROT='2',
 VER='1',
 PACK_TYPE='0402',
 CDS_LIB='pure_quanta',
 CDS_PART_NAME='Q_CAP_0402-0.1UF,25V,10%,X7R,CA',
 TOLERANCE='10%',
 MATERIAL='X7R',
 VOLTAGE='25V',
 VALUE='0.1UF',
 PRIM_FILE='./archive_libs/logical/q_cap/chips/chips.prt';

PART_NAME
 C1289 'Q_CAP_C0402-1UF,25V,10%,X6S,CHA':;

SECTION_NUMBER 1
 '@S9S_MB_2U_LIB.S9S_MB_2U(SCH_1):PAGE137_I110@PURE_QUANTA.Q_CAP(CHIPS)':
 C_PATH='@s9s_mb_2u_lib.s9s_mb_2u(sch_1):page137_i110@pure_quanta.q_cap(chips)',
 P_PATH='@s9s_mb_2u_lib.s9s_mb_2u(sch_1):page134_i110@pure_quanta.q_cap(chips)',
 PATH='I110',
 DRAWING='@S9S_MB_2U_LIB.S9S_MB_2U(SCH_1):PAGE137',
 PHYS_PAGE='134',
 XY='(-9175,-2075)',
 ROT='2',
 VER='1',
 PACK_TYPE='C0402',
 CDS_LIB='pure_quanta',
 CDS_PART_NAME='Q_CAP_C0402-1UF,25V,10%,X6S,CHA',
 TOLERANCE='10%',
 MATERIAL='X6S',
 VOLTAGE='25V',
 VALUE='1UF',
 PRIM_FILE='./archive_libs/logical/q_cap/chips/chips.prt';

PART_NAME
 C1290 'Q_CAP_C0402-1UF,25V,10%,X6S,CHA':;

SECTION_NUMBER 1
 '@S9S_MB_2U_LIB.S9S_MB_2U(SCH_1):PAGE226_I43@PURE_QUANTA.Q_CAP(CHIPS)':
 C_PATH='@s9s_mb_2u_lib.s9s_mb_2u(sch_1):page226_i43@pure_quanta.q_cap(chips)',
 P_PATH='@s9s_mb_2u_lib.s9s_mb_2u(sch_1):page239_i43@pure_quanta.q_cap(chips)',
 PATH='I43',
 DRAWING='@S9S_MB_2U_LIB.S9S_MB_2U(SCH_1):PAGE226',
 PHYS_PAGE='239',
 XY='(-10700,2200)',
 ROT='0',
 VER='1',
 PACK_TYPE='C0402',
 CDS_LIB='pure_quanta',
 CDS_PART_NAME='Q_CAP_C0402-1UF,25V,10%,X6S,CHA',
 TOLERANCE='10%',
 MATERIAL='X6S',
 VOLTAGE='25V',
 VALUE='1UF',
 PRIM_FILE='./archive_libs/logical/q_cap/chips/chips.prt';

PART_NAME
 C1291 'Q_CAP_C0402-1UF,25V,10%,X6S,CHA':;

SECTION_NUMBER 1
 '@S9S_MB_2U_LIB.S9S_MB_2U(SCH_1):PAGE226_I16@PURE_QUANTA.Q_CAP(CHIPS)':
 C_PATH='@s9s_mb_2u_lib.s9s_mb_2u(sch_1):page226_i16@pure_quanta.q_cap(chips)',
 P_PATH='@s9s_mb_2u_lib.s9s_mb_2u(sch_1):page239_i16@pure_quanta.q_cap(chips)',
 PATH='I16',
 DRAWING='@S9S_MB_2U_LIB.S9S_MB_2U(SCH_1):PAGE226',
 PHYS_PAGE='239',
 XY='(-10675,3775)',
 ROT='0',
 VER='1',
 PACK_TYPE='C0402',
 CDS_LIB='pure_quanta',
 CDS_PART_NAME='Q_CAP_C0402-1UF,25V,10%,X6S,CHA',
 TOLERANCE='10%',
 MATERIAL='X6S',
 VOLTAGE='25V',
 VALUE='1UF',
 PRIM_FILE='./archive_libs/logical/q_cap/chips/chips.prt';

PART_NAME
 C1292 'Q_CAP_0402-0.1UF,25V,10%,X7R,CA':;

SECTION_NUMBER 1
 '@S9S_MB_2U_LIB.S9S_MB_2U(SCH_1):PAGE137_I90@PURE_QUANTA.Q_CAP(CHIPS)':
 C_PATH='@s9s_mb_2u_lib.s9s_mb_2u(sch_1):page137_i90@pure_quanta.q_cap(chips)',
 P_PATH='@s9s_mb_2u_lib.s9s_mb_2u(sch_1):page134_i90@pure_quanta.q_cap(chips)',
 PATH='I90',
 DRAWING='@S9S_MB_2U_LIB.S9S_MB_2U(SCH_1):PAGE137',
 PHYS_PAGE='134',
 XY='(-5275,-1950)',
 ROT='0',
 VER='1',
 PACK_TYPE='0402',
 CDS_LIB='pure_quanta',
 CDS_PART_NAME='Q_CAP_0402-0.1UF,25V,10%,X7R,CA',
 TOLERANCE='10%',
 MATERIAL='X7R',
 VOLTAGE='25V',
 VALUE='0.1UF',
 PRIM_FILE='./archive_libs/logical/q_cap/chips/chips.prt';

PART_NAME
 C1293 'Q_CAP_C0402-1UF,25V,10%,X6S,CHA':;

SECTION_NUMBER 1
 '@S9S_MB_2U_LIB.S9S_MB_2U(SCH_1):PAGE137_I95@PURE_QUANTA.Q_CAP(CHIPS)':
 C_PATH='@s9s_mb_2u_lib.s9s_mb_2u(sch_1):page137_i95@pure_quanta.q_cap(chips)',
 P_PATH='@s9s_mb_2u_lib.s9s_mb_2u(sch_1):page134_i95@pure_quanta.q_cap(chips)',
 PATH='I95',
 DRAWING='@S9S_MB_2U_LIB.S9S_MB_2U(SCH_1):PAGE137',
 PHYS_PAGE='134',
 XY='(-7050,-2075)',
 ROT='0',
 VER='1',
 PACK_TYPE='C0402',
 CDS_LIB='pure_quanta',
 CDS_PART_NAME='Q_CAP_C0402-1UF,25V,10%,X6S,CHA',
 TOLERANCE='10%',
 MATERIAL='X6S',
 VOLTAGE='25V',
 VALUE='1UF',
 PRIM_FILE='./archive_libs/logical/q_cap/chips/chips.prt';

PART_NAME
 C1296 'Q_CAP_0402-1000PF,50V,5%,X7R,TA':;

SECTION_NUMBER 1
 '@S9S_MB_2U_LIB.S9S_MB_2U(SCH_1):PAGE268_I31@PURE_QUANTA.Q_CAP(CHIPS)':
 C_PATH='@s9s_mb_2u_lib.s9s_mb_2u(sch_1):page268_i31@pure_quanta.q_cap(chips)',
 P_PATH='@s9s_mb_2u_lib.s9s_mb_2u(sch_1):page282_i31@pure_quanta.q_cap(chips)',
 PATH='I31',
 DRAWING='@S9S_MB_2U_LIB.S9S_MB_2U(SCH_1):PAGE268',
 PHYS_PAGE='282',
 XY='(-4350,10450)',
 ROT='0',
 VER='1',
 PACK_TYPE='0402',
 LOCATION='C1296',
 CDS_LIB='pure_quanta',
 CDS_PART_NAME='Q_CAP_0402-1000PF,50V,5%,X7R,TA',
 TOLERANCE='5%',
 MATERIAL='X7R',
 VOLTAGE='50V',
 VALUE='1000PF',
 PRIM_FILE='./archive_libs/logical/q_cap/chips/chips.prt';

PART_NAME
 C1297 'Q_CAP_0402-1000PF,50V,5%,X7R,TA':;

SECTION_NUMBER 1
 '@S9S_MB_2U_LIB.S9S_MB_2U(SCH_1):PAGE286_I37@PURE_QUANTA.Q_CAP(CHIPS)':
 C_PATH='@s9s_mb_2u_lib.s9s_mb_2u(sch_1):page286_i37@pure_quanta.q_cap(chips)',
 P_PATH='@s9s_mb_2u_lib.s9s_mb_2u(sch_1):page300_i37@pure_quanta.q_cap(chips)',
 PATH='I37',
 DRAWING='@S9S_MB_2U_LIB.S9S_MB_2U(SCH_1):PAGE286',
 PHYS_PAGE='300',
 XY='(7875,7550)',
 ROT='0',
 VER='1',
 PACK_TYPE='0402',
 LOCATION='C1297',
 CDS_LIB='pure_quanta',
 CDS_PART_NAME='Q_CAP_0402-1000PF,50V,5%,X7R,TA',
 TOLERANCE='5%',
 MATERIAL='X7R',
 VOLTAGE='50V',
 VALUE='1000PF',
 PRIM_FILE='./archive_libs/logical/q_cap/chips/chips.prt';

PART_NAME
 C1300 'Q_CAP_0402-1000PF,50V,5%,EMPTYA':;

SECTION_NUMBER 1
 '@S9S_MB_2U_LIB.S9S_MB_2U(SCH_1):PAGE267_I12@PURE_QUANTA.Q_CAP(CHIPS)':
 C_PATH='@s9s_mb_2u_lib.s9s_mb_2u(sch_1):page267_i12@pure_quanta.q_cap(chips)',
 P_PATH='@s9s_mb_2u_lib.s9s_mb_2u(sch_1):page281_i12@pure_quanta.q_cap(chips)',
 PATH='I12',
 DRAWING='@S9S_MB_2U_LIB.S9S_MB_2U(SCH_1):PAGE267',
 PHYS_PAGE='281',
 XY='(-10375,3400)',
 ROT='2',
 VER='1',
 PACK_TYPE='0402',
 LOCATION='C1300',
 CDS_LIB='pure_quanta',
 CDS_PART_NAME='Q_CAP_0402-1000PF,50V,5%,EMPTYA',
 TOLERANCE='5%',
 MATERIAL='EMPTY',
 VOLTAGE='50V',
 VALUE='1000PF',
 PRIM_FILE='./archive_libs/logical/q_cap/chips/chips.prt';

PART_NAME
 C1301 'Q_CAP_0402-1000PF,50V,5%,X7R,TA':;

SECTION_NUMBER 1
 '@S9S_MB_2U_LIB.S9S_MB_2U(SCH_1):PAGE267_I30@PURE_QUANTA.Q_CAP(CHIPS)':
 C_PATH='@s9s_mb_2u_lib.s9s_mb_2u(sch_1):page267_i30@pure_quanta.q_cap(chips)',
 P_PATH='@s9s_mb_2u_lib.s9s_mb_2u(sch_1):page281_i30@pure_quanta.q_cap(chips)',
 PATH='I30',
 DRAWING='@S9S_MB_2U_LIB.S9S_MB_2U(SCH_1):PAGE267',
 PHYS_PAGE='281',
 XY='(-6800,4200)',
 ROT='0',
 VER='2',
 PACK_TYPE='0402',
 LOCATION='C1301',
 CDS_LIB='pure_quanta',
 CDS_PART_NAME='Q_CAP_0402-1000PF,50V,5%,X7R,TA',
 TOLERANCE='5%',
 MATERIAL='X7R',
 VOLTAGE='50V',
 VALUE='1000PF',
 PRIM_FILE='./archive_libs/logical/q_cap/chips/chips.prt';

PART_NAME
 C1302 'Q_CAP_C0402-22UF,4V,20%,X6S,CHA':;

SECTION_NUMBER 1
 '@S9S_MB_2U_LIB.S9S_MB_2U(SCH_1):PAGE227_I82@PURE_QUANTA.Q_CAP(CHIPS)':
 C_PATH='@s9s_mb_2u_lib.s9s_mb_2u(sch_1):page227_i82@pure_quanta.q_cap(chips)',
 P_PATH='@s9s_mb_2u_lib.s9s_mb_2u(sch_1):page240_i82@pure_quanta.q_cap(chips)',
 PATH='I82',
 DRAWING='@S9S_MB_2U_LIB.S9S_MB_2U(SCH_1):PAGE227',
 PHYS_PAGE='240',
 XY='(-14975,2175)',
 ROT='0',
 VER='1',
 PACK_TYPE='C0402',
 LOCATION='C1302',
 CDS_LIB='pure_quanta',
 CDS_PART_NAME='Q_CAP_C0402-22UF,4V,20%,X6S,CHA',
 TOLERANCE='20%',
 MATERIAL='X6S',
 VOLTAGE='4V',
 VALUE='22UF',
 PRIM_FILE='./archive_libs/logical/q_cap/chips/chips.prt';

PART_NAME
 C1305 'Q_CAP_0402-0.1UF,25V,10%,X7R,CA':;

SECTION_NUMBER 1
 '@S9S_MB_2U_LIB.S9S_MB_2U(SCH_1):PAGE183_I52@PURE_QUANTA.Q_CAP(CHIPS)':
 C_PATH='@s9s_mb_2u_lib.s9s_mb_2u(sch_1):page183_i52@pure_quanta.q_cap(chips)',
 P_PATH='@s9s_mb_2u_lib.s9s_mb_2u(sch_1):page194_i52@pure_quanta.q_cap(chips)',
 PATH='I52',
 DRAWING='@S9S_MB_2U_LIB.S9S_MB_2U(SCH_1):PAGE183',
 PHYS_PAGE='194',
 XY='(-425,3775)',
 ROT='2',
 VER='1',
 PACK_TYPE='0402',
 CDS_LIB='pure_quanta',
 CDS_PART_NAME='Q_CAP_0402-0.1UF,25V,10%,X7R,CA',
 TOLERANCE='10%',
 MATERIAL='X7R',
 VOLTAGE='25V',
 VALUE='0.1UF',
 PRIM_FILE='./archive_libs/logical/q_cap/chips/chips.prt';

PART_NAME
 C1307 'Q_CAP_0402-1000PF,50V,5%,EMPTYA':;

SECTION_NUMBER 1
 '@S9S_MB_2U_LIB.S9S_MB_2U(SCH_1):PAGE268_I4@PURE_QUANTA.Q_CAP(CHIPS)':
 C_PATH='@s9s_mb_2u_lib.s9s_mb_2u(sch_1):page268_i4@pure_quanta.q_cap(chips)',
 P_PATH='@s9s_mb_2u_lib.s9s_mb_2u(sch_1):page282_i4@pure_quanta.q_cap(chips)',
 PATH='I4',
 DRAWING='@S9S_MB_2U_LIB.S9S_MB_2U(SCH_1):PAGE268',
 PHYS_PAGE='282',
 XY='(-9225,9675)',
 ROT='2',
 VER='1',
 PACK_TYPE='0402',
 LOCATION='C1307',
 CDS_LIB='pure_quanta',
 CDS_PART_NAME='Q_CAP_0402-1000PF,50V,5%,EMPTYA',
 TOLERANCE='5%',
 MATERIAL='EMPTY',
 VOLTAGE='50V',
 VALUE='1000PF',
 PRIM_FILE='./archive_libs/logical/q_cap/chips/chips.prt';

PART_NAME
 C1308 'Q_CAP_0402-1000PF,50V,5%,EMPTYA':;

SECTION_NUMBER 1
 '@S9S_MB_2U_LIB.S9S_MB_2U(SCH_1):PAGE286_I6@PURE_QUANTA.Q_CAP(CHIPS)':
 C_PATH='@s9s_mb_2u_lib.s9s_mb_2u(sch_1):page286_i6@pure_quanta.q_cap(chips)',
 P_PATH='@s9s_mb_2u_lib.s9s_mb_2u(sch_1):page300_i6@pure_quanta.q_cap(chips)',
 PATH='I6',
 DRAWING='@S9S_MB_2U_LIB.S9S_MB_2U(SCH_1):PAGE286',
 PHYS_PAGE='300',
 XY='(2400,7025)',
 ROT='2',
 VER='1',
 PACK_TYPE='0402',
 LOCATION='C1308',
 CDS_LIB='pure_quanta',
 CDS_PART_NAME='Q_CAP_0402-1000PF,50V,5%,EMPTYA',
 TOLERANCE='5%',
 MATERIAL='EMPTY',
 VOLTAGE='50V',
 VALUE='1000PF',
 PRIM_FILE='./archive_libs/logical/q_cap/chips/chips.prt';

PART_NAME
 C1309 'Q_CAP_C0603-10UF,6.3V,20%,X6S,A':;

SECTION_NUMBER 1
 '@S9S_MB_2U_LIB.S9S_MB_2U(SCH_1):PAGE199_I44@PURE_QUANTA.Q_CAP(CHIPS)':
 C_PATH='@s9s_mb_2u_lib.s9s_mb_2u(sch_1):page199_i44@pure_quanta.q_cap(chips)',
 P_PATH='@s9s_mb_2u_lib.s9s_mb_2u(sch_1):page210_i44@pure_quanta.q_cap(chips)',
 PATH='I44',
 DRAWING='@S9S_MB_2U_LIB.S9S_MB_2U(SCH_1):PAGE199',
 PHYS_PAGE='210',
 XY='(-11850,6225)',
 ROT='0',
 VER='1',
 PACK_TYPE='C0603',
 CDS_LIB='pure_quanta',
 CDS_PART_NAME='Q_CAP_C0603-10UF,6.3V,20%,X6S,A',
 TOLERANCE='20%',
 MATERIAL='X6S',
 VOLTAGE='6.3V',
 VALUE='10UF',
 PRIM_FILE='./archive_libs/logical/q_cap/chips/chips.prt';

PART_NAME
 C1310 'Q_CAP_C0603-10UF,6.3V,20%,X6S,A':;

SECTION_NUMBER 1
 '@S9S_MB_2U_LIB.S9S_MB_2U(SCH_1):PAGE199_I59@PURE_QUANTA.Q_CAP(CHIPS)':
 C_PATH='@s9s_mb_2u_lib.s9s_mb_2u(sch_1):page199_i59@pure_quanta.q_cap(chips)',
 P_PATH='@s9s_mb_2u_lib.s9s_mb_2u(sch_1):page210_i59@pure_quanta.q_cap(chips)',
 PATH='I59',
 DRAWING='@S9S_MB_2U_LIB.S9S_MB_2U(SCH_1):PAGE199',
 PHYS_PAGE='210',
 XY='(-11850,4925)',
 ROT='0',
 VER='1',
 PACK_TYPE='C0603',
 CDS_LIB='pure_quanta',
 CDS_PART_NAME='Q_CAP_C0603-10UF,6.3V,20%,X6S,A',
 TOLERANCE='20%',
 MATERIAL='X6S',
 VOLTAGE='6.3V',
 VALUE='10UF',
 PRIM_FILE='./archive_libs/logical/q_cap/chips/chips.prt';

PART_NAME
 C1311 'Q_CAP_C0402-1UF,25V,10%,X6S,CHA':;

SECTION_NUMBER 1
 '@S9S_MB_2U_LIB.S9S_MB_2U(SCH_1):PAGE199_I43@PURE_QUANTA.Q_CAP(CHIPS)':
 C_PATH='@s9s_mb_2u_lib.s9s_mb_2u(sch_1):page199_i43@pure_quanta.q_cap(chips)',
 P_PATH='@s9s_mb_2u_lib.s9s_mb_2u(sch_1):page210_i43@pure_quanta.q_cap(chips)',
 PATH='I43',
 DRAWING='@S9S_MB_2U_LIB.S9S_MB_2U(SCH_1):PAGE199',
 BOM_COST='VR_SYSTEM ',
 PHYS_PAGE='210',
 XY='(-11500,6225)',
 ROT='0',
 VER='1',
 PACK_TYPE='C0402',
 CDS_LIB='pure_quanta',
 CDS_PART_NAME='Q_CAP_C0402-1UF,25V,10%,X6S,CHA',
 TOLERANCE='10%',
 MATERIAL='X6S',
 VOLTAGE='25V',
 VALUE='1UF',
 PRIM_FILE='./archive_libs/logical/q_cap/chips/chips.prt';

PART_NAME
 C1312 'Q_CAP_C0402-1UF,25V,10%,X6S,CHA':;

SECTION_NUMBER 1
 '@S9S_MB_2U_LIB.S9S_MB_2U(SCH_1):PAGE199_I58@PURE_QUANTA.Q_CAP(CHIPS)':
 C_PATH='@s9s_mb_2u_lib.s9s_mb_2u(sch_1):page199_i58@pure_quanta.q_cap(chips)',
 P_PATH='@s9s_mb_2u_lib.s9s_mb_2u(sch_1):page210_i58@pure_quanta.q_cap(chips)',
 PATH='I58',
 DRAWING='@S9S_MB_2U_LIB.S9S_MB_2U(SCH_1):PAGE199',
 BOM_COST='VR_SYSTEM ',
 PHYS_PAGE='210',
 XY='(-11500,4925)',
 ROT='0',
 VER='1',
 PACK_TYPE='C0402',
 CDS_LIB='pure_quanta',
 CDS_PART_NAME='Q_CAP_C0402-1UF,25V,10%,X6S,CHA',
 TOLERANCE='10%',
 MATERIAL='X6S',
 VOLTAGE='25V',
 VALUE='1UF',
 PRIM_FILE='./archive_libs/logical/q_cap/chips/chips.prt';

PART_NAME
 C1313 'Q_CAP_C0603-10UF,6.3V,20%,X6S,A':;

SECTION_NUMBER 1
 '@S9S_MB_2U_LIB.S9S_MB_2U(SCH_1):PAGE199_I48@PURE_QUANTA.Q_CAP(CHIPS)':
 C_PATH='@s9s_mb_2u_lib.s9s_mb_2u(sch_1):page199_i48@pure_quanta.q_cap(chips)',
 P_PATH='@s9s_mb_2u_lib.s9s_mb_2u(sch_1):page210_i48@pure_quanta.q_cap(chips)',
 PATH='I48',
 DRAWING='@S9S_MB_2U_LIB.S9S_MB_2U(SCH_1):PAGE199',
 PHYS_PAGE='210',
 XY='(-9250,6225)',
 ROT='0',
 VER='1',
 PACK_TYPE='C0603',
 CDS_LIB='pure_quanta',
 CDS_PART_NAME='Q_CAP_C0603-10UF,6.3V,20%,X6S,A',
 TOLERANCE='20%',
 MATERIAL='X6S',
 VOLTAGE='6.3V',
 VALUE='10UF',
 PRIM_FILE='./archive_libs/logical/q_cap/chips/chips.prt';

PART_NAME
 C1314 'Q_CAP_C0603-10UF,6.3V,20%,X6S,A':;

SECTION_NUMBER 1
 '@S9S_MB_2U_LIB.S9S_MB_2U(SCH_1):PAGE199_I53@PURE_QUANTA.Q_CAP(CHIPS)':
 C_PATH='@s9s_mb_2u_lib.s9s_mb_2u(sch_1):page199_i53@pure_quanta.q_cap(chips)',
 P_PATH='@s9s_mb_2u_lib.s9s_mb_2u(sch_1):page210_i53@pure_quanta.q_cap(chips)',
 PATH='I53',
 DRAWING='@S9S_MB_2U_LIB.S9S_MB_2U(SCH_1):PAGE199',
 PHYS_PAGE='210',
 XY='(-9250,4925)',
 ROT='0',
 VER='1',
 PACK_TYPE='C0603',
 CDS_LIB='pure_quanta',
 CDS_PART_NAME='Q_CAP_C0603-10UF,6.3V,20%,X6S,A',
 TOLERANCE='20%',
 MATERIAL='X6S',
 VOLTAGE='6.3V',
 VALUE='10UF',
 PRIM_FILE='./archive_libs/logical/q_cap/chips/chips.prt';

PART_NAME
 C1315 'Q_CAP_C0402-1UF,25V,10%,X6S,CHA':;

SECTION_NUMBER 1
 '@S9S_MB_2U_LIB.S9S_MB_2U(SCH_1):PAGE232_I24@PURE_QUANTA.Q_CAP(CHIPS)':
 C_PATH='@s9s_mb_2u_lib.s9s_mb_2u(sch_1):page232_i24@pure_quanta.q_cap(chips)',
 P_PATH='@s9s_mb_2u_lib.s9s_mb_2u(sch_1):page244_i24@pure_quanta.q_cap(chips)',
 PATH='I24',
 DRAWING='@S9S_MB_2U_LIB.S9S_MB_2U(SCH_1):PAGE232',
 PHYS_PAGE='244',
 XY='(-850,2100)',
 ROT='2',
 VER='1',
 PACK_TYPE='C0402',
 CDS_LIB='pure_quanta',
 CDS_PART_NAME='Q_CAP_C0402-1UF,25V,10%,X6S,CHA',
 TOLERANCE='10%',
 MATERIAL='X6S',
 VOLTAGE='25V',
 VALUE='1UF',
 PRIM_FILE='./archive_libs/logical/q_cap/chips/chips.prt';

PART_NAME
 C1316 'Q_CAP_C0402-0.047UF,25V,10%,X7A':;

SECTION_NUMBER 1
 '@S9S_MB_2U_LIB.S9S_MB_2U(SCH_1):PAGE232_I47@PURE_QUANTA.Q_CAP(CHIPS)':
 C_PATH='@s9s_mb_2u_lib.s9s_mb_2u(sch_1):page232_i47@pure_quanta.q_cap(chips)',
 P_PATH='@s9s_mb_2u_lib.s9s_mb_2u(sch_1):page244_i47@pure_quanta.q_cap(chips)',
 PATH='I47',
 DRAWING='@S9S_MB_2U_LIB.S9S_MB_2U(SCH_1):PAGE232',
 PHYS_PAGE='244',
 XY='(1425,900)',
 ROT='0',
 VER='1',
 PACK_TYPE='C0402',
 CDS_LIB='pure_quanta',
 CDS_PART_NAME='Q_CAP_C0402-0.047UF,25V,10%,X7A',
 TOLERANCE='10%',
 MATERIAL='X7R',
 VOLTAGE='25V',
 VALUE='0.047UF',
 PRIM_FILE='./archive_libs/logical/q_cap/chips/chips.prt';

PART_NAME
 C1317 'Q_CAP_0402-0.1UF,25V,10%,X7R,CA':;

SECTION_NUMBER 1
 '@S9S_MB_2U_LIB.S9S_MB_2U(SCH_1):PAGE232_I9@PURE_QUANTA.Q_CAP(CHIPS)':
 C_PATH='@s9s_mb_2u_lib.s9s_mb_2u(sch_1):page232_i9@pure_quanta.q_cap(chips)',
 P_PATH='@s9s_mb_2u_lib.s9s_mb_2u(sch_1):page244_i9@pure_quanta.q_cap(chips)',
 PATH='I9',
 DRAWING='@S9S_MB_2U_LIB.S9S_MB_2U(SCH_1):PAGE232',
 PHYS_PAGE='244',
 XY='(-1375,-2000)',
 ROT='2',
 VER='1',
 PACK_TYPE='0402',
 CDS_LIB='pure_quanta',
 CDS_PART_NAME='Q_CAP_0402-0.1UF,25V,10%,X7R,CA',
 TOLERANCE='10%',
 MATERIAL='X7R',
 VOLTAGE='25V',
 VALUE='0.1UF',
 PRIM_FILE='./archive_libs/logical/q_cap/chips/chips.prt';

PART_NAME
 C1318 'Q_CAP_C0402-1UF,25V,10%,EMPTY,A':;

SECTION_NUMBER 1
 '@S9S_MB_2U_LIB.S9S_MB_2U(SCH_1):PAGE232_I7@PURE_QUANTA.Q_CAP(CHIPS)':
 C_PATH='@s9s_mb_2u_lib.s9s_mb_2u(sch_1):page232_i7@pure_quanta.q_cap(chips)',
 P_PATH='@s9s_mb_2u_lib.s9s_mb_2u(sch_1):page244_i7@pure_quanta.q_cap(chips)',
 PATH='I7',
 DRAWING='@S9S_MB_2U_LIB.S9S_MB_2U(SCH_1):PAGE232',
 PHYS_PAGE='244',
 XY='(-1375,-2475)',
 ROT='2',
 VER='1',
 PACK_TYPE='C0402',
 CDS_LIB='pure_quanta',
 CDS_PART_NAME='Q_CAP_C0402-1UF,25V,10%,EMPTY,A',
 TOLERANCE='10%',
 MATERIAL='EMPTY',
 VOLTAGE='25V',
 VALUE='1UF',
 PRIM_FILE='./archive_libs/logical/q_cap/chips/chips.prt';

PART_NAME
 C1319 'Q_CAP_C0402-1UF,25V,10%,X6S,CHA':;

SECTION_NUMBER 1
 '@S9S_MB_2U_LIB.S9S_MB_2U(SCH_1):PAGE232_I35@PURE_QUANTA.Q_CAP(CHIPS)':
 C_PATH='@s9s_mb_2u_lib.s9s_mb_2u(sch_1):page232_i35@pure_quanta.q_cap(chips)',
 P_PATH='@s9s_mb_2u_lib.s9s_mb_2u(sch_1):page244_i35@pure_quanta.q_cap(chips)',
 PATH='I35',
 DRAWING='@S9S_MB_2U_LIB.S9S_MB_2U(SCH_1):PAGE232',
 PHYS_PAGE='244',
 XY='(1325,-2525)',
 ROT='2',
 VER='1',
 PACK_TYPE='C0402',
 CDS_LIB='pure_quanta',
 CDS_PART_NAME='Q_CAP_C0402-1UF,25V,10%,X6S,CHA',
 TOLERANCE='10%',
 MATERIAL='X6S',
 VOLTAGE='25V',
 VALUE='1UF',
 PRIM_FILE='./archive_libs/logical/q_cap/chips/chips.prt';

PART_NAME
 C1320 'Q_CAP_0402-0.1UF,25V,10%,X7R,CA':;

SECTION_NUMBER 1
 '@S9S_MB_2U_LIB.S9S_MB_2U(SCH_1):PAGE313_I126@PURE_QUANTA.Q_CAP(CHIPS)':
 C_PATH='@s9s_mb_2u_lib.s9s_mb_2u(sch_1):page313_i126@pure_quanta.q_cap(chips)',
 P_PATH='@s9s_mb_2u_lib.s9s_mb_2u(sch_1):page214_i126@pure_quanta.q_cap(chips)',
 PATH='I126',
 DRAWING='@S9S_MB_2U_LIB.S9S_MB_2U(SCH_1):PAGE313',
 PHYS_PAGE='214',
 XY='(-3000,-2775)',
 ROT='2',
 VER='1',
 PACK_TYPE='0402',
 CDS_LIB='pure_quanta',
 CDS_PART_NAME='Q_CAP_0402-0.1UF,25V,10%,X7R,CA',
 TOLERANCE='10%',
 MATERIAL='X7R',
 VOLTAGE='25V',
 VALUE='0.1UF',
 PRIM_FILE='./archive_libs/logical/q_cap/chips/chips.prt';

PART_NAME
 C1321 'Q_CAP_0402-0.1UF,25V,10%,X7R,CA':;

SECTION_NUMBER 1
 '@S9S_MB_2U_LIB.S9S_MB_2U(SCH_1):PAGE226_I55@PURE_QUANTA.Q_CAP(CHIPS)':
 C_PATH='@s9s_mb_2u_lib.s9s_mb_2u(sch_1):page226_i55@pure_quanta.q_cap(chips)',
 P_PATH='@s9s_mb_2u_lib.s9s_mb_2u(sch_1):page239_i55@pure_quanta.q_cap(chips)',
 PATH='I55',
 DRAWING='@S9S_MB_2U_LIB.S9S_MB_2U(SCH_1):PAGE226',
 PHYS_PAGE='239',
 XY='(-11725,300)',
 ROT='0',
 VER='1',
 PACK_TYPE='0402',
 CDS_LIB='pure_quanta',
 CDS_PART_NAME='Q_CAP_0402-0.1UF,25V,10%,X7R,CA',
 TOLERANCE='10%',
 MATERIAL='X7R',
 VOLTAGE='25V',
 VALUE='0.1UF',
 PRIM_FILE='./archive_libs/logical/q_cap/chips/chips.prt';

PART_NAME
 C1322 'Q_CAP_0402-0.1UF,25V,10%,X7R,CA':;

SECTION_NUMBER 1
 '@S9S_MB_2U_LIB.S9S_MB_2U(SCH_1):PAGE226_I27@PURE_QUANTA.Q_CAP(CHIPS)':
 C_PATH='@s9s_mb_2u_lib.s9s_mb_2u(sch_1):page226_i27@pure_quanta.q_cap(chips)',
 P_PATH='@s9s_mb_2u_lib.s9s_mb_2u(sch_1):page239_i27@pure_quanta.q_cap(chips)',
 PATH='I27',
 DRAWING='@S9S_MB_2U_LIB.S9S_MB_2U(SCH_1):PAGE226',
 PHYS_PAGE='239',
 XY='(-7675,300)',
 ROT='0',
 VER='1',
 PACK_TYPE='0402',
 CDS_LIB='pure_quanta',
 CDS_PART_NAME='Q_CAP_0402-0.1UF,25V,10%,X7R,CA',
 TOLERANCE='10%',
 MATERIAL='X7R',
 VOLTAGE='25V',
 VALUE='0.1UF',
 PRIM_FILE='./archive_libs/logical/q_cap/chips/chips.prt';

PART_NAME
 C1323 'Q_CAP_0402-0.1UF,25V,10%,X7R,CA':;

SECTION_NUMBER 1
 '@S9S_MB_2U_LIB.S9S_MB_2U(SCH_1):PAGE183_I28@PURE_QUANTA.Q_CAP(CHIPS)':
 C_PATH='@s9s_mb_2u_lib.s9s_mb_2u(sch_1):page183_i28@pure_quanta.q_cap(chips)',
 P_PATH='@s9s_mb_2u_lib.s9s_mb_2u(sch_1):page194_i28@pure_quanta.q_cap(chips)',
 PATH='I28',
 DRAWING='@S9S_MB_2U_LIB.S9S_MB_2U(SCH_1):PAGE183',
 PHYS_PAGE='194',
 XY='(1400,3800)',
 ROT='0',
 VER='1',
 PACK_TYPE='0402',
 CDS_LIB='pure_quanta',
 CDS_PART_NAME='Q_CAP_0402-0.1UF,25V,10%,X7R,CA',
 TOLERANCE='10%',
 MATERIAL='X7R',
 VOLTAGE='25V',
 VALUE='0.1UF',
 PRIM_FILE='./archive_libs/logical/q_cap/chips/chips.prt';

PART_NAME
 C1324 'Q_CAP_0402-0.1UF,25V,10%,EMPTYA':;

SECTION_NUMBER 1
 '@S9S_MB_2U_LIB.S9S_MB_2U(SCH_1):PAGE197_I286@PURE_QUANTA.Q_CAP(CHIPS)':
 C_PATH='@s9s_mb_2u_lib.s9s_mb_2u(sch_1):page197_i286@pure_quanta.q_cap(chips)',
 P_PATH='@s9s_mb_2u_lib.s9s_mb_2u(sch_1):page208_i286@pure_quanta.q_cap(chips)',
 PATH='I286',
 DRAWING='@S9S_MB_2U_LIB.S9S_MB_2U(SCH_1):PAGE197',
 PHYS_PAGE='208',
 XY='(-1950,5775)',
 ROT='2',
 VER='1',
 PACK_TYPE='0402',
 CDS_LIB='pure_quanta',
 CDS_PART_NAME='Q_CAP_0402-0.1UF,25V,10%,EMPTYA',
 TOLERANCE='10%',
 MATERIAL='EMPTY',
 VOLTAGE='25V',
 VALUE='0.1UF',
 PRIM_FILE='./archive_libs/logical/q_cap/chips/chips.prt';

PART_NAME
 C1325 'Q_CAP_0402-0.1UF,25V,10%,X7R,CA':;

SECTION_NUMBER 1
 '@S9S_MB_2U_LIB.S9S_MB_2U(SCH_1):PAGE312_I39@PURE_QUANTA.Q_CAP(CHIPS)':
 C_PATH='@s9s_mb_2u_lib.s9s_mb_2u(sch_1):page312_i39@pure_quanta.q_cap(chips)',
 P_PATH='@s9s_mb_2u_lib.s9s_mb_2u(sch_1):page215_i39@pure_quanta.q_cap(chips)',
 PATH='I39',
 DRAWING='@S9S_MB_2U_LIB.S9S_MB_2U(SCH_1):PAGE312',
 PHYS_PAGE='215',
 XY='(775,2050)',
 ROT='2',
 VER='1',
 PACK_TYPE='0402',
 CDS_LIB='pure_quanta',
 CDS_PART_NAME='Q_CAP_0402-0.1UF,25V,10%,X7R,CA',
 TOLERANCE='10%',
 MATERIAL='X7R',
 VOLTAGE='25V',
 VALUE='0.1UF',
 PRIM_FILE='./archive_libs/logical/q_cap/chips/chips.prt';

PART_NAME
 C1331 'Q_CAP_C0805-10UF,16V,10%,X6S,CA':
 REUSE_ID='6';

SECTION_NUMBER 1
 '@S9S_MB_2U_LIB.S9S_MB_2U(SCH_1):PAGE246_I45@PURE_QUANTA.Q_CAP(CHIPS)':
 C_PATH='@s9s_mb_2u_lib.s9s_mb_2u(sch_1):page246_i45@pure_quanta.q_cap(chips)',
 P_PATH='@s9s_mb_2u_lib.s9s_mb_2u(sch_1):page260_i45@pure_quanta.q_cap(chips)',
 PATH='I45',
 DRAWING='@S9S_MB_2U_LIB.S9S_MB_2U(SCH_1):PAGE246',
 BOM_COST='VR_SYSTEM ',
 PHYS_PAGE='260',
 XY='(-3050,7400)',
 ROT='0',
 VER='1',
 PACK_TYPE='C0805',
 CDS_LIB='pure_quanta',
 CDS_PART_NAME='Q_CAP_C0805-10UF,16V,10%,X6S,CA',
 TOLERANCE='10%',
 MATERIAL='X6S',
 REUSE_ID='6',
 VOLTAGE='16V',
 VALUE='10UF',
 PRIM_FILE='./archive_libs/logical/q_cap/chips/chips.prt';

PART_NAME
 C1332 'Q_CAP_C0402-100NF,50V,10%,X7R,A':;

SECTION_NUMBER 1
 '@S9S_MB_2U_LIB.S9S_MB_2U(SCH_1):PAGE246_I48@PURE_QUANTA.Q_CAP(CHIPS)':
 C_PATH='@s9s_mb_2u_lib.s9s_mb_2u(sch_1):page246_i48@pure_quanta.q_cap(chips)',
 P_PATH='@s9s_mb_2u_lib.s9s_mb_2u(sch_1):page260_i48@pure_quanta.q_cap(chips)',
 PATH='I48',
 DRAWING='@S9S_MB_2U_LIB.S9S_MB_2U(SCH_1):PAGE246',
 BOM_COST='VR_SYSTEM ',
 PHYS_PAGE='260',
 XY='(-1150,5550)',
 ROT='2',
 VER='1',
 PACK_TYPE='C0402',
 CDS_LIB='pure_quanta',
 CDS_PART_NAME='Q_CAP_C0402-100NF,50V,10%,X7R,A',
 TOLERANCE='10%',
 MATERIAL='X7R',
 VOLTAGE='50V',
 VALUE='100NF',
 PRIM_FILE='./archive_libs/logical/q_cap/chips/chips.prt';

PART_NAME
 C1333 'Q_CAP_C0805-10UF,16V,10%,X6S,CA':;

SECTION_NUMBER 1
 '@S9S_MB_2U_LIB.S9S_MB_2U(SCH_1):PAGE246_I49@PURE_QUANTA.Q_CAP(CHIPS)':
 C_PATH='@s9s_mb_2u_lib.s9s_mb_2u(sch_1):page246_i49@pure_quanta.q_cap(chips)',
 P_PATH='@s9s_mb_2u_lib.s9s_mb_2u(sch_1):page260_i49@pure_quanta.q_cap(chips)',
 PATH='I49',
 DRAWING='@S9S_MB_2U_LIB.S9S_MB_2U(SCH_1):PAGE246',
 BOM_COST='VR_SYSTEM ',
 PHYS_PAGE='260',
 XY='(-825,5550)',
 ROT='2',
 VER='1',
 PACK_TYPE='C0805',
 CDS_LIB='pure_quanta',
 CDS_PART_NAME='Q_CAP_C0805-10UF,16V,10%,X6S,CA',
 TOLERANCE='10%',
 MATERIAL='X6S',
 VOLTAGE='16V',
 VALUE='10UF',
 PRIM_FILE='./archive_libs/logical/q_cap/chips/chips.prt';

PART_NAME
 C1336 'Q_CAP_C0402-10UF,6.3V,20%,X6S,B':;

SECTION_NUMBER 1
 '@S9S_MB_2U_LIB.S9S_MB_2U(SCH_1):PAGE282_I24@PURE_QUANTA.Q_CAP(CHIPS)':
 C_PATH='@s9s_mb_2u_lib.s9s_mb_2u(sch_1):page282_i24@pure_quanta.q_cap(chips)',
 P_PATH='@s9s_mb_2u_lib.s9s_mb_2u(sch_1):page296_i24@pure_quanta.q_cap(chips)',
 PATH='I24',
 DRAWING='@S9S_MB_2U_LIB.S9S_MB_2U(SCH_1):PAGE282',
 PHYS_PAGE='296',
 XY='(-7550,5175)',
 ROT='0',
 VER='1',
 PACK_TYPE='C0402',
 LOCATION='C1336',
 CDS_LIB='pure_quanta',
 CDS_PART_NAME='Q_CAP_C0402-10UF,6.3V,20%,X6S,B',
 TOLERANCE='20%',
 MATERIAL='X6S',
 VOLTAGE='6.3V',
 VALUE='10UF',
 PRIM_FILE='./archive_libs/logical/q_cap/chips/chips.prt';

PART_NAME
 C1337 'Q_CAP_0402-0.1UF,25V,10%,X7R,CA':;

SECTION_NUMBER 1
 '@S9S_MB_2U_LIB.S9S_MB_2U(SCH_1):PAGE282_I28@PURE_QUANTA.Q_CAP(CHIPS)':
 C_PATH='@s9s_mb_2u_lib.s9s_mb_2u(sch_1):page282_i28@pure_quanta.q_cap(chips)',
 P_PATH='@s9s_mb_2u_lib.s9s_mb_2u(sch_1):page296_i28@pure_quanta.q_cap(chips)',
 PATH='I28',
 DRAWING='@S9S_MB_2U_LIB.S9S_MB_2U(SCH_1):PAGE282',
 PHYS_PAGE='296',
 XY='(-7325,5175)',
 ROT='0',
 VER='1',
 PACK_TYPE='0402',
 LOCATION='C1337',
 CDS_LIB='pure_quanta',
 CDS_PART_NAME='Q_CAP_0402-0.1UF,25V,10%,X7R,CA',
 TOLERANCE='10%',
 MATERIAL='X7R',
 VOLTAGE='25V',
 VALUE='0.1UF',
 PRIM_FILE='./archive_libs/logical/q_cap/chips/chips.prt';

PART_NAME
 C1338 'Q_CAP_C0805-10UF,16V,10%,EMPTYA':;

SECTION_NUMBER 1
 '@S9S_MB_2U_LIB.S9S_MB_2U(SCH_1):PAGE246_I50@PURE_QUANTA.Q_CAP(CHIPS)':
 C_PATH='@s9s_mb_2u_lib.s9s_mb_2u(sch_1):page246_i50@pure_quanta.q_cap(chips)',
 P_PATH='@s9s_mb_2u_lib.s9s_mb_2u(sch_1):page260_i50@pure_quanta.q_cap(chips)',
 PATH='I50',
 DRAWING='@S9S_MB_2U_LIB.S9S_MB_2U(SCH_1):PAGE246',
 BOM_COST='VR_SYSTEM ',
 PHYS_PAGE='260',
 XY='(-425,5550)',
 ROT='2',
 VER='1',
 PACK_TYPE='C0805',
 CDS_LIB='pure_quanta',
 CDS_PART_NAME='Q_CAP_C0805-10UF,16V,10%,EMPTYA',
 TOLERANCE='10%',
 MATERIAL='EMPTY',
 VOLTAGE='16V',
 VALUE='10UF',
 PRIM_FILE='./archive_libs/logical/q_cap/chips/chips.prt';

PART_NAME
 C1339 'Q_CAP_C0402-100NF,50V,10%,X7R,A':;

SECTION_NUMBER 1
 '@S9S_MB_2U_LIB.S9S_MB_2U(SCH_1):PAGE246_I58@PURE_QUANTA.Q_CAP(CHIPS)':
 C_PATH='@s9s_mb_2u_lib.s9s_mb_2u(sch_1):page246_i58@pure_quanta.q_cap(chips)',
 P_PATH='@s9s_mb_2u_lib.s9s_mb_2u(sch_1):page260_i58@pure_quanta.q_cap(chips)',
 PATH='I58',
 DRAWING='@S9S_MB_2U_LIB.S9S_MB_2U(SCH_1):PAGE246',
 BOM_COST='VR_SYSTEM ',
 PHYS_PAGE='260',
 XY='(775,5125)',
 ROT='0',
 VER='1',
 PACK_TYPE='C0402',
 CDS_LIB='pure_quanta',
 CDS_PART_NAME='Q_CAP_C0402-100NF,50V,10%,X7R,A',
 TOLERANCE='10%',
 MATERIAL='X7R',
 VOLTAGE='50V',
 VALUE='100NF',
 PRIM_FILE='./archive_libs/logical/q_cap/chips/chips.prt';

PART_NAME
 C1340 'Q_CAP_C0805-10UF,16V,10%,X6S,CA':;

SECTION_NUMBER 1
 '@S9S_MB_2U_LIB.S9S_MB_2U(SCH_1):PAGE246_I61@PURE_QUANTA.Q_CAP(CHIPS)':
 C_PATH='@s9s_mb_2u_lib.s9s_mb_2u(sch_1):page246_i61@pure_quanta.q_cap(chips)',
 P_PATH='@s9s_mb_2u_lib.s9s_mb_2u(sch_1):page260_i61@pure_quanta.q_cap(chips)',
 PATH='I61',
 DRAWING='@S9S_MB_2U_LIB.S9S_MB_2U(SCH_1):PAGE246',
 BOM_COST='VR_SYSTEM ',
 PHYS_PAGE='260',
 XY='(1150,5125)',
 ROT='0',
 VER='1',
 PACK_TYPE='C0805',
 CDS_LIB='pure_quanta',
 CDS_PART_NAME='Q_CAP_C0805-10UF,16V,10%,X6S,CA',
 TOLERANCE='10%',
 MATERIAL='X6S',
 VOLTAGE='16V',
 VALUE='10UF',
 PRIM_FILE='./archive_libs/logical/q_cap/chips/chips.prt';

PART_NAME
 C1344 'Q_CAP_0402-100PF,50V,5%,EMPTY,A':
 ROOM='ADC1_BOM1';

SECTION_NUMBER 1
 '@S9S_MB_2U_LIB.S9S_MB_2U(SCH_1):PAGE239_I205@PURE_QUANTA.Q_CAP(CHIPS)':
 C_PATH='@s9s_mb_2u_lib.s9s_mb_2u(sch_1):page239_i205@pure_quanta.q_cap(chips)',
 P_PATH='@s9s_mb_2u_lib.s9s_mb_2u(sch_1):page250_i205@pure_quanta.q_cap(chips)',
 PATH='I205',
 DRAWING='@S9S_MB_2U_LIB.S9S_MB_2U(SCH_1):PAGE239',
 PHYS_PAGE='250',
 XY='(700,975)',
 ROT='0',
 VER='1',
 PACK_TYPE='0402',
 CDS_LIB='pure_quanta',
 CDS_PART_NAME='Q_CAP_0402-100PF,50V,5%,EMPTY,A',
 TOLERANCE='5%',
 MATERIAL='EMPTY',
 VOLTAGE='50V',
 ROOM='ADC1_BOM1',
 VALUE='100PF',
 PRIM_FILE='./archive_libs/logical/q_cap/chips/chips.prt';

PART_NAME
 C1347 'Q_CAP_0402-0.1UF,25V,10%,EMPTYA':
 ROOM='ADC1_BOM1';

SECTION_NUMBER 1
 '@S9S_MB_2U_LIB.S9S_MB_2U(SCH_1):PAGE239_I70@PURE_QUANTA.Q_CAP(CHIPS)':
 C_PATH='@s9s_mb_2u_lib.s9s_mb_2u(sch_1):page239_i70@pure_quanta.q_cap(chips)',
 P_PATH='@s9s_mb_2u_lib.s9s_mb_2u(sch_1):page250_i70@pure_quanta.q_cap(chips)',
 PATH='I70',
 DRAWING='@S9S_MB_2U_LIB.S9S_MB_2U(SCH_1):PAGE239',
 PHYS_PAGE='250',
 XY='(3700,4550)',
 ROT='2',
 VER='1',
 PACK_TYPE='0402',
 CDS_LIB='pure_quanta',
 CDS_PART_NAME='Q_CAP_0402-0.1UF,25V,10%,EMPTYA',
 TOLERANCE='10%',
 MATERIAL='EMPTY',
 VOLTAGE='25V',
 ROOM='ADC1_BOM1',
 VALUE='0.1UF',
 PRIM_FILE='./archive_libs/logical/q_cap/chips/chips.prt';

PART_NAME
 C1353 'Q_CAP_C0402-22UF,4V,20%,X6S,CHA':;

SECTION_NUMBER 1
 '@S9S_MB_2U_LIB.S9S_MB_2U(SCH_1):PAGE79_I49@PURE_QUANTA.Q_CAP(CHIPS)':
 C_PATH='@s9s_mb_2u_lib.s9s_mb_2u(sch_1):page79_i49@pure_quanta.q_cap(chips)',
 P_PATH='@s9s_mb_2u_lib.s9s_mb_2u(sch_1):page79_i49@pure_quanta.q_cap(chips)',
 PATH='I49',
 DRAWING='@S9S_MB_2U_LIB.S9S_MB_2U(SCH_1):PAGE79',
 PHYS_PAGE='79',
 XY='(-325,1450)',
 ROT='0',
 VER='1',
 PACK_TYPE='C0402',
 CDS_LIB='pure_quanta',
 CDS_PART_NAME='Q_CAP_C0402-22UF,4V,20%,X6S,CHA',
 TOLERANCE='20%',
 MATERIAL='X6S',
 VOLTAGE='4V',
 VALUE='22UF',
 PRIM_FILE='./archive_libs/logical/q_cap/chips/chips.prt';

PART_NAME
 C1362 'Q_CAP_C0402-22UF,4V,20%,X6S,CHA':;

SECTION_NUMBER 1
 '@S9S_MB_2U_LIB.S9S_MB_2U(SCH_1):PAGE76_I16@PURE_QUANTA.Q_CAP(CHIPS)':
 C_PATH='@s9s_mb_2u_lib.s9s_mb_2u(sch_1):page76_i16@pure_quanta.q_cap(chips)',
 P_PATH='@s9s_mb_2u_lib.s9s_mb_2u(sch_1):page76_i16@pure_quanta.q_cap(chips)',
 PATH='I16',
 DRAWING='@S9S_MB_2U_LIB.S9S_MB_2U(SCH_1):PAGE76',
 PHYS_PAGE='76',
 XY='(-3075,7100)',
 ROT='0',
 VER='1',
 PACK_TYPE='C0402',
 CDS_LIB='pure_quanta',
 CDS_PART_NAME='Q_CAP_C0402-22UF,4V,20%,X6S,CHA',
 TOLERANCE='20%',
 MATERIAL='X6S',
 VOLTAGE='4V',
 VALUE='22UF',
 PRIM_FILE='./archive_libs/logical/q_cap/chips/chips.prt';

PART_NAME
 C1363 'Q_CAP_C0402-22UF,4V,20%,X6S,CHA':;

SECTION_NUMBER 1
 '@S9S_MB_2U_LIB.S9S_MB_2U(SCH_1):PAGE80_I5@PURE_QUANTA.Q_CAP(CHIPS)':
 C_PATH='@s9s_mb_2u_lib.s9s_mb_2u(sch_1):page80_i5@pure_quanta.q_cap(chips)',
 P_PATH='@s9s_mb_2u_lib.s9s_mb_2u(sch_1):page80_i5@pure_quanta.q_cap(chips)',
 PATH='I5',
 DRAWING='@S9S_MB_2U_LIB.S9S_MB_2U(SCH_1):PAGE80',
 PHYS_PAGE='80',
 XY='(-2750,700)',
 ROT='0',
 VER='1',
 PACK_TYPE='C0402',
 CDS_LIB='pure_quanta',
 CDS_PART_NAME='Q_CAP_C0402-22UF,4V,20%,X6S,CHA',
 TOLERANCE='20%',
 MATERIAL='X6S',
 VOLTAGE='4V',
 VALUE='22UF',
 PRIM_FILE='./archive_libs/logical/q_cap/chips/chips.prt';

PART_NAME
 C1364 'Q_CAP_C0402-22UF,4V,20%,X6S,CHA':;

SECTION_NUMBER 1
 '@S9S_MB_2U_LIB.S9S_MB_2U(SCH_1):PAGE80_I9@PURE_QUANTA.Q_CAP(CHIPS)':
 C_PATH='@s9s_mb_2u_lib.s9s_mb_2u(sch_1):page80_i9@pure_quanta.q_cap(chips)',
 P_PATH='@s9s_mb_2u_lib.s9s_mb_2u(sch_1):page80_i9@pure_quanta.q_cap(chips)',
 PATH='I9',
 DRAWING='@S9S_MB_2U_LIB.S9S_MB_2U(SCH_1):PAGE80',
 PHYS_PAGE='80',
 XY='(-2375,700)',
 ROT='0',
 VER='1',
 PACK_TYPE='C0402',
 CDS_LIB='pure_quanta',
 CDS_PART_NAME='Q_CAP_C0402-22UF,4V,20%,X6S,CHA',
 TOLERANCE='20%',
 MATERIAL='X6S',
 VOLTAGE='4V',
 VALUE='22UF',
 PRIM_FILE='./archive_libs/logical/q_cap/chips/chips.prt';

PART_NAME
 C1365 'Q_CAP_C0402-22UF,4V,20%,X6S,CHA':;

SECTION_NUMBER 1
 '@S9S_MB_2U_LIB.S9S_MB_2U(SCH_1):PAGE80_I20@PURE_QUANTA.Q_CAP(CHIPS)':
 C_PATH='@s9s_mb_2u_lib.s9s_mb_2u(sch_1):page80_i20@pure_quanta.q_cap(chips)',
 P_PATH='@s9s_mb_2u_lib.s9s_mb_2u(sch_1):page80_i20@pure_quanta.q_cap(chips)',
 PATH='I20',
 DRAWING='@S9S_MB_2U_LIB.S9S_MB_2U(SCH_1):PAGE80',
 PHYS_PAGE='80',
 XY='(400,700)',
 ROT='0',
 VER='1',
 PACK_TYPE='C0402',
 CDS_LIB='pure_quanta',
 CDS_PART_NAME='Q_CAP_C0402-22UF,4V,20%,X6S,CHA',
 TOLERANCE='20%',
 MATERIAL='X6S',
 VOLTAGE='4V',
 VALUE='22UF',
 PRIM_FILE='./archive_libs/logical/q_cap/chips/chips.prt';

PART_NAME
 C1366 'Q_CAP_C0402-22UF,4V,20%,X6S,CHA':;

SECTION_NUMBER 1
 '@S9S_MB_2U_LIB.S9S_MB_2U(SCH_1):PAGE80_I28@PURE_QUANTA.Q_CAP(CHIPS)':
 C_PATH='@s9s_mb_2u_lib.s9s_mb_2u(sch_1):page80_i28@pure_quanta.q_cap(chips)',
 P_PATH='@s9s_mb_2u_lib.s9s_mb_2u(sch_1):page80_i28@pure_quanta.q_cap(chips)',
 PATH='I28',
 DRAWING='@S9S_MB_2U_LIB.S9S_MB_2U(SCH_1):PAGE80',
 PHYS_PAGE='80',
 XY='(775,700)',
 ROT='0',
 VER='1',
 PACK_TYPE='C0402',
 CDS_LIB='pure_quanta',
 CDS_PART_NAME='Q_CAP_C0402-22UF,4V,20%,X6S,CHA',
 TOLERANCE='20%',
 MATERIAL='X6S',
 VOLTAGE='4V',
 VALUE='22UF',
 PRIM_FILE='./archive_libs/logical/q_cap/chips/chips.prt';

PART_NAME
 C1387 'Q_CAP_C0805-47UF,4V,20%,X6S,CHA':;

SECTION_NUMBER 1
 '@S9S_MB_2U_LIB.S9S_MB_2U(SCH_1):PAGE78_I49@PURE_QUANTA.Q_CAP(CHIPS)':
 C_PATH='@s9s_mb_2u_lib.s9s_mb_2u(sch_1):page78_i49@pure_quanta.q_cap(chips)',
 P_PATH='@s9s_mb_2u_lib.s9s_mb_2u(sch_1):page78_i49@pure_quanta.q_cap(chips)',
 PATH='I49',
 DRAWING='@S9S_MB_2U_LIB.S9S_MB_2U(SCH_1):PAGE78',
 PHYS_PAGE='78',
 XY='(-100,-225)',
 ROT='0',
 VER='1',
 PACK_TYPE='C0805',
 CDS_LIB='pure_quanta',
 CDS_PART_NAME='Q_CAP_C0805-47UF,4V,20%,X6S,CHA',
 TOLERANCE='20%',
 MATERIAL='X6S',
 VOLTAGE='4V',
 VALUE='47UF',
 PRIM_FILE='./archive_libs/logical/q_cap/chips/chips.prt';

PART_NAME
 C1388 'Q_CAP_C0805-47UF,4V,20%,X6S,CHA':;

SECTION_NUMBER 1
 '@S9S_MB_2U_LIB.S9S_MB_2U(SCH_1):PAGE78_I46@PURE_QUANTA.Q_CAP(CHIPS)':
 C_PATH='@s9s_mb_2u_lib.s9s_mb_2u(sch_1):page78_i46@pure_quanta.q_cap(chips)',
 P_PATH='@s9s_mb_2u_lib.s9s_mb_2u(sch_1):page78_i46@pure_quanta.q_cap(chips)',
 PATH='I46',
 DRAWING='@S9S_MB_2U_LIB.S9S_MB_2U(SCH_1):PAGE78',
 PHYS_PAGE='78',
 XY='(-100,-1250)',
 ROT='0',
 VER='1',
 PACK_TYPE='C0805',
 CDS_LIB='pure_quanta',
 CDS_PART_NAME='Q_CAP_C0805-47UF,4V,20%,X6S,CHA',
 TOLERANCE='20%',
 MATERIAL='X6S',
 VOLTAGE='4V',
 VALUE='47UF',
 PRIM_FILE='./archive_libs/logical/q_cap/chips/chips.prt';

PART_NAME
 C1389 'Q_CAP_C0603-47UF,2.5V,20%,X6S,A':;

SECTION_NUMBER 1
 '@S9S_MB_2U_LIB.S9S_MB_2U(SCH_1):PAGE78_I51@PURE_QUANTA.Q_CAP(CHIPS)':
 C_PATH='@s9s_mb_2u_lib.s9s_mb_2u(sch_1):page78_i51@pure_quanta.q_cap(chips)',
 P_PATH='@s9s_mb_2u_lib.s9s_mb_2u(sch_1):page78_i51@pure_quanta.q_cap(chips)',
 PATH='I51',
 DRAWING='@S9S_MB_2U_LIB.S9S_MB_2U(SCH_1):PAGE78',
 PHYS_PAGE='78',
 XY='(350,-225)',
 ROT='0',
 VER='1',
 PACK_TYPE='C0603',
 CDS_LIB='pure_quanta',
 CDS_PART_NAME='Q_CAP_C0603-47UF,2.5V,20%,X6S,A',
 TOLERANCE='20%',
 MATERIAL='X6S',
 VOLTAGE='2.5V',
 VALUE='47UF',
 PRIM_FILE='./archive_libs/logical/q_cap/chips/chips.prt';

PART_NAME
 C1390 'Q_CAP_C0805-47UF,4V,20%,X6S,CHA':;

SECTION_NUMBER 1
 '@S9S_MB_2U_LIB.S9S_MB_2U(SCH_1):PAGE78_I48@PURE_QUANTA.Q_CAP(CHIPS)':
 C_PATH='@s9s_mb_2u_lib.s9s_mb_2u(sch_1):page78_i48@pure_quanta.q_cap(chips)',
 P_PATH='@s9s_mb_2u_lib.s9s_mb_2u(sch_1):page78_i48@pure_quanta.q_cap(chips)',
 PATH='I48',
 DRAWING='@S9S_MB_2U_LIB.S9S_MB_2U(SCH_1):PAGE78',
 PHYS_PAGE='78',
 XY='(350,-1250)',
 ROT='0',
 VER='1',
 PACK_TYPE='C0805',
 CDS_LIB='pure_quanta',
 CDS_PART_NAME='Q_CAP_C0805-47UF,4V,20%,X6S,CHA',
 TOLERANCE='20%',
 MATERIAL='X6S',
 VOLTAGE='4V',
 VALUE='47UF',
 PRIM_FILE='./archive_libs/logical/q_cap/chips/chips.prt';

PART_NAME
 C1391 'Q_CAP_C0603-47UF,2.5V,20%,X6S,A':;

SECTION_NUMBER 1
 '@S9S_MB_2U_LIB.S9S_MB_2U(SCH_1):PAGE78_I52@PURE_QUANTA.Q_CAP(CHIPS)':
 C_PATH='@s9s_mb_2u_lib.s9s_mb_2u(sch_1):page78_i52@pure_quanta.q_cap(chips)',
 P_PATH='@s9s_mb_2u_lib.s9s_mb_2u(sch_1):page78_i52@pure_quanta.q_cap(chips)',
 PATH='I52',
 DRAWING='@S9S_MB_2U_LIB.S9S_MB_2U(SCH_1):PAGE78',
 PHYS_PAGE='78',
 XY='(800,-225)',
 ROT='0',
 VER='1',
 PACK_TYPE='C0603',
 CDS_LIB='pure_quanta',
 CDS_PART_NAME='Q_CAP_C0603-47UF,2.5V,20%,X6S,A',
 TOLERANCE='20%',
 MATERIAL='X6S',
 VOLTAGE='2.5V',
 VALUE='47UF',
 PRIM_FILE='./archive_libs/logical/q_cap/chips/chips.prt';

PART_NAME
 C1392 'Q_CAP_C0805-47UF,4V,20%,X6S,CHA':;

SECTION_NUMBER 1
 '@S9S_MB_2U_LIB.S9S_MB_2U(SCH_1):PAGE78_I53@PURE_QUANTA.Q_CAP(CHIPS)':
 C_PATH='@s9s_mb_2u_lib.s9s_mb_2u(sch_1):page78_i53@pure_quanta.q_cap(chips)',
 P_PATH='@s9s_mb_2u_lib.s9s_mb_2u(sch_1):page78_i53@pure_quanta.q_cap(chips)',
 PATH='I53',
 DRAWING='@S9S_MB_2U_LIB.S9S_MB_2U(SCH_1):PAGE78',
 PHYS_PAGE='78',
 XY='(800,-1250)',
 ROT='0',
 VER='1',
 PACK_TYPE='C0805',
 CDS_LIB='pure_quanta',
 CDS_PART_NAME='Q_CAP_C0805-47UF,4V,20%,X6S,CHA',
 TOLERANCE='20%',
 MATERIAL='X6S',
 VOLTAGE='4V',
 VALUE='47UF',
 PRIM_FILE='./archive_libs/logical/q_cap/chips/chips.prt';

PART_NAME
 C1393 'Q_CAP_C0603-47UF,2.5V,20%,X6S,A':;

SECTION_NUMBER 1
 '@S9S_MB_2U_LIB.S9S_MB_2U(SCH_1):PAGE78_I57@PURE_QUANTA.Q_CAP(CHIPS)':
 C_PATH='@s9s_mb_2u_lib.s9s_mb_2u(sch_1):page78_i57@pure_quanta.q_cap(chips)',
 P_PATH='@s9s_mb_2u_lib.s9s_mb_2u(sch_1):page78_i57@pure_quanta.q_cap(chips)',
 PATH='I57',
 DRAWING='@S9S_MB_2U_LIB.S9S_MB_2U(SCH_1):PAGE78',
 PHYS_PAGE='78',
 XY='(1250,-225)',
 ROT='0',
 VER='1',
 PACK_TYPE='C0603',
 CDS_LIB='pure_quanta',
 CDS_PART_NAME='Q_CAP_C0603-47UF,2.5V,20%,X6S,A',
 TOLERANCE='20%',
 MATERIAL='X6S',
 VOLTAGE='2.5V',
 VALUE='47UF',
 PRIM_FILE='./archive_libs/logical/q_cap/chips/chips.prt';

PART_NAME
 C1396 'Q_CAP_C0805-47UF,4V,20%,X6S,CHA':;

SECTION_NUMBER 1
 '@S9S_MB_2U_LIB.S9S_MB_2U(SCH_1):PAGE75_I43@PURE_QUANTA.Q_CAP(CHIPS)':
 C_PATH='@s9s_mb_2u_lib.s9s_mb_2u(sch_1):page75_i43@pure_quanta.q_cap(chips)',
 P_PATH='@s9s_mb_2u_lib.s9s_mb_2u(sch_1):page75_i43@pure_quanta.q_cap(chips)',
 PATH='I43',
 DRAWING='@S9S_MB_2U_LIB.S9S_MB_2U(SCH_1):PAGE75',
 PHYS_PAGE='75',
 XY='(325,-1225)',
 ROT='0',
 VER='1',
 PACK_TYPE='C0805',
 CDS_LIB='pure_quanta',
 CDS_PART_NAME='Q_CAP_C0805-47UF,4V,20%,X6S,CHA',
 TOLERANCE='20%',
 MATERIAL='X6S',
 VOLTAGE='4V',
 VALUE='47UF',
 PRIM_FILE='./archive_libs/logical/q_cap/chips/chips.prt';

PART_NAME
 C1397 'Q_CAP_C0805-47UF,4V,20%,X6S,CHA':;

SECTION_NUMBER 1
 '@S9S_MB_2U_LIB.S9S_MB_2U(SCH_1):PAGE75_I44@PURE_QUANTA.Q_CAP(CHIPS)':
 C_PATH='@s9s_mb_2u_lib.s9s_mb_2u(sch_1):page75_i44@pure_quanta.q_cap(chips)',
 P_PATH='@s9s_mb_2u_lib.s9s_mb_2u(sch_1):page75_i44@pure_quanta.q_cap(chips)',
 PATH='I44',
 DRAWING='@S9S_MB_2U_LIB.S9S_MB_2U(SCH_1):PAGE75',
 PHYS_PAGE='75',
 XY='(775,-1225)',
 ROT='0',
 VER='1',
 PACK_TYPE='C0805',
 CDS_LIB='pure_quanta',
 CDS_PART_NAME='Q_CAP_C0805-47UF,4V,20%,X6S,CHA',
 TOLERANCE='20%',
 MATERIAL='X6S',
 VOLTAGE='4V',
 VALUE='47UF',
 PRIM_FILE='./archive_libs/logical/q_cap/chips/chips.prt';

PART_NAME
 C1398 'Q_CAP_C0805-47UF,4V,20%,X6S,CHA':;

SECTION_NUMBER 1
 '@S9S_MB_2U_LIB.S9S_MB_2U(SCH_1):PAGE75_I58@PURE_QUANTA.Q_CAP(CHIPS)':
 C_PATH='@s9s_mb_2u_lib.s9s_mb_2u(sch_1):page75_i58@pure_quanta.q_cap(chips)',
 P_PATH='@s9s_mb_2u_lib.s9s_mb_2u(sch_1):page75_i58@pure_quanta.q_cap(chips)',
 PATH='I58',
 DRAWING='@S9S_MB_2U_LIB.S9S_MB_2U(SCH_1):PAGE75',
 PHYS_PAGE='75',
 XY='(1225,-1225)',
 ROT='0',
 VER='1',
 PACK_TYPE='C0805',
 CDS_LIB='pure_quanta',
 CDS_PART_NAME='Q_CAP_C0805-47UF,4V,20%,X6S,CHA',
 TOLERANCE='20%',
 MATERIAL='X6S',
 VOLTAGE='4V',
 VALUE='47UF',
 PRIM_FILE='./archive_libs/logical/q_cap/chips/chips.prt';

PART_NAME
 C1399 'Q_CAP_C0805-47UF,4V,20%,X6S,CHA':;

SECTION_NUMBER 1
 '@S9S_MB_2U_LIB.S9S_MB_2U(SCH_1):PAGE76_I13@PURE_QUANTA.Q_CAP(CHIPS)':
 C_PATH='@s9s_mb_2u_lib.s9s_mb_2u(sch_1):page76_i13@pure_quanta.q_cap(chips)',
 P_PATH='@s9s_mb_2u_lib.s9s_mb_2u(sch_1):page76_i13@pure_quanta.q_cap(chips)',
 PATH='I13',
 DRAWING='@S9S_MB_2U_LIB.S9S_MB_2U(SCH_1):PAGE76',
 PHYS_PAGE='76',
 XY='(-3925,7100)',
 ROT='0',
 VER='1',
 PACK_TYPE='C0805',
 CDS_LIB='pure_quanta',
 CDS_PART_NAME='Q_CAP_C0805-47UF,4V,20%,X6S,CHA',
 TOLERANCE='20%',
 MATERIAL='X6S',
 VOLTAGE='4V',
 VALUE='47UF',
 PRIM_FILE='./archive_libs/logical/q_cap/chips/chips.prt';

PART_NAME
 C1400 'Q_CAP_C0805-47UF,4V,20%,X6S,CHA':;

SECTION_NUMBER 1
 '@S9S_MB_2U_LIB.S9S_MB_2U(SCH_1):PAGE76_I14@PURE_QUANTA.Q_CAP(CHIPS)':
 C_PATH='@s9s_mb_2u_lib.s9s_mb_2u(sch_1):page76_i14@pure_quanta.q_cap(chips)',
 P_PATH='@s9s_mb_2u_lib.s9s_mb_2u(sch_1):page76_i14@pure_quanta.q_cap(chips)',
 PATH='I14',
 DRAWING='@S9S_MB_2U_LIB.S9S_MB_2U(SCH_1):PAGE76',
 PHYS_PAGE='76',
 XY='(-3475,7100)',
 ROT='0',
 VER='1',
 PACK_TYPE='C0805',
 CDS_LIB='pure_quanta',
 CDS_PART_NAME='Q_CAP_C0805-47UF,4V,20%,X6S,CHA',
 TOLERANCE='20%',
 MATERIAL='X6S',
 VOLTAGE='4V',
 VALUE='47UF',
 PRIM_FILE='./archive_libs/logical/q_cap/chips/chips.prt';

PART_NAME
 C1403 'Q_CAP_C0805-47UF,4V,20%,X6S,CHA':;

SECTION_NUMBER 1
 '@S9S_MB_2U_LIB.S9S_MB_2U(SCH_1):PAGE79_I43@PURE_QUANTA.Q_CAP(CHIPS)':
 C_PATH='@s9s_mb_2u_lib.s9s_mb_2u(sch_1):page79_i43@pure_quanta.q_cap(chips)',
 P_PATH='@s9s_mb_2u_lib.s9s_mb_2u(sch_1):page79_i43@pure_quanta.q_cap(chips)',
 PATH='I43',
 DRAWING='@S9S_MB_2U_LIB.S9S_MB_2U(SCH_1):PAGE79',
 PHYS_PAGE='79',
 XY='(-1175,1450)',
 ROT='0',
 VER='1',
 PACK_TYPE='C0805',
 CDS_LIB='pure_quanta',
 CDS_PART_NAME='Q_CAP_C0805-47UF,4V,20%,X6S,CHA',
 TOLERANCE='20%',
 MATERIAL='X6S',
 VOLTAGE='4V',
 VALUE='47UF',
 PRIM_FILE='./archive_libs/logical/q_cap/chips/chips.prt';

PART_NAME
 C1404 'Q_CAP_C0805-47UF,4V,20%,X6S,CHA':;

SECTION_NUMBER 1
 '@S9S_MB_2U_LIB.S9S_MB_2U(SCH_1):PAGE79_I44@PURE_QUANTA.Q_CAP(CHIPS)':
 C_PATH='@s9s_mb_2u_lib.s9s_mb_2u(sch_1):page79_i44@pure_quanta.q_cap(chips)',
 P_PATH='@s9s_mb_2u_lib.s9s_mb_2u(sch_1):page79_i44@pure_quanta.q_cap(chips)',
 PATH='I44',
 DRAWING='@S9S_MB_2U_LIB.S9S_MB_2U(SCH_1):PAGE79',
 PHYS_PAGE='79',
 XY='(-725,1450)',
 ROT='0',
 VER='1',
 PACK_TYPE='C0805',
 CDS_LIB='pure_quanta',
 CDS_PART_NAME='Q_CAP_C0805-47UF,4V,20%,X6S,CHA',
 TOLERANCE='20%',
 MATERIAL='X6S',
 VOLTAGE='4V',
 VALUE='47UF',
 PRIM_FILE='./archive_libs/logical/q_cap/chips/chips.prt';

PART_NAME
 C1405 'Q_CAP_C0603-47UF,2.5V,20%,X6S,A':;

SECTION_NUMBER 1
 '@S9S_MB_2U_LIB.S9S_MB_2U(SCH_1):PAGE75_I47@PURE_QUANTA.Q_CAP(CHIPS)':
 C_PATH='@s9s_mb_2u_lib.s9s_mb_2u(sch_1):page75_i47@pure_quanta.q_cap(chips)',
 P_PATH='@s9s_mb_2u_lib.s9s_mb_2u(sch_1):page75_i47@pure_quanta.q_cap(chips)',
 PATH='I47',
 DRAWING='@S9S_MB_2U_LIB.S9S_MB_2U(SCH_1):PAGE75',
 PHYS_PAGE='75',
 XY='(775,-175)',
 ROT='0',
 VER='1',
 PACK_TYPE='C0603',
 CDS_LIB='pure_quanta',
 CDS_PART_NAME='Q_CAP_C0603-47UF,2.5V,20%,X6S,A',
 TOLERANCE='20%',
 MATERIAL='X6S',
 VOLTAGE='2.5V',
 VALUE='47UF',
 PRIM_FILE='./archive_libs/logical/q_cap/chips/chips.prt';

PART_NAME
 C1406 'Q_CAP_C0603-47UF,2.5V,20%,X6S,A':;

SECTION_NUMBER 1
 '@S9S_MB_2U_LIB.S9S_MB_2U(SCH_1):PAGE75_I61@PURE_QUANTA.Q_CAP(CHIPS)':
 C_PATH='@s9s_mb_2u_lib.s9s_mb_2u(sch_1):page75_i61@pure_quanta.q_cap(chips)',
 P_PATH='@s9s_mb_2u_lib.s9s_mb_2u(sch_1):page75_i61@pure_quanta.q_cap(chips)',
 PATH='I61',
 DRAWING='@S9S_MB_2U_LIB.S9S_MB_2U(SCH_1):PAGE75',
 PHYS_PAGE='75',
 XY='(1225,-175)',
 ROT='0',
 VER='1',
 PACK_TYPE='C0603',
 CDS_LIB='pure_quanta',
 CDS_PART_NAME='Q_CAP_C0603-47UF,2.5V,20%,X6S,A',
 TOLERANCE='20%',
 MATERIAL='X6S',
 VOLTAGE='2.5V',
 VALUE='47UF',
 PRIM_FILE='./archive_libs/logical/q_cap/chips/chips.prt';

PART_NAME
 C1407 'Q_CAP_C0603-47UF,2.5V,20%,X6S,A':;

SECTION_NUMBER 1
 '@S9S_MB_2U_LIB.S9S_MB_2U(SCH_1):PAGE75_I62@PURE_QUANTA.Q_CAP(CHIPS)':
 C_PATH='@s9s_mb_2u_lib.s9s_mb_2u(sch_1):page75_i62@pure_quanta.q_cap(chips)',
 P_PATH='@s9s_mb_2u_lib.s9s_mb_2u(sch_1):page75_i62@pure_quanta.q_cap(chips)',
 PATH='I62',
 DRAWING='@S9S_MB_2U_LIB.S9S_MB_2U(SCH_1):PAGE75',
 PHYS_PAGE='75',
 XY='(1675,-175)',
 ROT='0',
 VER='1',
 PACK_TYPE='C0603',
 CDS_LIB='pure_quanta',
 CDS_PART_NAME='Q_CAP_C0603-47UF,2.5V,20%,X6S,A',
 TOLERANCE='20%',
 MATERIAL='X6S',
 VOLTAGE='2.5V',
 VALUE='47UF',
 PRIM_FILE='./archive_libs/logical/q_cap/chips/chips.prt';

PART_NAME
 C1409 'Q_CAP_C0603-10UF,6.3V,20%,X6S,A':;

SECTION_NUMBER 1
 '@S9S_MB_2U_LIB.S9S_MB_2U(SCH_1):PAGE195_I419@PURE_QUANTA.Q_CAP(CHIPS)':
 C_PATH='@s9s_mb_2u_lib.s9s_mb_2u(sch_1):page195_i419@pure_quanta.q_cap(chips)',
 P_PATH='@s9s_mb_2u_lib.s9s_mb_2u(sch_1):page206_i419@pure_quanta.q_cap(chips)',
 PATH='I419',
 DRAWING='@S9S_MB_2U_LIB.S9S_MB_2U(SCH_1):PAGE195',
 PHYS_PAGE='206',
 XY='(-7300,4975)',
 ROT='0',
 VER='1',
 PACK_TYPE='C0603',
 CDS_LIB='pure_quanta',
 CDS_PART_NAME='Q_CAP_C0603-10UF,6.3V,20%,X6S,A',
 TOLERANCE='20%',
 MATERIAL='X6S',
 VOLTAGE='6.3V',
 VALUE='10UF',
 PRIM_FILE='./archive_libs/logical/q_cap/chips/chips.prt';

PART_NAME
 C1436 'Q_CAP_C0201-0.22UF,6.3V,10%,X6A':;

SECTION_NUMBER 1
 '@S9S_MB_2U_LIB.S9S_MB_2U(SCH_1):PAGE75_I59@PURE_QUANTA.Q_CAP(CHIPS)':
 C_PATH='@s9s_mb_2u_lib.s9s_mb_2u(sch_1):page75_i59@pure_quanta.q_cap(chips)',
 P_PATH='@s9s_mb_2u_lib.s9s_mb_2u(sch_1):page75_i59@pure_quanta.q_cap(chips)',
 PATH='I59',
 DRAWING='@S9S_MB_2U_LIB.S9S_MB_2U(SCH_1):PAGE75',
 PHYS_PAGE='75',
 XY='(1675,-1225)',
 ROT='0',
 VER='1',
 PACK_TYPE='C0201',
 CDS_LIB='pure_quanta',
 CDS_PART_NAME='Q_CAP_C0201-0.22UF,6.3V,10%,X6A',
 TOLERANCE='10%',
 MATERIAL='X6S',
 VOLTAGE='6.3V',
 VALUE='0.22UF',
 PRIM_FILE='./archive_libs/logical/q_cap/chips/chips.prt';

PART_NAME
 C1437 'Q_CAP_C0201-0.22UF,6.3V,10%,X6A':;

SECTION_NUMBER 1
 '@S9S_MB_2U_LIB.S9S_MB_2U(SCH_1):PAGE78_I55@PURE_QUANTA.Q_CAP(CHIPS)':
 C_PATH='@s9s_mb_2u_lib.s9s_mb_2u(sch_1):page78_i55@pure_quanta.q_cap(chips)',
 P_PATH='@s9s_mb_2u_lib.s9s_mb_2u(sch_1):page78_i55@pure_quanta.q_cap(chips)',
 PATH='I55',
 DRAWING='@S9S_MB_2U_LIB.S9S_MB_2U(SCH_1):PAGE78',
 PHYS_PAGE='78',
 XY='(1250,-1250)',
 ROT='0',
 VER='1',
 PACK_TYPE='C0201',
 CDS_LIB='pure_quanta',
 CDS_PART_NAME='Q_CAP_C0201-0.22UF,6.3V,10%,X6A',
 TOLERANCE='10%',
 MATERIAL='X6S',
 VOLTAGE='6.3V',
 VALUE='0.22UF',
 PRIM_FILE='./archive_libs/logical/q_cap/chips/chips.prt';

PART_NAME
 C1507 'Q_CAP_0402-18PF,50V,5%,C0G,CH0A':;

SECTION_NUMBER 1
 '@S9S_MB_2U_LIB.S9S_MB_2U(SCH_1):PAGE171_I10@PURE_QUANTA.Q_CAP(CHIPS)':
 C_PATH='@s9s_mb_2u_lib.s9s_mb_2u(sch_1):page171_i10@pure_quanta.q_cap(chips)',
 P_PATH='@s9s_mb_2u_lib.s9s_mb_2u(sch_1):page179_i10@pure_quanta.q_cap(chips)',
 PATH='I10',
 DRAWING='@S9S_MB_2U_LIB.S9S_MB_2U(SCH_1):PAGE171',
 PHYS_PAGE='179',
 XY='(1125,-775)',
 ROT='0',
 VER='1',
 PACK_TYPE='0402',
 CDS_LIB='pure_quanta',
 CDS_PART_NAME='Q_CAP_0402-18PF,50V,5%,C0G,CH0A',
 TOLERANCE='5%',
 MATERIAL='C0G',
 VOLTAGE='50V',
 VALUE='18PF',
 PRIM_FILE='./archive_libs/logical/q_cap/chips/chips.prt';

PART_NAME
 C1508 'Q_CAP_0402-18PF,50V,5%,C0G,CH0A':;

SECTION_NUMBER 1
 '@S9S_MB_2U_LIB.S9S_MB_2U(SCH_1):PAGE171_I17@PURE_QUANTA.Q_CAP(CHIPS)':
 C_PATH='@s9s_mb_2u_lib.s9s_mb_2u(sch_1):page171_i17@pure_quanta.q_cap(chips)',
 P_PATH='@s9s_mb_2u_lib.s9s_mb_2u(sch_1):page179_i17@pure_quanta.q_cap(chips)',
 PATH='I17',
 DRAWING='@S9S_MB_2U_LIB.S9S_MB_2U(SCH_1):PAGE171',
 PHYS_PAGE='179',
 XY='(2275,-775)',
 ROT='0',
 VER='1',
 PACK_TYPE='0402',
 CDS_LIB='pure_quanta',
 CDS_PART_NAME='Q_CAP_0402-18PF,50V,5%,C0G,CH0A',
 TOLERANCE='5%',
 MATERIAL='C0G',
 VOLTAGE='50V',
 VALUE='18PF',
 PRIM_FILE='./archive_libs/logical/q_cap/chips/chips.prt';

PART_NAME
 C1516 'Q_CAP_DIFFBUS_C0201-DIFF BUS_0A':;

SECTION_NUMBER 1
 '@S9S_MB_2U_LIB.S9S_MB_2U(SCH_1):PAGE168_I302@PURE_QUANTA.Q_CAP_DIFFBUS(CHIPS)':
 C_PATH='@s9s_mb_2u_lib.s9s_mb_2u(sch_1):page168_i302@pure_quanta.q_cap_diffbus(~
chips)',
 P_PATH='@s9s_mb_2u_lib.s9s_mb_2u(sch_1):page177_i302@pure_quanta.q_cap_diffbus(~
chips)',
 PATH='I302',
 DRAWING='@S9S_MB_2U_LIB.S9S_MB_2U(SCH_1):PAGE168',
 PIN_NAMES_ROTATE='TRUE',
 PHYS_PAGE='177',
 XY='(-1475,3550)',
 ROT='2',
 VER='2',
 PACK_TYPE='C0201',
 CDS_LIB='pure_quanta',
 CDS_PART_NAME='Q_CAP_DIFFBUS_C0201-DIFF BUS_0A',
 TOLERANCE='20%',
 MATERIAL='X6S',
 VOLTAGE='6.3V',
 VALUE='DIFF BUS_0.22UF',
 PRIM_FILE='./archive_libs/logical/q_cap_diffbus/chips/chips.prt';

PART_NAME
 C1517 'Q_CAP_DIFFBUS_C0201-DIFF BUS_0A':;

SECTION_NUMBER 1
 '@S9S_MB_2U_LIB.S9S_MB_2U(SCH_1):PAGE168_I301@PURE_QUANTA.Q_CAP_DIFFBUS(CHIPS)':
 C_PATH='@s9s_mb_2u_lib.s9s_mb_2u(sch_1):page168_i301@pure_quanta.q_cap_diffbus(~
chips)',
 P_PATH='@s9s_mb_2u_lib.s9s_mb_2u(sch_1):page177_i301@pure_quanta.q_cap_diffbus(~
chips)',
 PATH='I301',
 DRAWING='@S9S_MB_2U_LIB.S9S_MB_2U(SCH_1):PAGE168',
 PIN_NAMES_ROTATE='TRUE',
 PHYS_PAGE='177',
 XY='(-1475,3500)',
 ROT='2',
 VER='2',
 PACK_TYPE='C0201',
 CDS_LIB='pure_quanta',
 CDS_PART_NAME='Q_CAP_DIFFBUS_C0201-DIFF BUS_0A',
 TOLERANCE='20%',
 MATERIAL='X6S',
 VOLTAGE='6.3V',
 VALUE='DIFF BUS_0.22UF',
 PRIM_FILE='./archive_libs/logical/q_cap_diffbus/chips/chips.prt';

PART_NAME
 C1518 'Q_CAP_DIFFBUS_C0201-DIFF BUS_0A':;

SECTION_NUMBER 1
 '@S9S_MB_2U_LIB.S9S_MB_2U(SCH_1):PAGE168_I300@PURE_QUANTA.Q_CAP_DIFFBUS(CHIPS)':
 C_PATH='@s9s_mb_2u_lib.s9s_mb_2u(sch_1):page168_i300@pure_quanta.q_cap_diffbus(~
chips)',
 P_PATH='@s9s_mb_2u_lib.s9s_mb_2u(sch_1):page177_i300@pure_quanta.q_cap_diffbus(~
chips)',
 PATH='I300',
 DRAWING='@S9S_MB_2U_LIB.S9S_MB_2U(SCH_1):PAGE168',
 PIN_NAMES_ROTATE='TRUE',
 PHYS_PAGE='177',
 XY='(-1475,3350)',
 ROT='2',
 VER='2',
 PACK_TYPE='C0201',
 CDS_LIB='pure_quanta',
 CDS_PART_NAME='Q_CAP_DIFFBUS_C0201-DIFF BUS_0A',
 TOLERANCE='20%',
 MATERIAL='X6S',
 VOLTAGE='6.3V',
 VALUE='DIFF BUS_0.22UF',
 PRIM_FILE='./archive_libs/logical/q_cap_diffbus/chips/chips.prt';

PART_NAME
 C1519 'Q_CAP_DIFFBUS_C0201-DIFF BUS_0A':;

SECTION_NUMBER 1
 '@S9S_MB_2U_LIB.S9S_MB_2U(SCH_1):PAGE168_I299@PURE_QUANTA.Q_CAP_DIFFBUS(CHIPS)':
 C_PATH='@s9s_mb_2u_lib.s9s_mb_2u(sch_1):page168_i299@pure_quanta.q_cap_diffbus(~
chips)',
 P_PATH='@s9s_mb_2u_lib.s9s_mb_2u(sch_1):page177_i299@pure_quanta.q_cap_diffbus(~
chips)',
 PATH='I299',
 DRAWING='@S9S_MB_2U_LIB.S9S_MB_2U(SCH_1):PAGE168',
 PIN_NAMES_ROTATE='TRUE',
 PHYS_PAGE='177',
 XY='(-1475,3300)',
 ROT='2',
 VER='2',
 PACK_TYPE='C0201',
 CDS_LIB='pure_quanta',
 CDS_PART_NAME='Q_CAP_DIFFBUS_C0201-DIFF BUS_0A',
 TOLERANCE='20%',
 MATERIAL='X6S',
 VOLTAGE='6.3V',
 VALUE='DIFF BUS_0.22UF',
 PRIM_FILE='./archive_libs/logical/q_cap_diffbus/chips/chips.prt';

PART_NAME
 C1520 'Q_CAP_DIFFBUS_C0201-DIFF BUS_0A':;

SECTION_NUMBER 1
 '@S9S_MB_2U_LIB.S9S_MB_2U(SCH_1):PAGE168_I297@PURE_QUANTA.Q_CAP_DIFFBUS(CHIPS)':
 C_PATH='@s9s_mb_2u_lib.s9s_mb_2u(sch_1):page168_i297@pure_quanta.q_cap_diffbus(~
chips)',
 P_PATH='@s9s_mb_2u_lib.s9s_mb_2u(sch_1):page177_i297@pure_quanta.q_cap_diffbus(~
chips)',
 PATH='I297',
 DRAWING='@S9S_MB_2U_LIB.S9S_MB_2U(SCH_1):PAGE168',
 PIN_NAMES_ROTATE='TRUE',
 PHYS_PAGE='177',
 XY='(-1475,3150)',
 ROT='2',
 VER='2',
 PACK_TYPE='C0201',
 CDS_LIB='pure_quanta',
 CDS_PART_NAME='Q_CAP_DIFFBUS_C0201-DIFF BUS_0A',
 TOLERANCE='20%',
 MATERIAL='X6S',
 VOLTAGE='6.3V',
 VALUE='DIFF BUS_0.22UF',
 PRIM_FILE='./archive_libs/logical/q_cap_diffbus/chips/chips.prt';

PART_NAME
 C1521 'Q_CAP_DIFFBUS_C0201-DIFF BUS_0A':;

SECTION_NUMBER 1
 '@S9S_MB_2U_LIB.S9S_MB_2U(SCH_1):PAGE168_I298@PURE_QUANTA.Q_CAP_DIFFBUS(CHIPS)':
 C_PATH='@s9s_mb_2u_lib.s9s_mb_2u(sch_1):page168_i298@pure_quanta.q_cap_diffbus(~
chips)',
 P_PATH='@s9s_mb_2u_lib.s9s_mb_2u(sch_1):page177_i298@pure_quanta.q_cap_diffbus(~
chips)',
 PATH='I298',
 DRAWING='@S9S_MB_2U_LIB.S9S_MB_2U(SCH_1):PAGE168',
 PIN_NAMES_ROTATE='TRUE',
 PHYS_PAGE='177',
 XY='(-1475,3100)',
 ROT='2',
 VER='2',
 PACK_TYPE='C0201',
 CDS_LIB='pure_quanta',
 CDS_PART_NAME='Q_CAP_DIFFBUS_C0201-DIFF BUS_0A',
 TOLERANCE='20%',
 MATERIAL='X6S',
 VOLTAGE='6.3V',
 VALUE='DIFF BUS_0.22UF',
 PRIM_FILE='./archive_libs/logical/q_cap_diffbus/chips/chips.prt';

PART_NAME
 C1522 'Q_CAP_DIFFBUS_C0201-DIFF BUS_0A':;

SECTION_NUMBER 1
 '@S9S_MB_2U_LIB.S9S_MB_2U(SCH_1):PAGE168_I286@PURE_QUANTA.Q_CAP_DIFFBUS(CHIPS)':
 C_PATH='@s9s_mb_2u_lib.s9s_mb_2u(sch_1):page168_i286@pure_quanta.q_cap_diffbus(~
chips)',
 P_PATH='@s9s_mb_2u_lib.s9s_mb_2u(sch_1):page177_i286@pure_quanta.q_cap_diffbus(~
chips)',
 PATH='I286',
 DRAWING='@S9S_MB_2U_LIB.S9S_MB_2U(SCH_1):PAGE168',
 PIN_NAMES_ROTATE='TRUE',
 PHYS_PAGE='177',
 XY='(-1475,2950)',
 ROT='2',
 VER='2',
 PACK_TYPE='C0201',
 CDS_LIB='pure_quanta',
 CDS_PART_NAME='Q_CAP_DIFFBUS_C0201-DIFF BUS_0A',
 TOLERANCE='20%',
 MATERIAL='X6S',
 VOLTAGE='6.3V',
 VALUE='DIFF BUS_0.22UF',
 PRIM_FILE='./archive_libs/logical/q_cap_diffbus/chips/chips.prt';

PART_NAME
 C1523 'Q_CAP_DIFFBUS_C0201-DIFF BUS_0A':;

SECTION_NUMBER 1
 '@S9S_MB_2U_LIB.S9S_MB_2U(SCH_1):PAGE168_I285@PURE_QUANTA.Q_CAP_DIFFBUS(CHIPS)':
 C_PATH='@s9s_mb_2u_lib.s9s_mb_2u(sch_1):page168_i285@pure_quanta.q_cap_diffbus(~
chips)',
 P_PATH='@s9s_mb_2u_lib.s9s_mb_2u(sch_1):page177_i285@pure_quanta.q_cap_diffbus(~
chips)',
 PATH='I285',
 DRAWING='@S9S_MB_2U_LIB.S9S_MB_2U(SCH_1):PAGE168',
 PIN_NAMES_ROTATE='TRUE',
 PHYS_PAGE='177',
 XY='(-1475,2900)',
 ROT='2',
 VER='2',
 PACK_TYPE='C0201',
 CDS_LIB='pure_quanta',
 CDS_PART_NAME='Q_CAP_DIFFBUS_C0201-DIFF BUS_0A',
 TOLERANCE='20%',
 MATERIAL='X6S',
 VOLTAGE='6.3V',
 VALUE='DIFF BUS_0.22UF',
 PRIM_FILE='./archive_libs/logical/q_cap_diffbus/chips/chips.prt';

PART_NAME
 C1524 'Q_CAP_DIFFBUS_C0201-DIFF BUS_0A':;

SECTION_NUMBER 1
 '@S9S_MB_2U_LIB.S9S_MB_2U(SCH_1):PAGE168_I284@PURE_QUANTA.Q_CAP_DIFFBUS(CHIPS)':
 C_PATH='@s9s_mb_2u_lib.s9s_mb_2u(sch_1):page168_i284@pure_quanta.q_cap_diffbus(~
chips)',
 P_PATH='@s9s_mb_2u_lib.s9s_mb_2u(sch_1):page177_i284@pure_quanta.q_cap_diffbus(~
chips)',
 PATH='I284',
 DRAWING='@S9S_MB_2U_LIB.S9S_MB_2U(SCH_1):PAGE168',
 PIN_NAMES_ROTATE='TRUE',
 PHYS_PAGE='177',
 XY='(-1475,2750)',
 ROT='2',
 VER='2',
 PACK_TYPE='C0201',
 CDS_LIB='pure_quanta',
 CDS_PART_NAME='Q_CAP_DIFFBUS_C0201-DIFF BUS_0A',
 TOLERANCE='20%',
 MATERIAL='X6S',
 VOLTAGE='6.3V',
 VALUE='DIFF BUS_0.22UF',
 PRIM_FILE='./archive_libs/logical/q_cap_diffbus/chips/chips.prt';

PART_NAME
 C1525 'Q_CAP_DIFFBUS_C0201-DIFF BUS_0A':;

SECTION_NUMBER 1
 '@S9S_MB_2U_LIB.S9S_MB_2U(SCH_1):PAGE168_I283@PURE_QUANTA.Q_CAP_DIFFBUS(CHIPS)':
 C_PATH='@s9s_mb_2u_lib.s9s_mb_2u(sch_1):page168_i283@pure_quanta.q_cap_diffbus(~
chips)',
 P_PATH='@s9s_mb_2u_lib.s9s_mb_2u(sch_1):page177_i283@pure_quanta.q_cap_diffbus(~
chips)',
 PATH='I283',
 DRAWING='@S9S_MB_2U_LIB.S9S_MB_2U(SCH_1):PAGE168',
 PIN_NAMES_ROTATE='TRUE',
 PHYS_PAGE='177',
 XY='(-1475,2700)',
 ROT='2',
 VER='2',
 PACK_TYPE='C0201',
 CDS_LIB='pure_quanta',
 CDS_PART_NAME='Q_CAP_DIFFBUS_C0201-DIFF BUS_0A',
 TOLERANCE='20%',
 MATERIAL='X6S',
 VOLTAGE='6.3V',
 VALUE='DIFF BUS_0.22UF',
 PRIM_FILE='./archive_libs/logical/q_cap_diffbus/chips/chips.prt';

PART_NAME
 C1526 'Q_CAP_DIFFBUS_C0201-DIFF BUS_0A':;

SECTION_NUMBER 1
 '@S9S_MB_2U_LIB.S9S_MB_2U(SCH_1):PAGE168_I282@PURE_QUANTA.Q_CAP_DIFFBUS(CHIPS)':
 C_PATH='@s9s_mb_2u_lib.s9s_mb_2u(sch_1):page168_i282@pure_quanta.q_cap_diffbus(~
chips)',
 P_PATH='@s9s_mb_2u_lib.s9s_mb_2u(sch_1):page177_i282@pure_quanta.q_cap_diffbus(~
chips)',
 PATH='I282',
 DRAWING='@S9S_MB_2U_LIB.S9S_MB_2U(SCH_1):PAGE168',
 PIN_NAMES_ROTATE='TRUE',
 PHYS_PAGE='177',
 XY='(-1475,2550)',
 ROT='2',
 VER='2',
 PACK_TYPE='C0201',
 CDS_LIB='pure_quanta',
 CDS_PART_NAME='Q_CAP_DIFFBUS_C0201-DIFF BUS_0A',
 TOLERANCE='20%',
 MATERIAL='X6S',
 VOLTAGE='6.3V',
 VALUE='DIFF BUS_0.22UF',
 PRIM_FILE='./archive_libs/logical/q_cap_diffbus/chips/chips.prt';

PART_NAME
 C1527 'Q_CAP_DIFFBUS_C0201-DIFF BUS_0A':;

SECTION_NUMBER 1
 '@S9S_MB_2U_LIB.S9S_MB_2U(SCH_1):PAGE168_I281@PURE_QUANTA.Q_CAP_DIFFBUS(CHIPS)':
 C_PATH='@s9s_mb_2u_lib.s9s_mb_2u(sch_1):page168_i281@pure_quanta.q_cap_diffbus(~
chips)',
 P_PATH='@s9s_mb_2u_lib.s9s_mb_2u(sch_1):page177_i281@pure_quanta.q_cap_diffbus(~
chips)',
 PATH='I281',
 DRAWING='@S9S_MB_2U_LIB.S9S_MB_2U(SCH_1):PAGE168',
 PIN_NAMES_ROTATE='TRUE',
 PHYS_PAGE='177',
 XY='(-1475,2500)',
 ROT='2',
 VER='2',
 PACK_TYPE='C0201',
 CDS_LIB='pure_quanta',
 CDS_PART_NAME='Q_CAP_DIFFBUS_C0201-DIFF BUS_0A',
 TOLERANCE='20%',
 MATERIAL='X6S',
 VOLTAGE='6.3V',
 VALUE='DIFF BUS_0.22UF',
 PRIM_FILE='./archive_libs/logical/q_cap_diffbus/chips/chips.prt';

PART_NAME
 C1528 'Q_CAP_DIFFBUS_C0201-DIFF BUS_0A':;

SECTION_NUMBER 1
 '@S9S_MB_2U_LIB.S9S_MB_2U(SCH_1):PAGE168_I280@PURE_QUANTA.Q_CAP_DIFFBUS(CHIPS)':
 C_PATH='@s9s_mb_2u_lib.s9s_mb_2u(sch_1):page168_i280@pure_quanta.q_cap_diffbus(~
chips)',
 P_PATH='@s9s_mb_2u_lib.s9s_mb_2u(sch_1):page177_i280@pure_quanta.q_cap_diffbus(~
chips)',
 PATH='I280',
 DRAWING='@S9S_MB_2U_LIB.S9S_MB_2U(SCH_1):PAGE168',
 PIN_NAMES_ROTATE='TRUE',
 PHYS_PAGE='177',
 XY='(-1475,2350)',
 ROT='2',
 VER='2',
 PACK_TYPE='C0201',
 CDS_LIB='pure_quanta',
 CDS_PART_NAME='Q_CAP_DIFFBUS_C0201-DIFF BUS_0A',
 TOLERANCE='20%',
 MATERIAL='X6S',
 VOLTAGE='6.3V',
 VALUE='DIFF BUS_0.22UF',
 PRIM_FILE='./archive_libs/logical/q_cap_diffbus/chips/chips.prt';

PART_NAME
 C1529 'Q_CAP_DIFFBUS_C0201-DIFF BUS_0A':;

SECTION_NUMBER 1
 '@S9S_MB_2U_LIB.S9S_MB_2U(SCH_1):PAGE168_I279@PURE_QUANTA.Q_CAP_DIFFBUS(CHIPS)':
 C_PATH='@s9s_mb_2u_lib.s9s_mb_2u(sch_1):page168_i279@pure_quanta.q_cap_diffbus(~
chips)',
 P_PATH='@s9s_mb_2u_lib.s9s_mb_2u(sch_1):page177_i279@pure_quanta.q_cap_diffbus(~
chips)',
 PATH='I279',
 DRAWING='@S9S_MB_2U_LIB.S9S_MB_2U(SCH_1):PAGE168',
 PIN_NAMES_ROTATE='TRUE',
 PHYS_PAGE='177',
 XY='(-1475,2300)',
 ROT='2',
 VER='2',
 PACK_TYPE='C0201',
 CDS_LIB='pure_quanta',
 CDS_PART_NAME='Q_CAP_DIFFBUS_C0201-DIFF BUS_0A',
 TOLERANCE='20%',
 MATERIAL='X6S',
 VOLTAGE='6.3V',
 VALUE='DIFF BUS_0.22UF',
 PRIM_FILE='./archive_libs/logical/q_cap_diffbus/chips/chips.prt';

PART_NAME
 C1530 'Q_CAP_DIFFBUS_C0201-DIFF BUS_0A':;

SECTION_NUMBER 1
 '@S9S_MB_2U_LIB.S9S_MB_2U(SCH_1):PAGE168_I277@PURE_QUANTA.Q_CAP_DIFFBUS(CHIPS)':
 C_PATH='@s9s_mb_2u_lib.s9s_mb_2u(sch_1):page168_i277@pure_quanta.q_cap_diffbus(~
chips)',
 P_PATH='@s9s_mb_2u_lib.s9s_mb_2u(sch_1):page177_i277@pure_quanta.q_cap_diffbus(~
chips)',
 PATH='I277',
 DRAWING='@S9S_MB_2U_LIB.S9S_MB_2U(SCH_1):PAGE168',
 PIN_NAMES_ROTATE='TRUE',
 PHYS_PAGE='177',
 XY='(-1475,2150)',
 ROT='2',
 VER='2',
 PACK_TYPE='C0201',
 CDS_LIB='pure_quanta',
 CDS_PART_NAME='Q_CAP_DIFFBUS_C0201-DIFF BUS_0A',
 TOLERANCE='20%',
 MATERIAL='X6S',
 VOLTAGE='6.3V',
 VALUE='DIFF BUS_0.22UF',
 PRIM_FILE='./archive_libs/logical/q_cap_diffbus/chips/chips.prt';

PART_NAME
 C1531 'Q_CAP_DIFFBUS_C0201-DIFF BUS_0A':;

SECTION_NUMBER 1
 '@S9S_MB_2U_LIB.S9S_MB_2U(SCH_1):PAGE168_I278@PURE_QUANTA.Q_CAP_DIFFBUS(CHIPS)':
 C_PATH='@s9s_mb_2u_lib.s9s_mb_2u(sch_1):page168_i278@pure_quanta.q_cap_diffbus(~
chips)',
 P_PATH='@s9s_mb_2u_lib.s9s_mb_2u(sch_1):page177_i278@pure_quanta.q_cap_diffbus(~
chips)',
 PATH='I278',
 DRAWING='@S9S_MB_2U_LIB.S9S_MB_2U(SCH_1):PAGE168',
 PIN_NAMES_ROTATE='TRUE',
 PHYS_PAGE='177',
 XY='(-1475,2100)',
 ROT='2',
 VER='2',
 PACK_TYPE='C0201',
 CDS_LIB='pure_quanta',
 CDS_PART_NAME='Q_CAP_DIFFBUS_C0201-DIFF BUS_0A',
 TOLERANCE='20%',
 MATERIAL='X6S',
 VOLTAGE='6.3V',
 VALUE='DIFF BUS_0.22UF',
 PRIM_FILE='./archive_libs/logical/q_cap_diffbus/chips/chips.prt';

PART_NAME
 C1532 'Q_CAP_DIFFBUS_C0201-DIFF BUS_0A':;

SECTION_NUMBER 1
 '@S9S_MB_2U_LIB.S9S_MB_2U(SCH_1):PAGE168_I254@PURE_QUANTA.Q_CAP_DIFFBUS(CHIPS)':
 C_PATH='@s9s_mb_2u_lib.s9s_mb_2u(sch_1):page168_i254@pure_quanta.q_cap_diffbus(~
chips)',
 P_PATH='@s9s_mb_2u_lib.s9s_mb_2u(sch_1):page177_i254@pure_quanta.q_cap_diffbus(~
chips)',
 PATH='I254',
 DRAWING='@S9S_MB_2U_LIB.S9S_MB_2U(SCH_1):PAGE168',
 PIN_NAMES_ROTATE='TRUE',
 PHYS_PAGE='177',
 XY='(-1475,1575)',
 ROT='2',
 VER='2',
 PACK_TYPE='C0201',
 CDS_LIB='pure_quanta',
 CDS_PART_NAME='Q_CAP_DIFFBUS_C0201-DIFF BUS_0A',
 TOLERANCE='20%',
 MATERIAL='X6S',
 VOLTAGE='6.3V',
 VALUE='DIFF BUS_0.22UF',
 PRIM_FILE='./archive_libs/logical/q_cap_diffbus/chips/chips.prt';

PART_NAME
 C1533 'Q_CAP_DIFFBUS_C0201-DIFF BUS_0A':;

SECTION_NUMBER 1
 '@S9S_MB_2U_LIB.S9S_MB_2U(SCH_1):PAGE168_I253@PURE_QUANTA.Q_CAP_DIFFBUS(CHIPS)':
 C_PATH='@s9s_mb_2u_lib.s9s_mb_2u(sch_1):page168_i253@pure_quanta.q_cap_diffbus(~
chips)',
 P_PATH='@s9s_mb_2u_lib.s9s_mb_2u(sch_1):page177_i253@pure_quanta.q_cap_diffbus(~
chips)',
 PATH='I253',
 DRAWING='@S9S_MB_2U_LIB.S9S_MB_2U(SCH_1):PAGE168',
 PIN_NAMES_ROTATE='TRUE',
 PHYS_PAGE='177',
 XY='(-1475,1525)',
 ROT='2',
 VER='2',
 PACK_TYPE='C0201',
 CDS_LIB='pure_quanta',
 CDS_PART_NAME='Q_CAP_DIFFBUS_C0201-DIFF BUS_0A',
 TOLERANCE='20%',
 MATERIAL='X6S',
 VOLTAGE='6.3V',
 VALUE='DIFF BUS_0.22UF',
 PRIM_FILE='./archive_libs/logical/q_cap_diffbus/chips/chips.prt';

PART_NAME
 C1534 'Q_CAP_DIFFBUS_C0201-DIFF BUS_0A':;

SECTION_NUMBER 1
 '@S9S_MB_2U_LIB.S9S_MB_2U(SCH_1):PAGE168_I251@PURE_QUANTA.Q_CAP_DIFFBUS(CHIPS)':
 C_PATH='@s9s_mb_2u_lib.s9s_mb_2u(sch_1):page168_i251@pure_quanta.q_cap_diffbus(~
chips)',
 P_PATH='@s9s_mb_2u_lib.s9s_mb_2u(sch_1):page177_i251@pure_quanta.q_cap_diffbus(~
chips)',
 PATH='I251',
 DRAWING='@S9S_MB_2U_LIB.S9S_MB_2U(SCH_1):PAGE168',
 PIN_NAMES_ROTATE='TRUE',
 PHYS_PAGE='177',
 XY='(-1475,1375)',
 ROT='2',
 VER='2',
 PACK_TYPE='C0201',
 CDS_LIB='pure_quanta',
 CDS_PART_NAME='Q_CAP_DIFFBUS_C0201-DIFF BUS_0A',
 TOLERANCE='20%',
 MATERIAL='X6S',
 VOLTAGE='6.3V',
 VALUE='DIFF BUS_0.22UF',
 PRIM_FILE='./archive_libs/logical/q_cap_diffbus/chips/chips.prt';

PART_NAME
 C1535 'Q_CAP_DIFFBUS_C0201-DIFF BUS_0A':;

SECTION_NUMBER 1
 '@S9S_MB_2U_LIB.S9S_MB_2U(SCH_1):PAGE168_I252@PURE_QUANTA.Q_CAP_DIFFBUS(CHIPS)':
 C_PATH='@s9s_mb_2u_lib.s9s_mb_2u(sch_1):page168_i252@pure_quanta.q_cap_diffbus(~
chips)',
 P_PATH='@s9s_mb_2u_lib.s9s_mb_2u(sch_1):page177_i252@pure_quanta.q_cap_diffbus(~
chips)',
 PATH='I252',
 DRAWING='@S9S_MB_2U_LIB.S9S_MB_2U(SCH_1):PAGE168',
 PIN_NAMES_ROTATE='TRUE',
 PHYS_PAGE='177',
 XY='(-1475,1325)',
 ROT='2',
 VER='2',
 PACK_TYPE='C0201',
 CDS_LIB='pure_quanta',
 CDS_PART_NAME='Q_CAP_DIFFBUS_C0201-DIFF BUS_0A',
 TOLERANCE='20%',
 MATERIAL='X6S',
 VOLTAGE='6.3V',
 VALUE='DIFF BUS_0.22UF',
 PRIM_FILE='./archive_libs/logical/q_cap_diffbus/chips/chips.prt';

PART_NAME
 C1536 'Q_CAP_DIFFBUS_C0201-DIFF BUS_0A':;

SECTION_NUMBER 1
 '@S9S_MB_2U_LIB.S9S_MB_2U(SCH_1):PAGE168_I250@PURE_QUANTA.Q_CAP_DIFFBUS(CHIPS)':
 C_PATH='@s9s_mb_2u_lib.s9s_mb_2u(sch_1):page168_i250@pure_quanta.q_cap_diffbus(~
chips)',
 P_PATH='@s9s_mb_2u_lib.s9s_mb_2u(sch_1):page177_i250@pure_quanta.q_cap_diffbus(~
chips)',
 PATH='I250',
 DRAWING='@S9S_MB_2U_LIB.S9S_MB_2U(SCH_1):PAGE168',
 PIN_NAMES_ROTATE='TRUE',
 PHYS_PAGE='177',
 XY='(-1475,1175)',
 ROT='2',
 VER='2',
 PACK_TYPE='C0201',
 CDS_LIB='pure_quanta',
 CDS_PART_NAME='Q_CAP_DIFFBUS_C0201-DIFF BUS_0A',
 TOLERANCE='20%',
 MATERIAL='X6S',
 VOLTAGE='6.3V',
 VALUE='DIFF BUS_0.22UF',
 PRIM_FILE='./archive_libs/logical/q_cap_diffbus/chips/chips.prt';

PART_NAME
 C1537 'Q_CAP_DIFFBUS_C0201-DIFF BUS_0A':;

SECTION_NUMBER 1
 '@S9S_MB_2U_LIB.S9S_MB_2U(SCH_1):PAGE168_I249@PURE_QUANTA.Q_CAP_DIFFBUS(CHIPS)':
 C_PATH='@s9s_mb_2u_lib.s9s_mb_2u(sch_1):page168_i249@pure_quanta.q_cap_diffbus(~
chips)',
 P_PATH='@s9s_mb_2u_lib.s9s_mb_2u(sch_1):page177_i249@pure_quanta.q_cap_diffbus(~
chips)',
 PATH='I249',
 DRAWING='@S9S_MB_2U_LIB.S9S_MB_2U(SCH_1):PAGE168',
 PIN_NAMES_ROTATE='TRUE',
 PHYS_PAGE='177',
 XY='(-1475,1125)',
 ROT='2',
 VER='2',
 PACK_TYPE='C0201',
 CDS_LIB='pure_quanta',
 CDS_PART_NAME='Q_CAP_DIFFBUS_C0201-DIFF BUS_0A',
 TOLERANCE='20%',
 MATERIAL='X6S',
 VOLTAGE='6.3V',
 VALUE='DIFF BUS_0.22UF',
 PRIM_FILE='./archive_libs/logical/q_cap_diffbus/chips/chips.prt';

PART_NAME
 C1538 'Q_CAP_DIFFBUS_C0201-DIFF BUS_0A':;

SECTION_NUMBER 1
 '@S9S_MB_2U_LIB.S9S_MB_2U(SCH_1):PAGE168_I238@PURE_QUANTA.Q_CAP_DIFFBUS(CHIPS)':
 C_PATH='@s9s_mb_2u_lib.s9s_mb_2u(sch_1):page168_i238@pure_quanta.q_cap_diffbus(~
chips)',
 P_PATH='@s9s_mb_2u_lib.s9s_mb_2u(sch_1):page177_i238@pure_quanta.q_cap_diffbus(~
chips)',
 PATH='I238',
 DRAWING='@S9S_MB_2U_LIB.S9S_MB_2U(SCH_1):PAGE168',
 PIN_NAMES_ROTATE='TRUE',
 PHYS_PAGE='177',
 XY='(-1475,975)',
 ROT='2',
 VER='2',
 PACK_TYPE='C0201',
 CDS_LIB='pure_quanta',
 CDS_PART_NAME='Q_CAP_DIFFBUS_C0201-DIFF BUS_0A',
 TOLERANCE='20%',
 MATERIAL='X6S',
 VOLTAGE='6.3V',
 VALUE='DIFF BUS_0.22UF',
 PRIM_FILE='./archive_libs/logical/q_cap_diffbus/chips/chips.prt';

PART_NAME
 C1539 'Q_CAP_DIFFBUS_C0201-DIFF BUS_0A':;

SECTION_NUMBER 1
 '@S9S_MB_2U_LIB.S9S_MB_2U(SCH_1):PAGE168_I237@PURE_QUANTA.Q_CAP_DIFFBUS(CHIPS)':
 C_PATH='@s9s_mb_2u_lib.s9s_mb_2u(sch_1):page168_i237@pure_quanta.q_cap_diffbus(~
chips)',
 P_PATH='@s9s_mb_2u_lib.s9s_mb_2u(sch_1):page177_i237@pure_quanta.q_cap_diffbus(~
chips)',
 PATH='I237',
 DRAWING='@S9S_MB_2U_LIB.S9S_MB_2U(SCH_1):PAGE168',
 PIN_NAMES_ROTATE='TRUE',
 PHYS_PAGE='177',
 XY='(-1475,925)',
 ROT='2',
 VER='2',
 PACK_TYPE='C0201',
 CDS_LIB='pure_quanta',
 CDS_PART_NAME='Q_CAP_DIFFBUS_C0201-DIFF BUS_0A',
 TOLERANCE='20%',
 MATERIAL='X6S',
 VOLTAGE='6.3V',
 VALUE='DIFF BUS_0.22UF',
 PRIM_FILE='./archive_libs/logical/q_cap_diffbus/chips/chips.prt';

PART_NAME
 C1540 'Q_CAP_DIFFBUS_C0201-DIFF BUS_0A':;

SECTION_NUMBER 1
 '@S9S_MB_2U_LIB.S9S_MB_2U(SCH_1):PAGE168_I236@PURE_QUANTA.Q_CAP_DIFFBUS(CHIPS)':
 C_PATH='@s9s_mb_2u_lib.s9s_mb_2u(sch_1):page168_i236@pure_quanta.q_cap_diffbus(~
chips)',
 P_PATH='@s9s_mb_2u_lib.s9s_mb_2u(sch_1):page177_i236@pure_quanta.q_cap_diffbus(~
chips)',
 PATH='I236',
 DRAWING='@S9S_MB_2U_LIB.S9S_MB_2U(SCH_1):PAGE168',
 PIN_NAMES_ROTATE='TRUE',
 PHYS_PAGE='177',
 XY='(-1475,775)',
 ROT='2',
 VER='2',
 PACK_TYPE='C0201',
 CDS_LIB='pure_quanta',
 CDS_PART_NAME='Q_CAP_DIFFBUS_C0201-DIFF BUS_0A',
 TOLERANCE='20%',
 MATERIAL='X6S',
 VOLTAGE='6.3V',
 VALUE='DIFF BUS_0.22UF',
 PRIM_FILE='./archive_libs/logical/q_cap_diffbus/chips/chips.prt';

PART_NAME
 C1541 'Q_CAP_DIFFBUS_C0201-DIFF BUS_0A':;

SECTION_NUMBER 1
 '@S9S_MB_2U_LIB.S9S_MB_2U(SCH_1):PAGE168_I235@PURE_QUANTA.Q_CAP_DIFFBUS(CHIPS)':
 C_PATH='@s9s_mb_2u_lib.s9s_mb_2u(sch_1):page168_i235@pure_quanta.q_cap_diffbus(~
chips)',
 P_PATH='@s9s_mb_2u_lib.s9s_mb_2u(sch_1):page177_i235@pure_quanta.q_cap_diffbus(~
chips)',
 PATH='I235',
 DRAWING='@S9S_MB_2U_LIB.S9S_MB_2U(SCH_1):PAGE168',
 PIN_NAMES_ROTATE='TRUE',
 PHYS_PAGE='177',
 XY='(-1475,725)',
 ROT='2',
 VER='2',
 PACK_TYPE='C0201',
 CDS_LIB='pure_quanta',
 CDS_PART_NAME='Q_CAP_DIFFBUS_C0201-DIFF BUS_0A',
 TOLERANCE='20%',
 MATERIAL='X6S',
 VOLTAGE='6.3V',
 VALUE='DIFF BUS_0.22UF',
 PRIM_FILE='./archive_libs/logical/q_cap_diffbus/chips/chips.prt';

PART_NAME
 C1542 'Q_CAP_DIFFBUS_C0201-DIFF BUS_0A':;

SECTION_NUMBER 1
 '@S9S_MB_2U_LIB.S9S_MB_2U(SCH_1):PAGE168_I233@PURE_QUANTA.Q_CAP_DIFFBUS(CHIPS)':
 C_PATH='@s9s_mb_2u_lib.s9s_mb_2u(sch_1):page168_i233@pure_quanta.q_cap_diffbus(~
chips)',
 P_PATH='@s9s_mb_2u_lib.s9s_mb_2u(sch_1):page177_i233@pure_quanta.q_cap_diffbus(~
chips)',
 PATH='I233',
 DRAWING='@S9S_MB_2U_LIB.S9S_MB_2U(SCH_1):PAGE168',
 PIN_NAMES_ROTATE='TRUE',
 PHYS_PAGE='177',
 XY='(-1475,575)',
 ROT='2',
 VER='2',
 PACK_TYPE='C0201',
 CDS_LIB='pure_quanta',
 CDS_PART_NAME='Q_CAP_DIFFBUS_C0201-DIFF BUS_0A',
 TOLERANCE='20%',
 MATERIAL='X6S',
 VOLTAGE='6.3V',
 VALUE='DIFF BUS_0.22UF',
 PRIM_FILE='./archive_libs/logical/q_cap_diffbus/chips/chips.prt';

PART_NAME
 C1543 'Q_CAP_DIFFBUS_C0201-DIFF BUS_0A':;

SECTION_NUMBER 1
 '@S9S_MB_2U_LIB.S9S_MB_2U(SCH_1):PAGE168_I234@PURE_QUANTA.Q_CAP_DIFFBUS(CHIPS)':
 C_PATH='@s9s_mb_2u_lib.s9s_mb_2u(sch_1):page168_i234@pure_quanta.q_cap_diffbus(~
chips)',
 P_PATH='@s9s_mb_2u_lib.s9s_mb_2u(sch_1):page177_i234@pure_quanta.q_cap_diffbus(~
chips)',
 PATH='I234',
 DRAWING='@S9S_MB_2U_LIB.S9S_MB_2U(SCH_1):PAGE168',
 PIN_NAMES_ROTATE='TRUE',
 PHYS_PAGE='177',
 XY='(-1475,525)',
 ROT='2',
 VER='2',
 PACK_TYPE='C0201',
 CDS_LIB='pure_quanta',
 CDS_PART_NAME='Q_CAP_DIFFBUS_C0201-DIFF BUS_0A',
 TOLERANCE='20%',
 MATERIAL='X6S',
 VOLTAGE='6.3V',
 VALUE='DIFF BUS_0.22UF',
 PRIM_FILE='./archive_libs/logical/q_cap_diffbus/chips/chips.prt';

PART_NAME
 C1544 'Q_CAP_DIFFBUS_C0201-DIFF BUS_0A':;

SECTION_NUMBER 1
 '@S9S_MB_2U_LIB.S9S_MB_2U(SCH_1):PAGE168_I232@PURE_QUANTA.Q_CAP_DIFFBUS(CHIPS)':
 C_PATH='@s9s_mb_2u_lib.s9s_mb_2u(sch_1):page168_i232@pure_quanta.q_cap_diffbus(~
chips)',
 P_PATH='@s9s_mb_2u_lib.s9s_mb_2u(sch_1):page177_i232@pure_quanta.q_cap_diffbus(~
chips)',
 PATH='I232',
 DRAWING='@S9S_MB_2U_LIB.S9S_MB_2U(SCH_1):PAGE168',
 PIN_NAMES_ROTATE='TRUE',
 PHYS_PAGE='177',
 XY='(-1475,375)',
 ROT='2',
 VER='2',
 PACK_TYPE='C0201',
 CDS_LIB='pure_quanta',
 CDS_PART_NAME='Q_CAP_DIFFBUS_C0201-DIFF BUS_0A',
 TOLERANCE='20%',
 MATERIAL='X6S',
 VOLTAGE='6.3V',
 VALUE='DIFF BUS_0.22UF',
 PRIM_FILE='./archive_libs/logical/q_cap_diffbus/chips/chips.prt';

PART_NAME
 C1545 'Q_CAP_DIFFBUS_C0201-DIFF BUS_0A':;

SECTION_NUMBER 1
 '@S9S_MB_2U_LIB.S9S_MB_2U(SCH_1):PAGE168_I231@PURE_QUANTA.Q_CAP_DIFFBUS(CHIPS)':
 C_PATH='@s9s_mb_2u_lib.s9s_mb_2u(sch_1):page168_i231@pure_quanta.q_cap_diffbus(~
chips)',
 P_PATH='@s9s_mb_2u_lib.s9s_mb_2u(sch_1):page177_i231@pure_quanta.q_cap_diffbus(~
chips)',
 PATH='I231',
 DRAWING='@S9S_MB_2U_LIB.S9S_MB_2U(SCH_1):PAGE168',
 PIN_NAMES_ROTATE='TRUE',
 PHYS_PAGE='177',
 XY='(-1475,325)',
 ROT='2',
 VER='2',
 PACK_TYPE='C0201',
 CDS_LIB='pure_quanta',
 CDS_PART_NAME='Q_CAP_DIFFBUS_C0201-DIFF BUS_0A',
 TOLERANCE='20%',
 MATERIAL='X6S',
 VOLTAGE='6.3V',
 VALUE='DIFF BUS_0.22UF',
 PRIM_FILE='./archive_libs/logical/q_cap_diffbus/chips/chips.prt';

PART_NAME
 C1546 'Q_CAP_DIFFBUS_C0201-DIFF BUS_0A':;

SECTION_NUMBER 1
 '@S9S_MB_2U_LIB.S9S_MB_2U(SCH_1):PAGE168_I230@PURE_QUANTA.Q_CAP_DIFFBUS(CHIPS)':
 C_PATH='@s9s_mb_2u_lib.s9s_mb_2u(sch_1):page168_i230@pure_quanta.q_cap_diffbus(~
chips)',
 P_PATH='@s9s_mb_2u_lib.s9s_mb_2u(sch_1):page177_i230@pure_quanta.q_cap_diffbus(~
chips)',
 PATH='I230',
 DRAWING='@S9S_MB_2U_LIB.S9S_MB_2U(SCH_1):PAGE168',
 PIN_NAMES_ROTATE='TRUE',
 PHYS_PAGE='177',
 XY='(-1475,175)',
 ROT='2',
 VER='2',
 PACK_TYPE='C0201',
 CDS_LIB='pure_quanta',
 CDS_PART_NAME='Q_CAP_DIFFBUS_C0201-DIFF BUS_0A',
 TOLERANCE='20%',
 MATERIAL='X6S',
 VOLTAGE='6.3V',
 VALUE='DIFF BUS_0.22UF',
 PRIM_FILE='./archive_libs/logical/q_cap_diffbus/chips/chips.prt';

PART_NAME
 C1547 'Q_CAP_DIFFBUS_C0201-DIFF BUS_0A':;

SECTION_NUMBER 1
 '@S9S_MB_2U_LIB.S9S_MB_2U(SCH_1):PAGE168_I229@PURE_QUANTA.Q_CAP_DIFFBUS(CHIPS)':
 C_PATH='@s9s_mb_2u_lib.s9s_mb_2u(sch_1):page168_i229@pure_quanta.q_cap_diffbus(~
chips)',
 P_PATH='@s9s_mb_2u_lib.s9s_mb_2u(sch_1):page177_i229@pure_quanta.q_cap_diffbus(~
chips)',
 PATH='I229',
 DRAWING='@S9S_MB_2U_LIB.S9S_MB_2U(SCH_1):PAGE168',
 PIN_NAMES_ROTATE='TRUE',
 PHYS_PAGE='177',
 XY='(-1475,125)',
 ROT='2',
 VER='2',
 PACK_TYPE='C0201',
 CDS_LIB='pure_quanta',
 CDS_PART_NAME='Q_CAP_DIFFBUS_C0201-DIFF BUS_0A',
 TOLERANCE='20%',
 MATERIAL='X6S',
 VOLTAGE='6.3V',
 VALUE='DIFF BUS_0.22UF',
 PRIM_FILE='./archive_libs/logical/q_cap_diffbus/chips/chips.prt';

PART_NAME
 C1548 'Q_CAP_DIFFBUS_C0201-DIFF BUS_0A':;

SECTION_NUMBER 1
 '@S9S_MB_2U_LIB.S9S_MB_2U(SCH_1):PAGE166_I273@PURE_QUANTA.Q_CAP_DIFFBUS(CHIPS)':
 C_PATH='@s9s_mb_2u_lib.s9s_mb_2u(sch_1):page166_i273@pure_quanta.q_cap_diffbus(~
chips)',
 P_PATH='@s9s_mb_2u_lib.s9s_mb_2u(sch_1):page175_i273@pure_quanta.q_cap_diffbus(~
chips)',
 PATH='I273',
 DRAWING='@S9S_MB_2U_LIB.S9S_MB_2U(SCH_1):PAGE166',
 PIN_NAMES_ROTATE='TRUE',
 PHYS_PAGE='175',
 XY='(-925,3575)',
 ROT='2',
 VER='2',
 PACK_TYPE='C0201',
 CDS_LIB='pure_quanta',
 CDS_PART_NAME='Q_CAP_DIFFBUS_C0201-DIFF BUS_0A',
 TOLERANCE='20%',
 MATERIAL='X6S',
 VOLTAGE='6.3V',
 VALUE='DIFF BUS_0.22UF',
 PRIM_FILE='./archive_libs/logical/q_cap_diffbus/chips/chips.prt';

PART_NAME
 C1549 'Q_CAP_DIFFBUS_C0201-DIFF BUS_0A':;

SECTION_NUMBER 1
 '@S9S_MB_2U_LIB.S9S_MB_2U(SCH_1):PAGE166_I274@PURE_QUANTA.Q_CAP_DIFFBUS(CHIPS)':
 C_PATH='@s9s_mb_2u_lib.s9s_mb_2u(sch_1):page166_i274@pure_quanta.q_cap_diffbus(~
chips)',
 P_PATH='@s9s_mb_2u_lib.s9s_mb_2u(sch_1):page175_i274@pure_quanta.q_cap_diffbus(~
chips)',
 PATH='I274',
 DRAWING='@S9S_MB_2U_LIB.S9S_MB_2U(SCH_1):PAGE166',
 PIN_NAMES_ROTATE='TRUE',
 PHYS_PAGE='175',
 XY='(-925,3525)',
 ROT='2',
 VER='2',
 PACK_TYPE='C0201',
 CDS_LIB='pure_quanta',
 CDS_PART_NAME='Q_CAP_DIFFBUS_C0201-DIFF BUS_0A',
 TOLERANCE='20%',
 MATERIAL='X6S',
 VOLTAGE='6.3V',
 VALUE='DIFF BUS_0.22UF',
 PRIM_FILE='./archive_libs/logical/q_cap_diffbus/chips/chips.prt';

PART_NAME
 C1550 'Q_CAP_DIFFBUS_C0201-DIFF BUS_0A':;

SECTION_NUMBER 1
 '@S9S_MB_2U_LIB.S9S_MB_2U(SCH_1):PAGE166_I272@PURE_QUANTA.Q_CAP_DIFFBUS(CHIPS)':
 C_PATH='@s9s_mb_2u_lib.s9s_mb_2u(sch_1):page166_i272@pure_quanta.q_cap_diffbus(~
chips)',
 P_PATH='@s9s_mb_2u_lib.s9s_mb_2u(sch_1):page175_i272@pure_quanta.q_cap_diffbus(~
chips)',
 PATH='I272',
 DRAWING='@S9S_MB_2U_LIB.S9S_MB_2U(SCH_1):PAGE166',
 PIN_NAMES_ROTATE='TRUE',
 PHYS_PAGE='175',
 XY='(-925,3375)',
 ROT='2',
 VER='2',
 PACK_TYPE='C0201',
 CDS_LIB='pure_quanta',
 CDS_PART_NAME='Q_CAP_DIFFBUS_C0201-DIFF BUS_0A',
 TOLERANCE='20%',
 MATERIAL='X6S',
 VOLTAGE='6.3V',
 VALUE='DIFF BUS_0.22UF',
 PRIM_FILE='./archive_libs/logical/q_cap_diffbus/chips/chips.prt';

PART_NAME
 C1552 'Q_CAP_DIFFBUS_C0201-DIFF BUS_0A':;

SECTION_NUMBER 1
 '@S9S_MB_2U_LIB.S9S_MB_2U(SCH_1):PAGE166_I270@PURE_QUANTA.Q_CAP_DIFFBUS(CHIPS)':
 C_PATH='@s9s_mb_2u_lib.s9s_mb_2u(sch_1):page166_i270@pure_quanta.q_cap_diffbus(~
chips)',
 P_PATH='@s9s_mb_2u_lib.s9s_mb_2u(sch_1):page175_i270@pure_quanta.q_cap_diffbus(~
chips)',
 PATH='I270',
 DRAWING='@S9S_MB_2U_LIB.S9S_MB_2U(SCH_1):PAGE166',
 PIN_NAMES_ROTATE='TRUE',
 PHYS_PAGE='175',
 XY='(-925,3175)',
 ROT='2',
 VER='2',
 PACK_TYPE='C0201',
 CDS_LIB='pure_quanta',
 CDS_PART_NAME='Q_CAP_DIFFBUS_C0201-DIFF BUS_0A',
 TOLERANCE='20%',
 MATERIAL='X6S',
 VOLTAGE='6.3V',
 VALUE='DIFF BUS_0.22UF',
 PRIM_FILE='./archive_libs/logical/q_cap_diffbus/chips/chips.prt';

PART_NAME
 C1553 'Q_CAP_DIFFBUS_C0201-DIFF BUS_0A':;

SECTION_NUMBER 1
 '@S9S_MB_2U_LIB.S9S_MB_2U(SCH_1):PAGE166_I269@PURE_QUANTA.Q_CAP_DIFFBUS(CHIPS)':
 C_PATH='@s9s_mb_2u_lib.s9s_mb_2u(sch_1):page166_i269@pure_quanta.q_cap_diffbus(~
chips)',
 P_PATH='@s9s_mb_2u_lib.s9s_mb_2u(sch_1):page175_i269@pure_quanta.q_cap_diffbus(~
chips)',
 PATH='I269',
 DRAWING='@S9S_MB_2U_LIB.S9S_MB_2U(SCH_1):PAGE166',
 PIN_NAMES_ROTATE='TRUE',
 PHYS_PAGE='175',
 XY='(-925,3125)',
 ROT='2',
 VER='2',
 PACK_TYPE='C0201',
 CDS_LIB='pure_quanta',
 CDS_PART_NAME='Q_CAP_DIFFBUS_C0201-DIFF BUS_0A',
 TOLERANCE='20%',
 MATERIAL='X6S',
 VOLTAGE='6.3V',
 VALUE='DIFF BUS_0.22UF',
 PRIM_FILE='./archive_libs/logical/q_cap_diffbus/chips/chips.prt';

PART_NAME
 C1554 'Q_CAP_DIFFBUS_C0201-DIFF BUS_0A':;

SECTION_NUMBER 1
 '@S9S_MB_2U_LIB.S9S_MB_2U(SCH_1):PAGE166_I268@PURE_QUANTA.Q_CAP_DIFFBUS(CHIPS)':
 C_PATH='@s9s_mb_2u_lib.s9s_mb_2u(sch_1):page166_i268@pure_quanta.q_cap_diffbus(~
chips)',
 P_PATH='@s9s_mb_2u_lib.s9s_mb_2u(sch_1):page175_i268@pure_quanta.q_cap_diffbus(~
chips)',
 PATH='I268',
 DRAWING='@S9S_MB_2U_LIB.S9S_MB_2U(SCH_1):PAGE166',
 PIN_NAMES_ROTATE='TRUE',
 PHYS_PAGE='175',
 XY='(-925,2975)',
 ROT='2',
 VER='2',
 PACK_TYPE='C0201',
 CDS_LIB='pure_quanta',
 CDS_PART_NAME='Q_CAP_DIFFBUS_C0201-DIFF BUS_0A',
 TOLERANCE='20%',
 MATERIAL='X6S',
 VOLTAGE='6.3V',
 VALUE='DIFF BUS_0.22UF',
 PRIM_FILE='./archive_libs/logical/q_cap_diffbus/chips/chips.prt';

PART_NAME
 C1555 'Q_CAP_DIFFBUS_C0201-DIFF BUS_0A':;

SECTION_NUMBER 1
 '@S9S_MB_2U_LIB.S9S_MB_2U(SCH_1):PAGE166_I267@PURE_QUANTA.Q_CAP_DIFFBUS(CHIPS)':
 C_PATH='@s9s_mb_2u_lib.s9s_mb_2u(sch_1):page166_i267@pure_quanta.q_cap_diffbus(~
chips)',
 P_PATH='@s9s_mb_2u_lib.s9s_mb_2u(sch_1):page175_i267@pure_quanta.q_cap_diffbus(~
chips)',
 PATH='I267',
 DRAWING='@S9S_MB_2U_LIB.S9S_MB_2U(SCH_1):PAGE166',
 PIN_NAMES_ROTATE='TRUE',
 PHYS_PAGE='175',
 XY='(-925,2925)',
 ROT='2',
 VER='2',
 PACK_TYPE='C0201',
 CDS_LIB='pure_quanta',
 CDS_PART_NAME='Q_CAP_DIFFBUS_C0201-DIFF BUS_0A',
 TOLERANCE='20%',
 MATERIAL='X6S',
 VOLTAGE='6.3V',
 VALUE='DIFF BUS_0.22UF',
 PRIM_FILE='./archive_libs/logical/q_cap_diffbus/chips/chips.prt';

PART_NAME
 C1556 'Q_CAP_DIFFBUS_C0201-DIFF BUS_0A':;

SECTION_NUMBER 1
 '@S9S_MB_2U_LIB.S9S_MB_2U(SCH_1):PAGE166_I265@PURE_QUANTA.Q_CAP_DIFFBUS(CHIPS)':
 C_PATH='@s9s_mb_2u_lib.s9s_mb_2u(sch_1):page166_i265@pure_quanta.q_cap_diffbus(~
chips)',
 P_PATH='@s9s_mb_2u_lib.s9s_mb_2u(sch_1):page175_i265@pure_quanta.q_cap_diffbus(~
chips)',
 PATH='I265',
 DRAWING='@S9S_MB_2U_LIB.S9S_MB_2U(SCH_1):PAGE166',
 PIN_NAMES_ROTATE='TRUE',
 PHYS_PAGE='175',
 XY='(-925,2775)',
 ROT='2',
 VER='2',
 PACK_TYPE='C0201',
 CDS_LIB='pure_quanta',
 CDS_PART_NAME='Q_CAP_DIFFBUS_C0201-DIFF BUS_0A',
 TOLERANCE='20%',
 MATERIAL='X6S',
 VOLTAGE='6.3V',
 VALUE='DIFF BUS_0.22UF',
 PRIM_FILE='./archive_libs/logical/q_cap_diffbus/chips/chips.prt';

PART_NAME
 C1557 'Q_CAP_DIFFBUS_C0201-DIFF BUS_0A':;

SECTION_NUMBER 1
 '@S9S_MB_2U_LIB.S9S_MB_2U(SCH_1):PAGE166_I266@PURE_QUANTA.Q_CAP_DIFFBUS(CHIPS)':
 C_PATH='@s9s_mb_2u_lib.s9s_mb_2u(sch_1):page166_i266@pure_quanta.q_cap_diffbus(~
chips)',
 P_PATH='@s9s_mb_2u_lib.s9s_mb_2u(sch_1):page175_i266@pure_quanta.q_cap_diffbus(~
chips)',
 PATH='I266',
 DRAWING='@S9S_MB_2U_LIB.S9S_MB_2U(SCH_1):PAGE166',
 PIN_NAMES_ROTATE='TRUE',
 PHYS_PAGE='175',
 XY='(-925,2725)',
 ROT='2',
 VER='2',
 PACK_TYPE='C0201',
 CDS_LIB='pure_quanta',
 CDS_PART_NAME='Q_CAP_DIFFBUS_C0201-DIFF BUS_0A',
 TOLERANCE='20%',
 MATERIAL='X6S',
 VOLTAGE='6.3V',
 VALUE='DIFF BUS_0.22UF',
 PRIM_FILE='./archive_libs/logical/q_cap_diffbus/chips/chips.prt';

PART_NAME
 C1558 'Q_CAP_DIFFBUS_C0201-DIFF BUS_0A':;

SECTION_NUMBER 1
 '@S9S_MB_2U_LIB.S9S_MB_2U(SCH_1):PAGE166_I264@PURE_QUANTA.Q_CAP_DIFFBUS(CHIPS)':
 C_PATH='@s9s_mb_2u_lib.s9s_mb_2u(sch_1):page166_i264@pure_quanta.q_cap_diffbus(~
chips)',
 P_PATH='@s9s_mb_2u_lib.s9s_mb_2u(sch_1):page175_i264@pure_quanta.q_cap_diffbus(~
chips)',
 PATH='I264',
 DRAWING='@S9S_MB_2U_LIB.S9S_MB_2U(SCH_1):PAGE166',
 PIN_NAMES_ROTATE='TRUE',
 PHYS_PAGE='175',
 XY='(-925,2575)',
 ROT='2',
 VER='2',
 PACK_TYPE='C0201',
 CDS_LIB='pure_quanta',
 CDS_PART_NAME='Q_CAP_DIFFBUS_C0201-DIFF BUS_0A',
 TOLERANCE='20%',
 MATERIAL='X6S',
 VOLTAGE='6.3V',
 VALUE='DIFF BUS_0.22UF',
 PRIM_FILE='./archive_libs/logical/q_cap_diffbus/chips/chips.prt';

PART_NAME
 C1559 'Q_CAP_DIFFBUS_C0201-DIFF BUS_0A':;

SECTION_NUMBER 1
 '@S9S_MB_2U_LIB.S9S_MB_2U(SCH_1):PAGE166_I263@PURE_QUANTA.Q_CAP_DIFFBUS(CHIPS)':
 C_PATH='@s9s_mb_2u_lib.s9s_mb_2u(sch_1):page166_i263@pure_quanta.q_cap_diffbus(~
chips)',
 P_PATH='@s9s_mb_2u_lib.s9s_mb_2u(sch_1):page175_i263@pure_quanta.q_cap_diffbus(~
chips)',
 PATH='I263',
 DRAWING='@S9S_MB_2U_LIB.S9S_MB_2U(SCH_1):PAGE166',
 PIN_NAMES_ROTATE='TRUE',
 PHYS_PAGE='175',
 XY='(-925,2525)',
 ROT='2',
 VER='2',
 PACK_TYPE='C0201',
 CDS_LIB='pure_quanta',
 CDS_PART_NAME='Q_CAP_DIFFBUS_C0201-DIFF BUS_0A',
 TOLERANCE='20%',
 MATERIAL='X6S',
 VOLTAGE='6.3V',
 VALUE='DIFF BUS_0.22UF',
 PRIM_FILE='./archive_libs/logical/q_cap_diffbus/chips/chips.prt';

PART_NAME
 C1560 'Q_CAP_DIFFBUS_C0201-DIFF BUS_0A':;

SECTION_NUMBER 1
 '@S9S_MB_2U_LIB.S9S_MB_2U(SCH_1):PAGE166_I262@PURE_QUANTA.Q_CAP_DIFFBUS(CHIPS)':
 C_PATH='@s9s_mb_2u_lib.s9s_mb_2u(sch_1):page166_i262@pure_quanta.q_cap_diffbus(~
chips)',
 P_PATH='@s9s_mb_2u_lib.s9s_mb_2u(sch_1):page175_i262@pure_quanta.q_cap_diffbus(~
chips)',
 PATH='I262',
 DRAWING='@S9S_MB_2U_LIB.S9S_MB_2U(SCH_1):PAGE166',
 PIN_NAMES_ROTATE='TRUE',
 PHYS_PAGE='175',
 XY='(-925,2375)',
 ROT='2',
 VER='2',
 PACK_TYPE='C0201',
 CDS_LIB='pure_quanta',
 CDS_PART_NAME='Q_CAP_DIFFBUS_C0201-DIFF BUS_0A',
 TOLERANCE='20%',
 MATERIAL='X6S',
 VOLTAGE='6.3V',
 VALUE='DIFF BUS_0.22UF',
 PRIM_FILE='./archive_libs/logical/q_cap_diffbus/chips/chips.prt';

PART_NAME
 C1561 'Q_CAP_C0402-1UF,25V,10%,X6S,CHA':;

SECTION_NUMBER 1
 '@S9S_MB_2U_LIB.S9S_MB_2U(SCH_1):PAGE326_I90@PURE_QUANTA.Q_CAP(CHIPS)':
 C_PATH='@s9s_mb_2u_lib.s9s_mb_2u(sch_1):page326_i90@pure_quanta.q_cap(chips)',
 P_PATH='@s9s_mb_2u_lib.s9s_mb_2u(sch_1):page306_i90@pure_quanta.q_cap(chips)',
 PATH='I90',
 DRAWING='@S9S_MB_2U_LIB.S9S_MB_2U(SCH_1):PAGE326',
 PHYS_PAGE='306',
 XY='(550,275)',
 ROT='0',
 VER='1',
 PACK_TYPE='C0402',
 LOCATION='C1561',
 CDS_LIB='pure_quanta',
 CDS_PART_NAME='Q_CAP_C0402-1UF,25V,10%,X6S,CHA',
 TOLERANCE='10%',
 MATERIAL='X6S',
 VOLTAGE='25V',
 VALUE='1UF',
 PRIM_FILE='./archive_libs/logical/q_cap/chips/chips.prt';

PART_NAME
 C1562 'Q_CAP_C0402-1UF,25V,10%,EMPTY,A':;

SECTION_NUMBER 1
 '@S9S_MB_2U_LIB.S9S_MB_2U(SCH_1):PAGE326_I89@PURE_QUANTA.Q_CAP(CHIPS)':
 C_PATH='@s9s_mb_2u_lib.s9s_mb_2u(sch_1):page326_i89@pure_quanta.q_cap(chips)',
 P_PATH='@s9s_mb_2u_lib.s9s_mb_2u(sch_1):page306_i89@pure_quanta.q_cap(chips)',
 PATH='I89',
 DRAWING='@S9S_MB_2U_LIB.S9S_MB_2U(SCH_1):PAGE326',
 PHYS_PAGE='306',
 XY='(-2025,-1025)',
 ROT='0',
 VER='1',
 PACK_TYPE='C0402',
 LOCATION='C1562',
 CDS_LIB='pure_quanta',
 CDS_PART_NAME='Q_CAP_C0402-1UF,25V,10%,EMPTY,A',
 TOLERANCE='10%',
 MATERIAL='EMPTY',
 VOLTAGE='25V',
 VALUE='1UF',
 PRIM_FILE='./archive_libs/logical/q_cap/chips/chips.prt';

PART_NAME
 C1563 'Q_CAP_DIFFBUS_C0201-DIFF BUS_0A':;

SECTION_NUMBER 1
 '@S9S_MB_2U_LIB.S9S_MB_2U(SCH_1):PAGE166_I259@PURE_QUANTA.Q_CAP_DIFFBUS(CHIPS)':
 C_PATH='@s9s_mb_2u_lib.s9s_mb_2u(sch_1):page166_i259@pure_quanta.q_cap_diffbus(~
chips)',
 P_PATH='@s9s_mb_2u_lib.s9s_mb_2u(sch_1):page175_i259@pure_quanta.q_cap_diffbus(~
chips)',
 PATH='I259',
 DRAWING='@S9S_MB_2U_LIB.S9S_MB_2U(SCH_1):PAGE166',
 PIN_NAMES_ROTATE='TRUE',
 PHYS_PAGE='175',
 XY='(-925,2125)',
 ROT='2',
 VER='2',
 PACK_TYPE='C0201',
 CDS_LIB='pure_quanta',
 CDS_PART_NAME='Q_CAP_DIFFBUS_C0201-DIFF BUS_0A',
 TOLERANCE='20%',
 MATERIAL='X6S',
 VOLTAGE='6.3V',
 VALUE='DIFF BUS_0.22UF',
 PRIM_FILE='./archive_libs/logical/q_cap_diffbus/chips/chips.prt';

PART_NAME
 C1564 'Q_CAP_DIFFBUS_C0201-DIFF BUS_0A':;

SECTION_NUMBER 1
 '@S9S_MB_2U_LIB.S9S_MB_2U(SCH_1):PAGE166_I242@PURE_QUANTA.Q_CAP_DIFFBUS(CHIPS)':
 C_PATH='@s9s_mb_2u_lib.s9s_mb_2u(sch_1):page166_i242@pure_quanta.q_cap_diffbus(~
chips)',
 P_PATH='@s9s_mb_2u_lib.s9s_mb_2u(sch_1):page175_i242@pure_quanta.q_cap_diffbus(~
chips)',
 PATH='I242',
 DRAWING='@S9S_MB_2U_LIB.S9S_MB_2U(SCH_1):PAGE166',
 PIN_NAMES_ROTATE='TRUE',
 PHYS_PAGE='175',
 XY='(-925,1600)',
 ROT='2',
 VER='2',
 PACK_TYPE='C0201',
 CDS_LIB='pure_quanta',
 CDS_PART_NAME='Q_CAP_DIFFBUS_C0201-DIFF BUS_0A',
 TOLERANCE='20%',
 MATERIAL='X6S',
 VOLTAGE='6.3V',
 VALUE='DIFF BUS_0.22UF',
 PRIM_FILE='./archive_libs/logical/q_cap_diffbus/chips/chips.prt';

PART_NAME
 C1565 'Q_CAP_DIFFBUS_C0201-DIFF BUS_0A':;

SECTION_NUMBER 1
 '@S9S_MB_2U_LIB.S9S_MB_2U(SCH_1):PAGE166_I241@PURE_QUANTA.Q_CAP_DIFFBUS(CHIPS)':
 C_PATH='@s9s_mb_2u_lib.s9s_mb_2u(sch_1):page166_i241@pure_quanta.q_cap_diffbus(~
chips)',
 P_PATH='@s9s_mb_2u_lib.s9s_mb_2u(sch_1):page175_i241@pure_quanta.q_cap_diffbus(~
chips)',
 PATH='I241',
 DRAWING='@S9S_MB_2U_LIB.S9S_MB_2U(SCH_1):PAGE166',
 PIN_NAMES_ROTATE='TRUE',
 PHYS_PAGE='175',
 XY='(-925,1550)',
 ROT='2',
 VER='2',
 PACK_TYPE='C0201',
 CDS_LIB='pure_quanta',
 CDS_PART_NAME='Q_CAP_DIFFBUS_C0201-DIFF BUS_0A',
 TOLERANCE='20%',
 MATERIAL='X6S',
 VOLTAGE='6.3V',
 VALUE='DIFF BUS_0.22UF',
 PRIM_FILE='./archive_libs/logical/q_cap_diffbus/chips/chips.prt';

PART_NAME
 C1566 'Q_CAP_DIFFBUS_C0201-DIFF BUS_0A':;

SECTION_NUMBER 1
 '@S9S_MB_2U_LIB.S9S_MB_2U(SCH_1):PAGE166_I240@PURE_QUANTA.Q_CAP_DIFFBUS(CHIPS)':
 C_PATH='@s9s_mb_2u_lib.s9s_mb_2u(sch_1):page166_i240@pure_quanta.q_cap_diffbus(~
chips)',
 P_PATH='@s9s_mb_2u_lib.s9s_mb_2u(sch_1):page175_i240@pure_quanta.q_cap_diffbus(~
chips)',
 PATH='I240',
 DRAWING='@S9S_MB_2U_LIB.S9S_MB_2U(SCH_1):PAGE166',
 PIN_NAMES_ROTATE='TRUE',
 PHYS_PAGE='175',
 XY='(-925,1400)',
 ROT='2',
 VER='2',
 PACK_TYPE='C0201',
 CDS_LIB='pure_quanta',
 CDS_PART_NAME='Q_CAP_DIFFBUS_C0201-DIFF BUS_0A',
 TOLERANCE='20%',
 MATERIAL='X6S',
 VOLTAGE='6.3V',
 VALUE='DIFF BUS_0.22UF',
 PRIM_FILE='./archive_libs/logical/q_cap_diffbus/chips/chips.prt';

PART_NAME
 C1567 'Q_CAP_DIFFBUS_C0201-DIFF BUS_0A':;

SECTION_NUMBER 1
 '@S9S_MB_2U_LIB.S9S_MB_2U(SCH_1):PAGE166_I239@PURE_QUANTA.Q_CAP_DIFFBUS(CHIPS)':
 C_PATH='@s9s_mb_2u_lib.s9s_mb_2u(sch_1):page166_i239@pure_quanta.q_cap_diffbus(~
chips)',
 P_PATH='@s9s_mb_2u_lib.s9s_mb_2u(sch_1):page175_i239@pure_quanta.q_cap_diffbus(~
chips)',
 PATH='I239',
 DRAWING='@S9S_MB_2U_LIB.S9S_MB_2U(SCH_1):PAGE166',
 PIN_NAMES_ROTATE='TRUE',
 PHYS_PAGE='175',
 XY='(-925,1350)',
 ROT='2',
 VER='2',
 PACK_TYPE='C0201',
 CDS_LIB='pure_quanta',
 CDS_PART_NAME='Q_CAP_DIFFBUS_C0201-DIFF BUS_0A',
 TOLERANCE='20%',
 MATERIAL='X6S',
 VOLTAGE='6.3V',
 VALUE='DIFF BUS_0.22UF',
 PRIM_FILE='./archive_libs/logical/q_cap_diffbus/chips/chips.prt';

PART_NAME
 C1568 'Q_CAP_DIFFBUS_C0201-DIFF BUS_0A':;

SECTION_NUMBER 1
 '@S9S_MB_2U_LIB.S9S_MB_2U(SCH_1):PAGE166_I238@PURE_QUANTA.Q_CAP_DIFFBUS(CHIPS)':
 C_PATH='@s9s_mb_2u_lib.s9s_mb_2u(sch_1):page166_i238@pure_quanta.q_cap_diffbus(~
chips)',
 P_PATH='@s9s_mb_2u_lib.s9s_mb_2u(sch_1):page175_i238@pure_quanta.q_cap_diffbus(~
chips)',
 PATH='I238',
 DRAWING='@S9S_MB_2U_LIB.S9S_MB_2U(SCH_1):PAGE166',
 PIN_NAMES_ROTATE='TRUE',
 PHYS_PAGE='175',
 XY='(-925,1200)',
 ROT='2',
 VER='2',
 PACK_TYPE='C0201',
 CDS_LIB='pure_quanta',
 CDS_PART_NAME='Q_CAP_DIFFBUS_C0201-DIFF BUS_0A',
 TOLERANCE='20%',
 MATERIAL='X6S',
 VOLTAGE='6.3V',
 VALUE='DIFF BUS_0.22UF',
 PRIM_FILE='./archive_libs/logical/q_cap_diffbus/chips/chips.prt';

PART_NAME
 C1569 'Q_CAP_DIFFBUS_C0201-DIFF BUS_0A':;

SECTION_NUMBER 1
 '@S9S_MB_2U_LIB.S9S_MB_2U(SCH_1):PAGE166_I237@PURE_QUANTA.Q_CAP_DIFFBUS(CHIPS)':
 C_PATH='@s9s_mb_2u_lib.s9s_mb_2u(sch_1):page166_i237@pure_quanta.q_cap_diffbus(~
chips)',
 P_PATH='@s9s_mb_2u_lib.s9s_mb_2u(sch_1):page175_i237@pure_quanta.q_cap_diffbus(~
chips)',
 PATH='I237',
 DRAWING='@S9S_MB_2U_LIB.S9S_MB_2U(SCH_1):PAGE166',
 PIN_NAMES_ROTATE='TRUE',
 PHYS_PAGE='175',
 XY='(-925,1150)',
 ROT='2',
 VER='2',
 PACK_TYPE='C0201',
 CDS_LIB='pure_quanta',
 CDS_PART_NAME='Q_CAP_DIFFBUS_C0201-DIFF BUS_0A',
 TOLERANCE='20%',
 MATERIAL='X6S',
 VOLTAGE='6.3V',
 VALUE='DIFF BUS_0.22UF',
 PRIM_FILE='./archive_libs/logical/q_cap_diffbus/chips/chips.prt';

PART_NAME
 C1570 'Q_CAP_DIFFBUS_C0201-DIFF BUS_0A':;

SECTION_NUMBER 1
 '@S9S_MB_2U_LIB.S9S_MB_2U(SCH_1):PAGE166_I235@PURE_QUANTA.Q_CAP_DIFFBUS(CHIPS)':
 C_PATH='@s9s_mb_2u_lib.s9s_mb_2u(sch_1):page166_i235@pure_quanta.q_cap_diffbus(~
chips)',
 P_PATH='@s9s_mb_2u_lib.s9s_mb_2u(sch_1):page175_i235@pure_quanta.q_cap_diffbus(~
chips)',
 PATH='I235',
 DRAWING='@S9S_MB_2U_LIB.S9S_MB_2U(SCH_1):PAGE166',
 PIN_NAMES_ROTATE='TRUE',
 PHYS_PAGE='175',
 XY='(-925,1000)',
 ROT='2',
 VER='2',
 PACK_TYPE='C0201',
 CDS_LIB='pure_quanta',
 CDS_PART_NAME='Q_CAP_DIFFBUS_C0201-DIFF BUS_0A',
 TOLERANCE='20%',
 MATERIAL='X6S',
 VOLTAGE='6.3V',
 VALUE='DIFF BUS_0.22UF',
 PRIM_FILE='./archive_libs/logical/q_cap_diffbus/chips/chips.prt';

PART_NAME
 C1571 'Q_CAP_DIFFBUS_C0201-DIFF BUS_0A':;

SECTION_NUMBER 1
 '@S9S_MB_2U_LIB.S9S_MB_2U(SCH_1):PAGE166_I236@PURE_QUANTA.Q_CAP_DIFFBUS(CHIPS)':
 C_PATH='@s9s_mb_2u_lib.s9s_mb_2u(sch_1):page166_i236@pure_quanta.q_cap_diffbus(~
chips)',
 P_PATH='@s9s_mb_2u_lib.s9s_mb_2u(sch_1):page175_i236@pure_quanta.q_cap_diffbus(~
chips)',
 PATH='I236',
 DRAWING='@S9S_MB_2U_LIB.S9S_MB_2U(SCH_1):PAGE166',
 PIN_NAMES_ROTATE='TRUE',
 PHYS_PAGE='175',
 XY='(-925,950)',
 ROT='2',
 VER='2',
 PACK_TYPE='C0201',
 CDS_LIB='pure_quanta',
 CDS_PART_NAME='Q_CAP_DIFFBUS_C0201-DIFF BUS_0A',
 TOLERANCE='20%',
 MATERIAL='X6S',
 VOLTAGE='6.3V',
 VALUE='DIFF BUS_0.22UF',
 PRIM_FILE='./archive_libs/logical/q_cap_diffbus/chips/chips.prt';

PART_NAME
 C1572 'Q_CAP_DIFFBUS_C0201-DIFF BUS_0A':;

SECTION_NUMBER 1
 '@S9S_MB_2U_LIB.S9S_MB_2U(SCH_1):PAGE166_I234@PURE_QUANTA.Q_CAP_DIFFBUS(CHIPS)':
 C_PATH='@s9s_mb_2u_lib.s9s_mb_2u(sch_1):page166_i234@pure_quanta.q_cap_diffbus(~
chips)',
 P_PATH='@s9s_mb_2u_lib.s9s_mb_2u(sch_1):page175_i234@pure_quanta.q_cap_diffbus(~
chips)',
 PATH='I234',
 DRAWING='@S9S_MB_2U_LIB.S9S_MB_2U(SCH_1):PAGE166',
 PIN_NAMES_ROTATE='TRUE',
 PHYS_PAGE='175',
 XY='(-925,800)',
 ROT='2',
 VER='2',
 PACK_TYPE='C0201',
 CDS_LIB='pure_quanta',
 CDS_PART_NAME='Q_CAP_DIFFBUS_C0201-DIFF BUS_0A',
 TOLERANCE='20%',
 MATERIAL='X6S',
 VOLTAGE='6.3V',
 VALUE='DIFF BUS_0.22UF',
 PRIM_FILE='./archive_libs/logical/q_cap_diffbus/chips/chips.prt';

PART_NAME
 C1573 'Q_CAP_DIFFBUS_C0201-DIFF BUS_0A':;

SECTION_NUMBER 1
 '@S9S_MB_2U_LIB.S9S_MB_2U(SCH_1):PAGE166_I233@PURE_QUANTA.Q_CAP_DIFFBUS(CHIPS)':
 C_PATH='@s9s_mb_2u_lib.s9s_mb_2u(sch_1):page166_i233@pure_quanta.q_cap_diffbus(~
chips)',
 P_PATH='@s9s_mb_2u_lib.s9s_mb_2u(sch_1):page175_i233@pure_quanta.q_cap_diffbus(~
chips)',
 PATH='I233',
 DRAWING='@S9S_MB_2U_LIB.S9S_MB_2U(SCH_1):PAGE166',
 PIN_NAMES_ROTATE='TRUE',
 PHYS_PAGE='175',
 XY='(-925,750)',
 ROT='2',
 VER='2',
 PACK_TYPE='C0201',
 CDS_LIB='pure_quanta',
 CDS_PART_NAME='Q_CAP_DIFFBUS_C0201-DIFF BUS_0A',
 TOLERANCE='20%',
 MATERIAL='X6S',
 VOLTAGE='6.3V',
 VALUE='DIFF BUS_0.22UF',
 PRIM_FILE='./archive_libs/logical/q_cap_diffbus/chips/chips.prt';

PART_NAME
 C1574 'Q_CAP_DIFFBUS_C0201-DIFF BUS_0A':;

SECTION_NUMBER 1
 '@S9S_MB_2U_LIB.S9S_MB_2U(SCH_1):PAGE166_I232@PURE_QUANTA.Q_CAP_DIFFBUS(CHIPS)':
 C_PATH='@s9s_mb_2u_lib.s9s_mb_2u(sch_1):page166_i232@pure_quanta.q_cap_diffbus(~
chips)',
 P_PATH='@s9s_mb_2u_lib.s9s_mb_2u(sch_1):page175_i232@pure_quanta.q_cap_diffbus(~
chips)',
 PATH='I232',
 DRAWING='@S9S_MB_2U_LIB.S9S_MB_2U(SCH_1):PAGE166',
 PIN_NAMES_ROTATE='TRUE',
 PHYS_PAGE='175',
 XY='(-925,600)',
 ROT='2',
 VER='2',
 PACK_TYPE='C0201',
 CDS_LIB='pure_quanta',
 CDS_PART_NAME='Q_CAP_DIFFBUS_C0201-DIFF BUS_0A',
 TOLERANCE='20%',
 MATERIAL='X6S',
 VOLTAGE='6.3V',
 VALUE='DIFF BUS_0.22UF',
 PRIM_FILE='./archive_libs/logical/q_cap_diffbus/chips/chips.prt';

PART_NAME
 C1575 'Q_CAP_DIFFBUS_C0201-DIFF BUS_0A':;

SECTION_NUMBER 1
 '@S9S_MB_2U_LIB.S9S_MB_2U(SCH_1):PAGE166_I231@PURE_QUANTA.Q_CAP_DIFFBUS(CHIPS)':
 C_PATH='@s9s_mb_2u_lib.s9s_mb_2u(sch_1):page166_i231@pure_quanta.q_cap_diffbus(~
chips)',
 P_PATH='@s9s_mb_2u_lib.s9s_mb_2u(sch_1):page175_i231@pure_quanta.q_cap_diffbus(~
chips)',
 PATH='I231',
 DRAWING='@S9S_MB_2U_LIB.S9S_MB_2U(SCH_1):PAGE166',
 PIN_NAMES_ROTATE='TRUE',
 PHYS_PAGE='175',
 XY='(-925,550)',
 ROT='2',
 VER='2',
 PACK_TYPE='C0201',
 CDS_LIB='pure_quanta',
 CDS_PART_NAME='Q_CAP_DIFFBUS_C0201-DIFF BUS_0A',
 TOLERANCE='20%',
 MATERIAL='X6S',
 VOLTAGE='6.3V',
 VALUE='DIFF BUS_0.22UF',
 PRIM_FILE='./archive_libs/logical/q_cap_diffbus/chips/chips.prt';

PART_NAME
 C1576 'Q_CAP_DIFFBUS_C0201-DIFF BUS_0A':;

SECTION_NUMBER 1
 '@S9S_MB_2U_LIB.S9S_MB_2U(SCH_1):PAGE166_I312@PURE_QUANTA.Q_CAP_DIFFBUS(CHIPS)':
 C_PATH='@s9s_mb_2u_lib.s9s_mb_2u(sch_1):page166_i312@pure_quanta.q_cap_diffbus(~
chips)',
 P_PATH='@s9s_mb_2u_lib.s9s_mb_2u(sch_1):page175_i312@pure_quanta.q_cap_diffbus(~
chips)',
 PATH='I312',
 DRAWING='@S9S_MB_2U_LIB.S9S_MB_2U(SCH_1):PAGE166',
 PIN_NAMES_ROTATE='TRUE',
 PHYS_PAGE='175',
 XY='(-925,400)',
 ROT='2',
 VER='2',
 PACK_TYPE='C0201',
 CDS_LIB='pure_quanta',
 CDS_PART_NAME='Q_CAP_DIFFBUS_C0201-DIFF BUS_0A',
 TOLERANCE='20%',
 MATERIAL='X6S',
 VOLTAGE='6.3V',
 VALUE='DIFF BUS_0.22UF',
 PRIM_FILE='./archive_libs/logical/q_cap_diffbus/chips/chips.prt';

PART_NAME
 C1577 'Q_CAP_DIFFBUS_C0201-DIFF BUS_0A':;

SECTION_NUMBER 1
 '@S9S_MB_2U_LIB.S9S_MB_2U(SCH_1):PAGE166_I311@PURE_QUANTA.Q_CAP_DIFFBUS(CHIPS)':
 C_PATH='@s9s_mb_2u_lib.s9s_mb_2u(sch_1):page166_i311@pure_quanta.q_cap_diffbus(~
chips)',
 P_PATH='@s9s_mb_2u_lib.s9s_mb_2u(sch_1):page175_i311@pure_quanta.q_cap_diffbus(~
chips)',
 PATH='I311',
 DRAWING='@S9S_MB_2U_LIB.S9S_MB_2U(SCH_1):PAGE166',
 PIN_NAMES_ROTATE='TRUE',
 PHYS_PAGE='175',
 XY='(-925,350)',
 ROT='2',
 VER='2',
 PACK_TYPE='C0201',
 CDS_LIB='pure_quanta',
 CDS_PART_NAME='Q_CAP_DIFFBUS_C0201-DIFF BUS_0A',
 TOLERANCE='20%',
 MATERIAL='X6S',
 VOLTAGE='6.3V',
 VALUE='DIFF BUS_0.22UF',
 PRIM_FILE='./archive_libs/logical/q_cap_diffbus/chips/chips.prt';

PART_NAME
 C1578 'Q_CAP_DIFFBUS_C0201-DIFF BUS_0A':;

SECTION_NUMBER 1
 '@S9S_MB_2U_LIB.S9S_MB_2U(SCH_1):PAGE166_I230@PURE_QUANTA.Q_CAP_DIFFBUS(CHIPS)':
 C_PATH='@s9s_mb_2u_lib.s9s_mb_2u(sch_1):page166_i230@pure_quanta.q_cap_diffbus(~
chips)',
 P_PATH='@s9s_mb_2u_lib.s9s_mb_2u(sch_1):page175_i230@pure_quanta.q_cap_diffbus(~
chips)',
 PATH='I230',
 DRAWING='@S9S_MB_2U_LIB.S9S_MB_2U(SCH_1):PAGE166',
 PIN_NAMES_ROTATE='TRUE',
 PHYS_PAGE='175',
 XY='(-925,200)',
 ROT='2',
 VER='2',
 PACK_TYPE='C0201',
 CDS_LIB='pure_quanta',
 CDS_PART_NAME='Q_CAP_DIFFBUS_C0201-DIFF BUS_0A',
 TOLERANCE='20%',
 MATERIAL='X6S',
 VOLTAGE='6.3V',
 VALUE='DIFF BUS_0.22UF',
 PRIM_FILE='./archive_libs/logical/q_cap_diffbus/chips/chips.prt';

PART_NAME
 C1579 'Q_CAP_DIFFBUS_C0201-DIFF BUS_0A':;

SECTION_NUMBER 1
 '@S9S_MB_2U_LIB.S9S_MB_2U(SCH_1):PAGE166_I229@PURE_QUANTA.Q_CAP_DIFFBUS(CHIPS)':
 C_PATH='@s9s_mb_2u_lib.s9s_mb_2u(sch_1):page166_i229@pure_quanta.q_cap_diffbus(~
chips)',
 P_PATH='@s9s_mb_2u_lib.s9s_mb_2u(sch_1):page175_i229@pure_quanta.q_cap_diffbus(~
chips)',
 PATH='I229',
 DRAWING='@S9S_MB_2U_LIB.S9S_MB_2U(SCH_1):PAGE166',
 PIN_NAMES_ROTATE='TRUE',
 PHYS_PAGE='175',
 XY='(-925,150)',
 ROT='2',
 VER='2',
 PACK_TYPE='C0201',
 CDS_LIB='pure_quanta',
 CDS_PART_NAME='Q_CAP_DIFFBUS_C0201-DIFF BUS_0A',
 TOLERANCE='20%',
 MATERIAL='X6S',
 VOLTAGE='6.3V',
 VALUE='DIFF BUS_0.22UF',
 PRIM_FILE='./archive_libs/logical/q_cap_diffbus/chips/chips.prt';

PART_NAME
 C1592 'Q_CAP_0402-0.1UF,25V,10%,X7R,CA':;

SECTION_NUMBER 1
 '@S9S_MB_2U_LIB.S9S_MB_2U(SCH_1):PAGE297_I304@PURE_QUANTA.Q_CAP(CHIPS)':
 C_PATH='@s9s_mb_2u_lib.s9s_mb_2u(sch_1):page297_i304@pure_quanta.q_cap(chips)',
 P_PATH='@s9s_mb_2u_lib.s9s_mb_2u(sch_1):page191_i304@pure_quanta.q_cap(chips)',
 PATH='I304',
 DRAWING='@S9S_MB_2U_LIB.S9S_MB_2U(SCH_1):PAGE297',
 PHYS_PAGE='191',
 XY='(950,-200)',
 ROT='0',
 VER='1',
 PACK_TYPE='0402',
 CDS_LIB='pure_quanta',
 CDS_PART_NAME='Q_CAP_0402-0.1UF,25V,10%,X7R,CA',
 TOLERANCE='10%',
 MATERIAL='X7R',
 VOLTAGE='25V',
 VALUE='0.1UF',
 PRIM_FILE='./archive_libs/logical/q_cap/chips/chips.prt';

PART_NAME
 C1612 'Q_CAP_C0402-1UF,25V,10%,X6S,CHA':;

SECTION_NUMBER 1
 '@S9S_MB_2U_LIB.S9S_MB_2U(SCH_1):PAGE185_I36@PURE_QUANTA.Q_CAP(CHIPS)':
 C_PATH='@s9s_mb_2u_lib.s9s_mb_2u(sch_1):page185_i36@pure_quanta.q_cap(chips)',
 P_PATH='@s9s_mb_2u_lib.s9s_mb_2u(sch_1):page197_i36@pure_quanta.q_cap(chips)',
 PATH='I36',
 DRAWING='@S9S_MB_2U_LIB.S9S_MB_2U(SCH_1):PAGE185',
 PHYS_PAGE='197',
 XY='(-4925,4475)',
 ROT='0',
 VER='1',
 PACK_TYPE='C0402',
 CDS_LIB='pure_quanta',
 CDS_PART_NAME='Q_CAP_C0402-1UF,25V,10%,X6S,CHA',
 TOLERANCE='10%',
 MATERIAL='X6S',
 VOLTAGE='25V',
 VALUE='1UF',
 PRIM_FILE='./archive_libs/logical/q_cap/chips/chips.prt';

PART_NAME
 C1613 'Q_CAP_0402-0.1UF,25V,10%,X7R,CA':;

SECTION_NUMBER 1
 '@S9S_MB_2U_LIB.S9S_MB_2U(SCH_1):PAGE224_I68@PURE_QUANTA.Q_CAP(CHIPS)':
 C_PATH='@s9s_mb_2u_lib.s9s_mb_2u(sch_1):page224_i68@pure_quanta.q_cap(chips)',
 P_PATH='@s9s_mb_2u_lib.s9s_mb_2u(sch_1):page236_i68@pure_quanta.q_cap(chips)',
 PATH='I68',
 DRAWING='@S9S_MB_2U_LIB.S9S_MB_2U(SCH_1):PAGE224',
 PHYS_PAGE='236',
 XY='(-975,9275)',
 ROT='2',
 VER='1',
 PACK_TYPE='0402',
 CDS_LIB='pure_quanta',
 CDS_PART_NAME='Q_CAP_0402-0.1UF,25V,10%,X7R,CA',
 TOLERANCE='10%',
 MATERIAL='X7R',
 VOLTAGE='25V',
 VALUE='0.1UF',
 PRIM_FILE='./archive_libs/logical/q_cap/chips/chips.prt';

PART_NAME
 C1614 'Q_CAP_0402-0.1UF,25V,10%,X7R,CA':;

SECTION_NUMBER 1
 '@S9S_MB_2U_LIB.S9S_MB_2U(SCH_1):PAGE297_I170@PURE_QUANTA.Q_CAP(CHIPS)':
 C_PATH='@s9s_mb_2u_lib.s9s_mb_2u(sch_1):page297_i170@pure_quanta.q_cap(chips)',
 P_PATH='@s9s_mb_2u_lib.s9s_mb_2u(sch_1):page191_i170@pure_quanta.q_cap(chips)',
 PATH='I170',
 DRAWING='@S9S_MB_2U_LIB.S9S_MB_2U(SCH_1):PAGE297',
 PHYS_PAGE='191',
 XY='(3850,1400)',
 ROT='0',
 VER='1',
 PACK_TYPE='0402',
 CDS_LIB='pure_quanta',
 CDS_PART_NAME='Q_CAP_0402-0.1UF,25V,10%,X7R,CA',
 TOLERANCE='10%',
 MATERIAL='X7R',
 VOLTAGE='25V',
 VALUE='0.1UF',
 PRIM_FILE='./archive_libs/logical/q_cap/chips/chips.prt';

PART_NAME
 C1619 'Q_CAP_0402-0.1UF,25V,10%,X7R,CA':;

SECTION_NUMBER 1
 '@S9S_MB_2U_LIB.S9S_MB_2U(SCH_1):PAGE213_I5@PURE_QUANTA.Q_CAP(CHIPS)':
 C_PATH='@s9s_mb_2u_lib.s9s_mb_2u(sch_1):page213_i5@pure_quanta.q_cap(chips)',
 P_PATH='@s9s_mb_2u_lib.s9s_mb_2u(sch_1):page224_i5@pure_quanta.q_cap(chips)',
 PATH='I5',
 DRAWING='@S9S_MB_2U_LIB.S9S_MB_2U(SCH_1):PAGE213',
 PHYS_PAGE='224',
 XY='(-7775,5475)',
 ROT='0',
 VER='1',
 PACK_TYPE='0402',
 CDS_LIB='pure_quanta',
 CDS_PART_NAME='Q_CAP_0402-0.1UF,25V,10%,X7R,CA',
 TOLERANCE='10%',
 MATERIAL='X7R',
 VOLTAGE='25V',
 VALUE='0.1UF',
 PRIM_FILE='./archive_libs/logical/q_cap/chips/chips.prt';

PART_NAME
 C1647 'Q_CAP_0402-0.1UF,25V,10%,X7R,CA':;

SECTION_NUMBER 1
 '@S9S_MB_2U_LIB.S9S_MB_2U(SCH_1):PAGE190_I84@PURE_QUANTA.Q_CAP(CHIPS)':
 C_PATH='@s9s_mb_2u_lib.s9s_mb_2u(sch_1):page190_i84@pure_quanta.q_cap(chips)',
 P_PATH='@s9s_mb_2u_lib.s9s_mb_2u(sch_1):page202_i84@pure_quanta.q_cap(chips)',
 PATH='I84',
 DRAWING='@S9S_MB_2U_LIB.S9S_MB_2U(SCH_1):PAGE190',
 PHYS_PAGE='202',
 XY='(1050,1750)',
 ROT='2',
 VER='1',
 PACK_TYPE='0402',
 CDS_LIB='pure_quanta',
 CDS_PART_NAME='Q_CAP_0402-0.1UF,25V,10%,X7R,CA',
 TOLERANCE='10%',
 MATERIAL='X7R',
 VOLTAGE='25V',
 VALUE='0.1UF',
 PRIM_FILE='./archive_libs/logical/q_cap/chips/chips.prt';

PART_NAME
 C1663 'Q_CAP_0402-0.1UF,25V,10%,X7R,CA':;

SECTION_NUMBER 1
 '@S9S_MB_2U_LIB.S9S_MB_2U(SCH_1):PAGE152_I68@PURE_QUANTA.Q_CAP(CHIPS)':
 C_PATH='@s9s_mb_2u_lib.s9s_mb_2u(sch_1):page152_i68@pure_quanta.q_cap(chips)',
 P_PATH='@s9s_mb_2u_lib.s9s_mb_2u(sch_1):page155_i68@pure_quanta.q_cap(chips)',
 PATH='I68',
 DRAWING='@S9S_MB_2U_LIB.S9S_MB_2U(SCH_1):PAGE152',
 PHYS_PAGE='155',
 XY='(-4500,4375)',
 ROT='0',
 VER='1',
 PACK_TYPE='0402',
 CDS_LIB='pure_quanta',
 CDS_PART_NAME='Q_CAP_0402-0.1UF,25V,10%,X7R,CA',
 TOLERANCE='10%',
 MATERIAL='X7R',
 VOLTAGE='25V',
 VALUE='0.1UF',
 PRIM_FILE='./archive_libs/logical/q_cap/chips/chips.prt';

PART_NAME
 C1664 'Q_CAP_0402-0.1UF,25V,10%,X7R,CA':;

SECTION_NUMBER 1
 '@S9S_MB_2U_LIB.S9S_MB_2U(SCH_1):PAGE226_I93@PURE_QUANTA.Q_CAP(CHIPS)':
 C_PATH='@s9s_mb_2u_lib.s9s_mb_2u(sch_1):page226_i93@pure_quanta.q_cap(chips)',
 P_PATH='@s9s_mb_2u_lib.s9s_mb_2u(sch_1):page239_i93@pure_quanta.q_cap(chips)',
 PATH='I93',
 DRAWING='@S9S_MB_2U_LIB.S9S_MB_2U(SCH_1):PAGE226',
 PHYS_PAGE='239',
 XY='(-9450,2075)',
 ROT='0',
 VER='2',
 PACK_TYPE='0402',
 CDS_LIB='pure_quanta',
 CDS_PART_NAME='Q_CAP_0402-0.1UF,25V,10%,X7R,CA',
 TOLERANCE='10%',
 MATERIAL='X7R',
 VOLTAGE='25V',
 VALUE='0.1UF',
 PRIM_FILE='./archive_libs/logical/q_cap/chips/chips.prt';

PART_NAME
 C1707 'Q_CAP_0402-0.1UF,25V,10%,X7R,CA':;

SECTION_NUMBER 1
 '@S9S_MB_2U_LIB.S9S_MB_2U(SCH_1):PAGE222_I58@PURE_QUANTA.Q_CAP(CHIPS)':
 C_PATH='@s9s_mb_2u_lib.s9s_mb_2u(sch_1):page222_i58@pure_quanta.q_cap(chips)',
 P_PATH='@s9s_mb_2u_lib.s9s_mb_2u(sch_1):page234_i58@pure_quanta.q_cap(chips)',
 PATH='I58',
 DRAWING='@S9S_MB_2U_LIB.S9S_MB_2U(SCH_1):PAGE222',
 PHYS_PAGE='234',
 XY='(-4000,9150)',
 ROT='0',
 VER='1',
 PACK_TYPE='0402',
 CDS_LIB='pure_quanta',
 CDS_PART_NAME='Q_CAP_0402-0.1UF,25V,10%,X7R,CA',
 TOLERANCE='10%',
 MATERIAL='X7R',
 VOLTAGE='25V',
 VALUE='0.1UF',
 PRIM_FILE='./archive_libs/logical/q_cap/chips/chips.prt';

PART_NAME
 C1708 'Q_CAP_0402-0.1UF,25V,10%,EMPTYA':;

SECTION_NUMBER 1
 '@S9S_MB_2U_LIB.S9S_MB_2U(SCH_1):PAGE222_I34@PURE_QUANTA.Q_CAP(CHIPS)':
 C_PATH='@s9s_mb_2u_lib.s9s_mb_2u(sch_1):page222_i34@pure_quanta.q_cap(chips)',
 P_PATH='@s9s_mb_2u_lib.s9s_mb_2u(sch_1):page234_i34@pure_quanta.q_cap(chips)',
 PATH='I34',
 DRAWING='@S9S_MB_2U_LIB.S9S_MB_2U(SCH_1):PAGE222',
 PHYS_PAGE='234',
 XY='(-1625,5050)',
 ROT='0',
 VER='1',
 PACK_TYPE='0402',
 CDS_LIB='pure_quanta',
 CDS_PART_NAME='Q_CAP_0402-0.1UF,25V,10%,EMPTYA',
 TOLERANCE='10%',
 MATERIAL='EMPTY',
 VOLTAGE='25V',
 VALUE='0.1UF',
 PRIM_FILE='./archive_libs/logical/q_cap/chips/chips.prt';

PART_NAME
 C1713 'Q_CAP_0402-0.1UF,25V,10%,X7R,CA':;

SECTION_NUMBER 1
 '@S9S_MB_2U_LIB.S9S_MB_2U(SCH_1):PAGE214_I87@PURE_QUANTA.Q_CAP(CHIPS)':
 C_PATH='@s9s_mb_2u_lib.s9s_mb_2u(sch_1):page214_i87@pure_quanta.q_cap(chips)',
 P_PATH='@s9s_mb_2u_lib.s9s_mb_2u(sch_1):page227_i87@pure_quanta.q_cap(chips)',
 PATH='I87',
 DRAWING='@S9S_MB_2U_LIB.S9S_MB_2U(SCH_1):PAGE214',
 PHYS_PAGE='227',
 XY='(9000,4150)',
 ROT='2',
 VER='1',
 PACK_TYPE='0402',
 CDS_LIB='pure_quanta',
 CDS_PART_NAME='Q_CAP_0402-0.1UF,25V,10%,X7R,CA',
 TOLERANCE='10%',
 MATERIAL='X7R',
 VOLTAGE='25V',
 VALUE='0.1UF',
 PRIM_FILE='./archive_libs/logical/q_cap/chips/chips.prt';

PART_NAME
 C1751 'Q_CAP_0402-0.1UF,25V,10%,X7R,CA':;

SECTION_NUMBER 1
 '@S9S_MB_2U_LIB.S9S_MB_2U(SCH_1):PAGE233_I19@PURE_QUANTA.Q_CAP(CHIPS)':
 C_PATH='@s9s_mb_2u_lib.s9s_mb_2u(sch_1):page233_i19@pure_quanta.q_cap(chips)',
 P_PATH='@s9s_mb_2u_lib.s9s_mb_2u(sch_1):page245_i19@pure_quanta.q_cap(chips)',
 PATH='I19',
 DRAWING='@S9S_MB_2U_LIB.S9S_MB_2U(SCH_1):PAGE233',
 PHYS_PAGE='245',
 XY='(-1700,-1600)',
 ROT='2',
 VER='1',
 PACK_TYPE='0402',
 CDS_LIB='pure_quanta',
 CDS_PART_NAME='Q_CAP_0402-0.1UF,25V,10%,X7R,CA',
 TOLERANCE='10%',
 MATERIAL='X7R',
 VOLTAGE='25V',
 VALUE='0.1UF',
 PRIM_FILE='./archive_libs/logical/q_cap/chips/chips.prt';

PART_NAME
 C1754 'Q_CAP_0402-1000PF,50V,5%,EMPTYA':;

SECTION_NUMBER 1
 '@S9S_MB_2U_LIB.S9S_MB_2U(SCH_1):PAGE145_I92@PURE_QUANTA.Q_CAP(CHIPS)':
 C_PATH='@s9s_mb_2u_lib.s9s_mb_2u(sch_1):page145_i92@pure_quanta.q_cap(chips)',
 P_PATH='@s9s_mb_2u_lib.s9s_mb_2u(sch_1):page148_i92@pure_quanta.q_cap(chips)',
 PATH='I92',
 DRAWING='@S9S_MB_2U_LIB.S9S_MB_2U(SCH_1):PAGE145',
 PHYS_PAGE='148',
 XY='(-1600,4925)',
 ROT='0',
 VER='1',
 PACK_TYPE='0402',
 CDS_LIB='pure_quanta',
 CDS_PART_NAME='Q_CAP_0402-1000PF,50V,5%,EMPTYA',
 TOLERANCE='5%',
 MATERIAL='EMPTY',
 VOLTAGE='50V',
 VALUE='1000PF',
 PRIM_FILE='./archive_libs/logical/q_cap/chips/chips.prt';

PART_NAME
 C1756 'Q_CAP_0402-1000PF,50V,5%,EMPTYA':;

SECTION_NUMBER 1
 '@S9S_MB_2U_LIB.S9S_MB_2U(SCH_1):PAGE145_I105@PURE_QUANTA.Q_CAP(CHIPS)':
 C_PATH='@s9s_mb_2u_lib.s9s_mb_2u(sch_1):page145_i105@pure_quanta.q_cap(chips)',
 P_PATH='@s9s_mb_2u_lib.s9s_mb_2u(sch_1):page148_i105@pure_quanta.q_cap(chips)',
 PATH='I105',
 DRAWING='@S9S_MB_2U_LIB.S9S_MB_2U(SCH_1):PAGE145',
 PHYS_PAGE='148',
 XY='(2925,6250)',
 ROT='0',
 VER='1',
 PACK_TYPE='0402',
 CDS_LIB='pure_quanta',
 CDS_PART_NAME='Q_CAP_0402-1000PF,50V,5%,EMPTYA',
 TOLERANCE='5%',
 MATERIAL='EMPTY',
 VOLTAGE='50V',
 VALUE='1000PF',
 PRIM_FILE='./archive_libs/logical/q_cap/chips/chips.prt';

PART_NAME
 C1757 'Q_CAP_0402-0.1UF,25V,10%,EMPTYA':
 ROOM='ADC1_BOM1';

SECTION_NUMBER 1
 '@S9S_MB_2U_LIB.S9S_MB_2U(SCH_1):PAGE239_I58@PURE_QUANTA.Q_CAP(CHIPS)':
 C_PATH='@s9s_mb_2u_lib.s9s_mb_2u(sch_1):page239_i58@pure_quanta.q_cap(chips)',
 P_PATH='@s9s_mb_2u_lib.s9s_mb_2u(sch_1):page250_i58@pure_quanta.q_cap(chips)',
 PATH='I58',
 DRAWING='@S9S_MB_2U_LIB.S9S_MB_2U(SCH_1):PAGE239',
 PHYS_PAGE='250',
 XY='(6400,4525)',
 ROT='2',
 VER='1',
 PACK_TYPE='0402',
 CDS_LIB='pure_quanta',
 CDS_PART_NAME='Q_CAP_0402-0.1UF,25V,10%,EMPTYA',
 TOLERANCE='10%',
 MATERIAL='EMPTY',
 VOLTAGE='25V',
 ROOM='ADC1_BOM1',
 VALUE='0.1UF',
 PRIM_FILE='./archive_libs/logical/q_cap/chips/chips.prt';

PART_NAME
 C1766 'Q_CAP_0402-0.1UF,25V,10%,X7R,CA':;

SECTION_NUMBER 1
 '@S9S_MB_2U_LIB.S9S_MB_2U(SCH_1):PAGE222_I66@PURE_QUANTA.Q_CAP(CHIPS)':
 C_PATH='@s9s_mb_2u_lib.s9s_mb_2u(sch_1):page222_i66@pure_quanta.q_cap(chips)',
 P_PATH='@s9s_mb_2u_lib.s9s_mb_2u(sch_1):page234_i66@pure_quanta.q_cap(chips)',
 PATH='I66',
 DRAWING='@S9S_MB_2U_LIB.S9S_MB_2U(SCH_1):PAGE222',
 PHYS_PAGE='234',
 XY='(-1525,7775)',
 ROT='0',
 VER='1',
 PACK_TYPE='0402',
 CDS_LIB='pure_quanta',
 CDS_PART_NAME='Q_CAP_0402-0.1UF,25V,10%,X7R,CA',
 TOLERANCE='10%',
 MATERIAL='X7R',
 VOLTAGE='25V',
 VALUE='0.1UF',
 PRIM_FILE='./archive_libs/logical/q_cap/chips/chips.prt';

PART_NAME
 C1767 'Q_CAP_C0805-10UF,16V,10%,EMPTYA':
 ROOM='ADC1_BOM1';

SECTION_NUMBER 1
 '@S9S_MB_2U_LIB.S9S_MB_2U(SCH_1):PAGE239_I68@PURE_QUANTA.Q_CAP(CHIPS)':
 C_PATH='@s9s_mb_2u_lib.s9s_mb_2u(sch_1):page239_i68@pure_quanta.q_cap(chips)',
 P_PATH='@s9s_mb_2u_lib.s9s_mb_2u(sch_1):page250_i68@pure_quanta.q_cap(chips)',
 PATH='I68',
 DRAWING='@S9S_MB_2U_LIB.S9S_MB_2U(SCH_1):PAGE239',
 PHYS_PAGE='250',
 XY='(4075,4550)',
 ROT='0',
 VER='1',
 PACK_TYPE='C0805',
 CDS_LIB='pure_quanta',
 CDS_PART_NAME='Q_CAP_C0805-10UF,16V,10%,EMPTYA',
 TOLERANCE='10%',
 MATERIAL='EMPTY',
 VOLTAGE='16V',
 ROOM='ADC1_BOM1',
 VALUE='10UF',
 PRIM_FILE='./archive_libs/logical/q_cap/chips/chips.prt';

PART_NAME
 C1768 'Q_CAP_C0805-10UF,16V,10%,EMPTYA':
 ROOM='ADC1_BOM1';

SECTION_NUMBER 1
 '@S9S_MB_2U_LIB.S9S_MB_2U(SCH_1):PAGE239_I61@PURE_QUANTA.Q_CAP(CHIPS)':
 C_PATH='@s9s_mb_2u_lib.s9s_mb_2u(sch_1):page239_i61@pure_quanta.q_cap(chips)',
 P_PATH='@s9s_mb_2u_lib.s9s_mb_2u(sch_1):page250_i61@pure_quanta.q_cap(chips)',
 PATH='I61',
 DRAWING='@S9S_MB_2U_LIB.S9S_MB_2U(SCH_1):PAGE239',
 PHYS_PAGE='250',
 XY='(6775,4525)',
 ROT='0',
 VER='1',
 PACK_TYPE='C0805',
 CDS_LIB='pure_quanta',
 CDS_PART_NAME='Q_CAP_C0805-10UF,16V,10%,EMPTYA',
 TOLERANCE='10%',
 MATERIAL='EMPTY',
 VOLTAGE='16V',
 ROOM='ADC1_BOM1',
 VALUE='10UF',
 PRIM_FILE='./archive_libs/logical/q_cap/chips/chips.prt';

PART_NAME
 C1769 'Q_CAP_0402-0.1UF,25V,10%,X7R,CA':;

SECTION_NUMBER 1
 '@S9S_MB_2U_LIB.S9S_MB_2U(SCH_1):PAGE140_I89@PURE_QUANTA.Q_CAP(CHIPS)':
 C_PATH='@s9s_mb_2u_lib.s9s_mb_2u(sch_1):page140_i89@pure_quanta.q_cap(chips)',
 P_PATH='@s9s_mb_2u_lib.s9s_mb_2u(sch_1):page151_i89@pure_quanta.q_cap(chips)',
 PATH='I89',
 DRAWING='@S9S_MB_2U_LIB.S9S_MB_2U(SCH_1):PAGE140',
 PHYS_PAGE='151',
 XY='(1625,3375)',
 ROT='0',
 VER='1',
 PACK_TYPE='0402',
 CDS_LIB='pure_quanta',
 CDS_PART_NAME='Q_CAP_0402-0.1UF,25V,10%,X7R,CA',
 TOLERANCE='10%',
 MATERIAL='X7R',
 VOLTAGE='25V',
 VALUE='0.1UF',
 PRIM_FILE='./archive_libs/logical/q_cap/chips/chips.prt';

PART_NAME
 C1770 'Q_CAP_0402-0.1UF,25V,10%,X7R,CA':;

SECTION_NUMBER 1
 '@S9S_MB_2U_LIB.S9S_MB_2U(SCH_1):PAGE140_I140@PURE_QUANTA.Q_CAP(CHIPS)':
 C_PATH='@s9s_mb_2u_lib.s9s_mb_2u(sch_1):page140_i140@pure_quanta.q_cap(chips)',
 P_PATH='@s9s_mb_2u_lib.s9s_mb_2u(sch_1):page151_i140@pure_quanta.q_cap(chips)',
 PATH='I140',
 DRAWING='@S9S_MB_2U_LIB.S9S_MB_2U(SCH_1):PAGE140',
 PHYS_PAGE='151',
 XY='(1625,975)',
 ROT='0',
 VER='1',
 PACK_TYPE='0402',
 CDS_LIB='pure_quanta',
 CDS_PART_NAME='Q_CAP_0402-0.1UF,25V,10%,X7R,CA',
 TOLERANCE='10%',
 MATERIAL='X7R',
 VOLTAGE='25V',
 VALUE='0.1UF',
 PRIM_FILE='./archive_libs/logical/q_cap/chips/chips.prt';

PART_NAME
 C1772 'Q_CAP_0402-1000PF,50V,5%,EMPTYA':;

SECTION_NUMBER 1
 '@S9S_MB_2U_LIB.S9S_MB_2U(SCH_1):PAGE145_I116@PURE_QUANTA.Q_CAP(CHIPS)':
 C_PATH='@s9s_mb_2u_lib.s9s_mb_2u(sch_1):page145_i116@pure_quanta.q_cap(chips)',
 P_PATH='@s9s_mb_2u_lib.s9s_mb_2u(sch_1):page148_i116@pure_quanta.q_cap(chips)',
 PATH='I116',
 DRAWING='@S9S_MB_2U_LIB.S9S_MB_2U(SCH_1):PAGE145',
 PHYS_PAGE='148',
 XY='(-1650,6275)',
 ROT='0',
 VER='1',
 PACK_TYPE='0402',
 CDS_LIB='pure_quanta',
 CDS_PART_NAME='Q_CAP_0402-1000PF,50V,5%,EMPTYA',
 TOLERANCE='5%',
 MATERIAL='EMPTY',
 VOLTAGE='50V',
 VALUE='1000PF',
 PRIM_FILE='./archive_libs/logical/q_cap/chips/chips.prt';

PART_NAME
 C1773 'Q_CAP_0402-1000PF,50V,5%,EMPTYA':;

SECTION_NUMBER 1
 '@S9S_MB_2U_LIB.S9S_MB_2U(SCH_1):PAGE145_I114@PURE_QUANTA.Q_CAP(CHIPS)':
 C_PATH='@s9s_mb_2u_lib.s9s_mb_2u(sch_1):page145_i114@pure_quanta.q_cap(chips)',
 P_PATH='@s9s_mb_2u_lib.s9s_mb_2u(sch_1):page148_i114@pure_quanta.q_cap(chips)',
 PATH='I114',
 DRAWING='@S9S_MB_2U_LIB.S9S_MB_2U(SCH_1):PAGE145',
 PHYS_PAGE='148',
 XY='(-1600,7650)',
 ROT='0',
 VER='1',
 PACK_TYPE='0402',
 CDS_LIB='pure_quanta',
 CDS_PART_NAME='Q_CAP_0402-1000PF,50V,5%,EMPTYA',
 TOLERANCE='5%',
 MATERIAL='EMPTY',
 VOLTAGE='50V',
 VALUE='1000PF',
 PRIM_FILE='./archive_libs/logical/q_cap/chips/chips.prt';

PART_NAME
 C1774 'Q_CAP_0402-1000PF,50V,5%,EMPTYA':;

SECTION_NUMBER 1
 '@S9S_MB_2U_LIB.S9S_MB_2U(SCH_1):PAGE145_I111@PURE_QUANTA.Q_CAP(CHIPS)':
 C_PATH='@s9s_mb_2u_lib.s9s_mb_2u(sch_1):page145_i111@pure_quanta.q_cap(chips)',
 P_PATH='@s9s_mb_2u_lib.s9s_mb_2u(sch_1):page148_i111@pure_quanta.q_cap(chips)',
 PATH='I111',
 DRAWING='@S9S_MB_2U_LIB.S9S_MB_2U(SCH_1):PAGE145',
 PHYS_PAGE='148',
 XY='(2875,7775)',
 ROT='0',
 VER='1',
 PACK_TYPE='0402',
 CDS_LIB='pure_quanta',
 CDS_PART_NAME='Q_CAP_0402-1000PF,50V,5%,EMPTYA',
 TOLERANCE='5%',
 MATERIAL='EMPTY',
 VOLTAGE='50V',
 VALUE='1000PF',
 PRIM_FILE='./archive_libs/logical/q_cap/chips/chips.prt';

PART_NAME
 C1775 'Q_CAP_0402-0.1UF,25V,10%,X7R,CA':;

SECTION_NUMBER 1
 '@S9S_MB_2U_LIB.S9S_MB_2U(SCH_1):PAGE230_I14@PURE_QUANTA.Q_CAP(CHIPS)':
 C_PATH='@s9s_mb_2u_lib.s9s_mb_2u(sch_1):page230_i14@pure_quanta.q_cap(chips)',
 P_PATH='@s9s_mb_2u_lib.s9s_mb_2u(sch_1):page246_i14@pure_quanta.q_cap(chips)',
 PATH='I14',
 DRAWING='@S9S_MB_2U_LIB.S9S_MB_2U(SCH_1):PAGE230',
 PHYS_PAGE='246',
 XY='(925,2475)',
 ROT='0',
 VER='1',
 PACK_TYPE='0402',
 CDS_LIB='pure_quanta',
 CDS_PART_NAME='Q_CAP_0402-0.1UF,25V,10%,X7R,CA',
 TOLERANCE='10%',
 MATERIAL='X7R',
 VOLTAGE='25V',
 VALUE='0.1UF',
 PRIM_FILE='./archive_libs/logical/q_cap/chips/chips.prt';

PART_NAME
 C1791 'Q_CAP_DIFFBUS_C0201-DIFF BUS_0A':;

SECTION_NUMBER 1
 '@S9S_MB_2U_LIB.S9S_MB_2U(SCH_1):PAGE169_I36@PURE_QUANTA.Q_CAP_DIFFBUS(CHIPS)':
 C_PATH='@s9s_mb_2u_lib.s9s_mb_2u(sch_1):page169_i36@pure_quanta.q_cap_diffbus(c~
hips)',
 P_PATH='@s9s_mb_2u_lib.s9s_mb_2u(sch_1):page178_i36@pure_quanta.q_cap_diffbus(c~
hips)',
 PATH='I36',
 DRAWING='@S9S_MB_2U_LIB.S9S_MB_2U(SCH_1):PAGE169',
 PIN_NAMES_ROTATE='TRUE',
 PHYS_PAGE='178',
 XY='(-725,1525)',
 ROT='2',
 VER='2',
 PACK_TYPE='C0201',
 CDS_LIB='pure_quanta',
 CDS_PART_NAME='Q_CAP_DIFFBUS_C0201-DIFF BUS_0A',
 TOLERANCE='20%',
 MATERIAL='X6S',
 VOLTAGE='6.3V',
 VALUE='DIFF BUS_0.22UF',
 PRIM_FILE='./archive_libs/logical/q_cap_diffbus/chips/chips.prt';

PART_NAME
 C1792 'Q_CAP_DIFFBUS_C0201-DIFF BUS_0A':;

SECTION_NUMBER 1
 '@S9S_MB_2U_LIB.S9S_MB_2U(SCH_1):PAGE166_I271@PURE_QUANTA.Q_CAP_DIFFBUS(CHIPS)':
 C_PATH='@s9s_mb_2u_lib.s9s_mb_2u(sch_1):page166_i271@pure_quanta.q_cap_diffbus(~
chips)',
 P_PATH='@s9s_mb_2u_lib.s9s_mb_2u(sch_1):page175_i271@pure_quanta.q_cap_diffbus(~
chips)',
 PATH='I271',
 DRAWING='@S9S_MB_2U_LIB.S9S_MB_2U(SCH_1):PAGE166',
 PIN_NAMES_ROTATE='TRUE',
 PHYS_PAGE='175',
 XY='(-925,3325)',
 ROT='2',
 VER='2',
 PACK_TYPE='C0201',
 CDS_LIB='pure_quanta',
 CDS_PART_NAME='Q_CAP_DIFFBUS_C0201-DIFF BUS_0A',
 TOLERANCE='20%',
 MATERIAL='X6S',
 VOLTAGE='6.3V',
 VALUE='DIFF BUS_0.22UF',
 PRIM_FILE='./archive_libs/logical/q_cap_diffbus/chips/chips.prt';

PART_NAME
 C1793 'Q_CAP_DIFFBUS_C0201-DIFF BUS_0A':;

SECTION_NUMBER 1
 '@S9S_MB_2U_LIB.S9S_MB_2U(SCH_1):PAGE166_I261@PURE_QUANTA.Q_CAP_DIFFBUS(CHIPS)':
 C_PATH='@s9s_mb_2u_lib.s9s_mb_2u(sch_1):page166_i261@pure_quanta.q_cap_diffbus(~
chips)',
 P_PATH='@s9s_mb_2u_lib.s9s_mb_2u(sch_1):page175_i261@pure_quanta.q_cap_diffbus(~
chips)',
 PATH='I261',
 DRAWING='@S9S_MB_2U_LIB.S9S_MB_2U(SCH_1):PAGE166',
 PIN_NAMES_ROTATE='TRUE',
 PHYS_PAGE='175',
 XY='(-925,2325)',
 ROT='2',
 VER='2',
 PACK_TYPE='C0201',
 CDS_LIB='pure_quanta',
 CDS_PART_NAME='Q_CAP_DIFFBUS_C0201-DIFF BUS_0A',
 TOLERANCE='20%',
 MATERIAL='X6S',
 VOLTAGE='6.3V',
 VALUE='DIFF BUS_0.22UF',
 PRIM_FILE='./archive_libs/logical/q_cap_diffbus/chips/chips.prt';

PART_NAME
 C1794 'Q_CAP_DIFFBUS_C0201-DIFF BUS_0A':;

SECTION_NUMBER 1
 '@S9S_MB_2U_LIB.S9S_MB_2U(SCH_1):PAGE166_I260@PURE_QUANTA.Q_CAP_DIFFBUS(CHIPS)':
 C_PATH='@s9s_mb_2u_lib.s9s_mb_2u(sch_1):page166_i260@pure_quanta.q_cap_diffbus(~
chips)',
 P_PATH='@s9s_mb_2u_lib.s9s_mb_2u(sch_1):page175_i260@pure_quanta.q_cap_diffbus(~
chips)',
 PATH='I260',
 DRAWING='@S9S_MB_2U_LIB.S9S_MB_2U(SCH_1):PAGE166',
 PIN_NAMES_ROTATE='TRUE',
 PHYS_PAGE='175',
 XY='(-925,2175)',
 ROT='2',
 VER='2',
 PACK_TYPE='C0201',
 CDS_LIB='pure_quanta',
 CDS_PART_NAME='Q_CAP_DIFFBUS_C0201-DIFF BUS_0A',
 TOLERANCE='20%',
 MATERIAL='X6S',
 VOLTAGE='6.3V',
 VALUE='DIFF BUS_0.22UF',
 PRIM_FILE='./archive_libs/logical/q_cap_diffbus/chips/chips.prt';

PART_NAME
 C1796 'Q_CAP_0402-0.1UF,25V,10%,X7R,CA':;

SECTION_NUMBER 1
 '@S9S_MB_2U_LIB.S9S_MB_2U(SCH_1):PAGE222_I20@PURE_QUANTA.Q_CAP(CHIPS)':
 C_PATH='@s9s_mb_2u_lib.s9s_mb_2u(sch_1):page222_i20@pure_quanta.q_cap(chips)',
 P_PATH='@s9s_mb_2u_lib.s9s_mb_2u(sch_1):page234_i20@pure_quanta.q_cap(chips)',
 PATH='I20',
 DRAWING='@S9S_MB_2U_LIB.S9S_MB_2U(SCH_1):PAGE222',
 PHYS_PAGE='234',
 XY='(-4125,6425)',
 ROT='0',
 VER='1',
 PACK_TYPE='0402',
 CDS_LIB='pure_quanta',
 CDS_PART_NAME='Q_CAP_0402-0.1UF,25V,10%,X7R,CA',
 TOLERANCE='10%',
 MATERIAL='X7R',
 VOLTAGE='25V',
 VALUE='0.1UF',
 PRIM_FILE='./archive_libs/logical/q_cap/chips/chips.prt';

PART_NAME
 C1797 'Q_CAP_0402-0.1UF,25V,10%,X7R,CA':;

SECTION_NUMBER 1
 '@S9S_MB_2U_LIB.S9S_MB_2U(SCH_1):PAGE303_I3@PURE_QUANTA.Q_CAP(CHIPS)':
 C_PATH='@s9s_mb_2u_lib.s9s_mb_2u(sch_1):page303_i3@pure_quanta.q_cap(chips)',
 P_PATH='@s9s_mb_2u_lib.s9s_mb_2u(sch_1):page301_i3@pure_quanta.q_cap(chips)',
 PATH='I3',
 DRAWING='@S9S_MB_2U_LIB.S9S_MB_2U(SCH_1):PAGE303',
 PHYS_PAGE='301',
 XY='(-17225,400)',
 ROT='0',
 VER='1',
 PACK_TYPE='0402',
 LOCATION='C1797',
 CDS_LIB='pure_quanta',
 CDS_PART_NAME='Q_CAP_0402-0.1UF,25V,10%,X7R,CA',
 TOLERANCE='10%',
 MATERIAL='X7R',
 VOLTAGE='25V',
 VALUE='0.1UF',
 PRIM_FILE='./archive_libs/logical/q_cap/chips/chips.prt';

PART_NAME
 C1802 'Q_CAP_0402-1000PF,50V,5%,EMPTYA':;

SECTION_NUMBER 1
 '@S9S_MB_2U_LIB.S9S_MB_2U(SCH_1):PAGE145_I148@PURE_QUANTA.Q_CAP(CHIPS)':
 C_PATH='@s9s_mb_2u_lib.s9s_mb_2u(sch_1):page145_i148@pure_quanta.q_cap(chips)',
 P_PATH='@s9s_mb_2u_lib.s9s_mb_2u(sch_1):page148_i148@pure_quanta.q_cap(chips)',
 PATH='I148',
 DRAWING='@S9S_MB_2U_LIB.S9S_MB_2U(SCH_1):PAGE145',
 PHYS_PAGE='148',
 XY='(-1600,3175)',
 ROT='0',
 VER='1',
 PACK_TYPE='0402',
 CDS_LIB='pure_quanta',
 CDS_PART_NAME='Q_CAP_0402-1000PF,50V,5%,EMPTYA',
 TOLERANCE='5%',
 MATERIAL='EMPTY',
 VOLTAGE='50V',
 VALUE='1000PF',
 PRIM_FILE='./archive_libs/logical/q_cap/chips/chips.prt';

PART_NAME
 C1803 'Q_CAP_0402-0.1UF,25V,10%,X7R,CA':;

SECTION_NUMBER 1
 '@S9S_MB_2U_LIB.S9S_MB_2U(SCH_1):PAGE140_I166@PURE_QUANTA.Q_CAP(CHIPS)':
 C_PATH='@s9s_mb_2u_lib.s9s_mb_2u(sch_1):page140_i166@pure_quanta.q_cap(chips)',
 P_PATH='@s9s_mb_2u_lib.s9s_mb_2u(sch_1):page151_i166@pure_quanta.q_cap(chips)',
 PATH='I166',
 DRAWING='@S9S_MB_2U_LIB.S9S_MB_2U(SCH_1):PAGE140',
 PHYS_PAGE='151',
 XY='(-325,-1375)',
 ROT='0',
 VER='1',
 PACK_TYPE='0402',
 CDS_LIB='pure_quanta',
 CDS_PART_NAME='Q_CAP_0402-0.1UF,25V,10%,X7R,CA',
 TOLERANCE='10%',
 MATERIAL='X7R',
 VOLTAGE='25V',
 VALUE='0.1UF',
 PRIM_FILE='./archive_libs/logical/q_cap/chips/chips.prt';

PART_NAME
 C1804 'Q_CAP_0402-1000PF,50V,5%,EMPTYA':;

SECTION_NUMBER 1
 '@S9S_MB_2U_LIB.S9S_MB_2U(SCH_1):PAGE145_I125@PURE_QUANTA.Q_CAP(CHIPS)':
 C_PATH='@s9s_mb_2u_lib.s9s_mb_2u(sch_1):page145_i125@pure_quanta.q_cap(chips)',
 P_PATH='@s9s_mb_2u_lib.s9s_mb_2u(sch_1):page148_i125@pure_quanta.q_cap(chips)',
 PATH='I125',
 DRAWING='@S9S_MB_2U_LIB.S9S_MB_2U(SCH_1):PAGE145',
 PHYS_PAGE='148',
 XY='(2950,4875)',
 ROT='0',
 VER='1',
 PACK_TYPE='0402',
 CDS_LIB='pure_quanta',
 CDS_PART_NAME='Q_CAP_0402-1000PF,50V,5%,EMPTYA',
 TOLERANCE='5%',
 MATERIAL='EMPTY',
 VOLTAGE='50V',
 VALUE='1000PF',
 PRIM_FILE='./archive_libs/logical/q_cap/chips/chips.prt';

PART_NAME
 C1809 'Q_CAP_0402-0.1UF,25V,10%,X7R,CA':;

SECTION_NUMBER 1
 '@S9S_MB_2U_LIB.S9S_MB_2U(SCH_1):PAGE131_I26@PURE_QUANTA.Q_CAP(CHIPS)':
 C_PATH='@s9s_mb_2u_lib.s9s_mb_2u(sch_1):page131_i26@pure_quanta.q_cap(chips)',
 P_PATH='@s9s_mb_2u_lib.s9s_mb_2u(sch_1):page162_i26@pure_quanta.q_cap(chips)',
 PATH='I26',
 DRAWING='@S9S_MB_2U_LIB.S9S_MB_2U(SCH_1):PAGE131',
 PHYS_PAGE='162',
 XY='(-500,-1925)',
 ROT='0',
 VER='1',
 PACK_TYPE='0402',
 CDS_LIB='pure_quanta',
 CDS_PART_NAME='Q_CAP_0402-0.1UF,25V,10%,X7R,CA',
 TOLERANCE='10%',
 MATERIAL='X7R',
 VOLTAGE='25V',
 VALUE='0.1UF',
 PRIM_FILE='./archive_libs/logical/q_cap/chips/chips.prt';

PART_NAME
 C1810 'Q_CAP_0402-0.1UF,25V,10%,X7R,CA':;

SECTION_NUMBER 1
 '@S9S_MB_2U_LIB.S9S_MB_2U(SCH_1):PAGE131_I21@PURE_QUANTA.Q_CAP(CHIPS)':
 C_PATH='@s9s_mb_2u_lib.s9s_mb_2u(sch_1):page131_i21@pure_quanta.q_cap(chips)',
 P_PATH='@s9s_mb_2u_lib.s9s_mb_2u(sch_1):page162_i21@pure_quanta.q_cap(chips)',
 PATH='I21',
 DRAWING='@S9S_MB_2U_LIB.S9S_MB_2U(SCH_1):PAGE131',
 PHYS_PAGE='162',
 XY='(-500,-2825)',
 ROT='0',
 VER='1',
 PACK_TYPE='0402',
 CDS_LIB='pure_quanta',
 CDS_PART_NAME='Q_CAP_0402-0.1UF,25V,10%,X7R,CA',
 TOLERANCE='10%',
 MATERIAL='X7R',
 VOLTAGE='25V',
 VALUE='0.1UF',
 PRIM_FILE='./archive_libs/logical/q_cap/chips/chips.prt';

PART_NAME
 C1817 'Q_CAP_0402-0.1UF,25V,10%,X7R,CA':;

SECTION_NUMBER 1
 '@S9S_MB_2U_LIB.S9S_MB_2U(SCH_1):PAGE132_I39@PURE_QUANTA.Q_CAP(CHIPS)':
 C_PATH='@s9s_mb_2u_lib.s9s_mb_2u(sch_1):page132_i39@pure_quanta.q_cap(chips)',
 P_PATH='@s9s_mb_2u_lib.s9s_mb_2u(sch_1):page164_i39@pure_quanta.q_cap(chips)',
 PATH='I39',
 DRAWING='@S9S_MB_2U_LIB.S9S_MB_2U(SCH_1):PAGE132',
 PHYS_PAGE='164',
 XY='(-2825,3775)',
 ROT='0',
 VER='1',
 PACK_TYPE='0402',
 CDS_LIB='pure_quanta',
 CDS_PART_NAME='Q_CAP_0402-0.1UF,25V,10%,X7R,CA',
 TOLERANCE='10%',
 MATERIAL='X7R',
 VOLTAGE='25V',
 VALUE='0.1UF',
 PRIM_FILE='./archive_libs/logical/q_cap/chips/chips.prt';

PART_NAME
 C1818 'Q_CAP_0402-0.1UF,25V,10%,X7R,CA':;

SECTION_NUMBER 1
 '@S9S_MB_2U_LIB.S9S_MB_2U(SCH_1):PAGE132_I15@PURE_QUANTA.Q_CAP(CHIPS)':
 C_PATH='@s9s_mb_2u_lib.s9s_mb_2u(sch_1):page132_i15@pure_quanta.q_cap(chips)',
 P_PATH='@s9s_mb_2u_lib.s9s_mb_2u(sch_1):page164_i15@pure_quanta.q_cap(chips)',
 PATH='I15',
 DRAWING='@S9S_MB_2U_LIB.S9S_MB_2U(SCH_1):PAGE132',
 PHYS_PAGE='164',
 XY='(-2600,-650)',
 ROT='0',
 VER='1',
 PACK_TYPE='0402',
 CDS_LIB='pure_quanta',
 CDS_PART_NAME='Q_CAP_0402-0.1UF,25V,10%,X7R,CA',
 TOLERANCE='10%',
 MATERIAL='X7R',
 VOLTAGE='25V',
 VALUE='0.1UF',
 PRIM_FILE='./archive_libs/logical/q_cap/chips/chips.prt';

PART_NAME
 C1819 'Q_CAP_0402-0.1UF,25V,10%,X7R,CA':;

SECTION_NUMBER 1
 '@S9S_MB_2U_LIB.S9S_MB_2U(SCH_1):PAGE132_I87@PURE_QUANTA.Q_CAP(CHIPS)':
 C_PATH='@s9s_mb_2u_lib.s9s_mb_2u(sch_1):page132_i87@pure_quanta.q_cap(chips)',
 P_PATH='@s9s_mb_2u_lib.s9s_mb_2u(sch_1):page164_i87@pure_quanta.q_cap(chips)',
 PATH='I87',
 DRAWING='@S9S_MB_2U_LIB.S9S_MB_2U(SCH_1):PAGE132',
 PHYS_PAGE='164',
 XY='(-4500,1025)',
 ROT='2',
 VER='1',
 PACK_TYPE='0402',
 CDS_LIB='pure_quanta',
 CDS_PART_NAME='Q_CAP_0402-0.1UF,25V,10%,X7R,CA',
 TOLERANCE='10%',
 MATERIAL='X7R',
 VOLTAGE='25V',
 VALUE='0.1UF',
 PRIM_FILE='./archive_libs/logical/q_cap/chips/chips.prt';

PART_NAME
 C1820 'Q_CAP_0402-0.1UF,25V,10%,X7R,CA':;

SECTION_NUMBER 1
 '@S9S_MB_2U_LIB.S9S_MB_2U(SCH_1):PAGE132_I58@PURE_QUANTA.Q_CAP(CHIPS)':
 C_PATH='@s9s_mb_2u_lib.s9s_mb_2u(sch_1):page132_i58@pure_quanta.q_cap(chips)',
 P_PATH='@s9s_mb_2u_lib.s9s_mb_2u(sch_1):page164_i58@pure_quanta.q_cap(chips)',
 PATH='I58',
 DRAWING='@S9S_MB_2U_LIB.S9S_MB_2U(SCH_1):PAGE132',
 PHYS_PAGE='164',
 XY='(2625,1350)',
 ROT='0',
 VER='1',
 PACK_TYPE='0402',
 CDS_LIB='pure_quanta',
 CDS_PART_NAME='Q_CAP_0402-0.1UF,25V,10%,X7R,CA',
 TOLERANCE='10%',
 MATERIAL='X7R',
 VOLTAGE='25V',
 VALUE='0.1UF',
 PRIM_FILE='./archive_libs/logical/q_cap/chips/chips.prt';

PART_NAME
 C1821 'Q_CAP_0402-0.1UF,25V,10%,X7R,CA':;

SECTION_NUMBER 1
 '@S9S_MB_2U_LIB.S9S_MB_2U(SCH_1):PAGE156_I12@PURE_QUANTA.Q_CAP(CHIPS)':
 C_PATH='@s9s_mb_2u_lib.s9s_mb_2u(sch_1):page156_i12@pure_quanta.q_cap(chips)',
 P_PATH='@s9s_mb_2u_lib.s9s_mb_2u(sch_1):page161_i12@pure_quanta.q_cap(chips)',
 PATH='I12',
 DRAWING='@S9S_MB_2U_LIB.S9S_MB_2U(SCH_1):PAGE156',
 PHYS_PAGE='161',
 XY='(5050,1425)',
 ROT='2',
 VER='1',
 PACK_TYPE='0402',
 CDS_LIB='pure_quanta',
 CDS_PART_NAME='Q_CAP_0402-0.1UF,25V,10%,X7R,CA',
 TOLERANCE='10%',
 MATERIAL='X7R',
 VOLTAGE='25V',
 VALUE='0.1UF',
 PRIM_FILE='./archive_libs/logical/q_cap/chips/chips.prt';

PART_NAME
 C1822 'Q_CAP_0402-0.1UF,25V,10%,X7R,CA':;

SECTION_NUMBER 1
 '@S9S_MB_2U_LIB.S9S_MB_2U(SCH_1):PAGE156_I27@PURE_QUANTA.Q_CAP(CHIPS)':
 C_PATH='@s9s_mb_2u_lib.s9s_mb_2u(sch_1):page156_i27@pure_quanta.q_cap(chips)',
 P_PATH='@s9s_mb_2u_lib.s9s_mb_2u(sch_1):page161_i27@pure_quanta.q_cap(chips)',
 PATH='I27',
 DRAWING='@S9S_MB_2U_LIB.S9S_MB_2U(SCH_1):PAGE156',
 PHYS_PAGE='161',
 XY='(5200,-1275)',
 ROT='0',
 VER='1',
 PACK_TYPE='0402',
 CDS_LIB='pure_quanta',
 CDS_PART_NAME='Q_CAP_0402-0.1UF,25V,10%,X7R,CA',
 TOLERANCE='10%',
 MATERIAL='X7R',
 VOLTAGE='25V',
 VALUE='0.1UF',
 PRIM_FILE='./archive_libs/logical/q_cap/chips/chips.prt';

PART_NAME
 C1823 'Q_CAP_0402-0.1UF,25V,10%,X7R,CA':;

SECTION_NUMBER 1
 '@S9S_MB_2U_LIB.S9S_MB_2U(SCH_1):PAGE156_I33@PURE_QUANTA.Q_CAP(CHIPS)':
 C_PATH='@s9s_mb_2u_lib.s9s_mb_2u(sch_1):page156_i33@pure_quanta.q_cap(chips)',
 P_PATH='@s9s_mb_2u_lib.s9s_mb_2u(sch_1):page161_i33@pure_quanta.q_cap(chips)',
 PATH='I33',
 DRAWING='@S9S_MB_2U_LIB.S9S_MB_2U(SCH_1):PAGE156',
 PHYS_PAGE='161',
 XY='(6500,-75)',
 ROT='0',
 VER='1',
 PACK_TYPE='0402',
 CDS_LIB='pure_quanta',
 CDS_PART_NAME='Q_CAP_0402-0.1UF,25V,10%,X7R,CA',
 TOLERANCE='10%',
 MATERIAL='X7R',
 VOLTAGE='25V',
 VALUE='0.1UF',
 PRIM_FILE='./archive_libs/logical/q_cap/chips/chips.prt';

PART_NAME
 C1824 'Q_CAP_0402-0.1UF,25V,10%,X7R,CA':;

SECTION_NUMBER 1
 '@S9S_MB_2U_LIB.S9S_MB_2U(SCH_1):PAGE156_I47@PURE_QUANTA.Q_CAP(CHIPS)':
 C_PATH='@s9s_mb_2u_lib.s9s_mb_2u(sch_1):page156_i47@pure_quanta.q_cap(chips)',
 P_PATH='@s9s_mb_2u_lib.s9s_mb_2u(sch_1):page161_i47@pure_quanta.q_cap(chips)',
 PATH='I47',
 DRAWING='@S9S_MB_2U_LIB.S9S_MB_2U(SCH_1):PAGE156',
 PHYS_PAGE='161',
 XY='(8750,-1500)',
 ROT='0',
 VER='1',
 PACK_TYPE='0402',
 CDS_LIB='pure_quanta',
 CDS_PART_NAME='Q_CAP_0402-0.1UF,25V,10%,X7R,CA',
 TOLERANCE='10%',
 MATERIAL='X7R',
 VOLTAGE='25V',
 VALUE='0.1UF',
 PRIM_FILE='./archive_libs/logical/q_cap/chips/chips.prt';

PART_NAME
 C1825 'Q_CAP_0402-0.1UF,25V,10%,X7R,CA':;

SECTION_NUMBER 1
 '@S9S_MB_2U_LIB.S9S_MB_2U(SCH_1):PAGE307_I17@PURE_QUANTA.Q_CAP(CHIPS)':
 C_PATH='@s9s_mb_2u_lib.s9s_mb_2u(sch_1):page307_i17@pure_quanta.q_cap(chips)',
 P_PATH='@s9s_mb_2u_lib.s9s_mb_2u(sch_1):page160_i17@pure_quanta.q_cap(chips)',
 PATH='I17',
 DRAWING='@S9S_MB_2U_LIB.S9S_MB_2U(SCH_1):PAGE307',
 PHYS_PAGE='160',
 XY='(-1600,-25)',
 ROT='2',
 VER='1',
 PACK_TYPE='0402',
 CDS_LIB='pure_quanta',
 CDS_PART_NAME='Q_CAP_0402-0.1UF,25V,10%,X7R,CA',
 TOLERANCE='10%',
 MATERIAL='X7R',
 VOLTAGE='25V',
 VALUE='0.1UF',
 PRIM_FILE='./archive_libs/logical/q_cap/chips/chips.prt';

PART_NAME
 C1826 'Q_CAP_0402-0.1UF,25V,10%,X7R,CA':;

SECTION_NUMBER 1
 '@S9S_MB_2U_LIB.S9S_MB_2U(SCH_1):PAGE307_I33@PURE_QUANTA.Q_CAP(CHIPS)':
 C_PATH='@s9s_mb_2u_lib.s9s_mb_2u(sch_1):page307_i33@pure_quanta.q_cap(chips)',
 P_PATH='@s9s_mb_2u_lib.s9s_mb_2u(sch_1):page160_i33@pure_quanta.q_cap(chips)',
 PATH='I33',
 DRAWING='@S9S_MB_2U_LIB.S9S_MB_2U(SCH_1):PAGE307',
 PHYS_PAGE='160',
 XY='(-525,2800)',
 ROT='2',
 VER='1',
 PACK_TYPE='0402',
 CDS_LIB='pure_quanta',
 CDS_PART_NAME='Q_CAP_0402-0.1UF,25V,10%,X7R,CA',
 TOLERANCE='10%',
 MATERIAL='X7R',
 VOLTAGE='25V',
 VALUE='0.1UF',
 PRIM_FILE='./archive_libs/logical/q_cap/chips/chips.prt';

PART_NAME
 C1827 'Q_CAP_0402-0.1UF,25V,10%,X7R,CA':;

SECTION_NUMBER 1
 '@S9S_MB_2U_LIB.S9S_MB_2U(SCH_1):PAGE307_I77@PURE_QUANTA.Q_CAP(CHIPS)':
 C_PATH='@s9s_mb_2u_lib.s9s_mb_2u(sch_1):page307_i77@pure_quanta.q_cap(chips)',
 P_PATH='@s9s_mb_2u_lib.s9s_mb_2u(sch_1):page160_i77@pure_quanta.q_cap(chips)',
 PATH='I77',
 DRAWING='@S9S_MB_2U_LIB.S9S_MB_2U(SCH_1):PAGE307',
 PHYS_PAGE='160',
 XY='(-525,1375)',
 ROT='2',
 VER='1',
 PACK_TYPE='0402',
 CDS_LIB='pure_quanta',
 CDS_PART_NAME='Q_CAP_0402-0.1UF,25V,10%,X7R,CA',
 TOLERANCE='10%',
 MATERIAL='X7R',
 VOLTAGE='25V',
 VALUE='0.1UF',
 PRIM_FILE='./archive_libs/logical/q_cap/chips/chips.prt';

PART_NAME
 C1829 'Q_CAP_C0805-22UF,16V,20%,X6S,CB':;

SECTION_NUMBER 1
 '@S9S_MB_2U_LIB.S9S_MB_2U(SCH_1):PAGE146_I166@PURE_QUANTA.Q_CAP(CHIPS)':
 C_PATH='@s9s_mb_2u_lib.s9s_mb_2u(sch_1):page146_i166@pure_quanta.q_cap(chips)',
 P_PATH='@s9s_mb_2u_lib.s9s_mb_2u(sch_1):page159_i166@pure_quanta.q_cap(chips)',
 PATH='I166',
 DRAWING='@S9S_MB_2U_LIB.S9S_MB_2U(SCH_1):PAGE146',
 PHYS_PAGE='159',
 XY='(5725,-250)',
 ROT='0',
 VER='1',
 PACK_TYPE='C0805',
 CDS_LIB='pure_quanta',
 CDS_PART_NAME='Q_CAP_C0805-22UF,16V,20%,X6S,CB',
 TOLERANCE='20%',
 MATERIAL='X6S',
 VOLTAGE='16V',
 VALUE='22UF',
 PRIM_FILE='./archive_libs/logical/q_cap/chips/chips.prt';

PART_NAME
 C1830 'Q_CAP_C0805-22UF,16V,20%,X6S,CB':;

SECTION_NUMBER 1
 '@S9S_MB_2U_LIB.S9S_MB_2U(SCH_1):PAGE146_I167@PURE_QUANTA.Q_CAP(CHIPS)':
 C_PATH='@s9s_mb_2u_lib.s9s_mb_2u(sch_1):page146_i167@pure_quanta.q_cap(chips)',
 P_PATH='@s9s_mb_2u_lib.s9s_mb_2u(sch_1):page159_i167@pure_quanta.q_cap(chips)',
 PATH='I167',
 DRAWING='@S9S_MB_2U_LIB.S9S_MB_2U(SCH_1):PAGE146',
 PHYS_PAGE='159',
 XY='(6000,-250)',
 ROT='0',
 VER='1',
 PACK_TYPE='C0805',
 CDS_LIB='pure_quanta',
 CDS_PART_NAME='Q_CAP_C0805-22UF,16V,20%,X6S,CB',
 TOLERANCE='20%',
 MATERIAL='X6S',
 VOLTAGE='16V',
 VALUE='22UF',
 PRIM_FILE='./archive_libs/logical/q_cap/chips/chips.prt';

PART_NAME
 C1831 'Q_CAP_0402-0.1UF,25V,10%,X7R,CA':;

SECTION_NUMBER 1
 '@S9S_MB_2U_LIB.S9S_MB_2U(SCH_1):PAGE146_I168@PURE_QUANTA.Q_CAP(CHIPS)':
 C_PATH='@s9s_mb_2u_lib.s9s_mb_2u(sch_1):page146_i168@pure_quanta.q_cap(chips)',
 P_PATH='@s9s_mb_2u_lib.s9s_mb_2u(sch_1):page159_i168@pure_quanta.q_cap(chips)',
 PATH='I168',
 DRAWING='@S9S_MB_2U_LIB.S9S_MB_2U(SCH_1):PAGE146',
 PHYS_PAGE='159',
 XY='(6400,-250)',
 ROT='0',
 VER='1',
 PACK_TYPE='0402',
 CDS_LIB='pure_quanta',
 CDS_PART_NAME='Q_CAP_0402-0.1UF,25V,10%,X7R,CA',
 TOLERANCE='10%',
 MATERIAL='X7R',
 VOLTAGE='25V',
 VALUE='0.1UF',
 PRIM_FILE='./archive_libs/logical/q_cap/chips/chips.prt';

PART_NAME
 C1832 'Q_CAP_0402-0.1UF,25V,10%,X7R,CA':;

SECTION_NUMBER 1
 '@S9S_MB_2U_LIB.S9S_MB_2U(SCH_1):PAGE146_I179@PURE_QUANTA.Q_CAP(CHIPS)':
 C_PATH='@s9s_mb_2u_lib.s9s_mb_2u(sch_1):page146_i179@pure_quanta.q_cap(chips)',
 P_PATH='@s9s_mb_2u_lib.s9s_mb_2u(sch_1):page159_i179@pure_quanta.q_cap(chips)',
 PATH='I179',
 DRAWING='@S9S_MB_2U_LIB.S9S_MB_2U(SCH_1):PAGE146',
 PHYS_PAGE='159',
 XY='(6675,-250)',
 ROT='0',
 VER='1',
 PACK_TYPE='0402',
 CDS_LIB='pure_quanta',
 CDS_PART_NAME='Q_CAP_0402-0.1UF,25V,10%,X7R,CA',
 TOLERANCE='10%',
 MATERIAL='X7R',
 VOLTAGE='25V',
 VALUE='0.1UF',
 PRIM_FILE='./archive_libs/logical/q_cap/chips/chips.prt';

PART_NAME
 C1833 'Q_CAP_0402-0.1UF,25V,10%,X7R,CA':;

SECTION_NUMBER 1
 '@S9S_MB_2U_LIB.S9S_MB_2U(SCH_1):PAGE146_I169@PURE_QUANTA.Q_CAP(CHIPS)':
 C_PATH='@s9s_mb_2u_lib.s9s_mb_2u(sch_1):page146_i169@pure_quanta.q_cap(chips)',
 P_PATH='@s9s_mb_2u_lib.s9s_mb_2u(sch_1):page159_i169@pure_quanta.q_cap(chips)',
 PATH='I169',
 DRAWING='@S9S_MB_2U_LIB.S9S_MB_2U(SCH_1):PAGE146',
 PHYS_PAGE='159',
 XY='(6950,-250)',
 ROT='0',
 VER='1',
 PACK_TYPE='0402',
 CDS_LIB='pure_quanta',
 CDS_PART_NAME='Q_CAP_0402-0.1UF,25V,10%,X7R,CA',
 TOLERANCE='10%',
 MATERIAL='X7R',
 VOLTAGE='25V',
 VALUE='0.1UF',
 PRIM_FILE='./archive_libs/logical/q_cap/chips/chips.prt';

PART_NAME
 C1834 'Q_CAP_0402-0.1UF,25V,10%,X7R,CA':;

SECTION_NUMBER 1
 '@S9S_MB_2U_LIB.S9S_MB_2U(SCH_1):PAGE146_I171@PURE_QUANTA.Q_CAP(CHIPS)':
 C_PATH='@s9s_mb_2u_lib.s9s_mb_2u(sch_1):page146_i171@pure_quanta.q_cap(chips)',
 P_PATH='@s9s_mb_2u_lib.s9s_mb_2u(sch_1):page159_i171@pure_quanta.q_cap(chips)',
 PATH='I171',
 DRAWING='@S9S_MB_2U_LIB.S9S_MB_2U(SCH_1):PAGE146',
 PHYS_PAGE='159',
 XY='(7425,-250)',
 ROT='0',
 VER='1',
 PACK_TYPE='0402',
 CDS_LIB='pure_quanta',
 CDS_PART_NAME='Q_CAP_0402-0.1UF,25V,10%,X7R,CA',
 TOLERANCE='10%',
 MATERIAL='X7R',
 VOLTAGE='25V',
 VALUE='0.1UF',
 PRIM_FILE='./archive_libs/logical/q_cap/chips/chips.prt';

PART_NAME
 C1835 'Q_CAP_0402-0.1UF,25V,10%,X7R,CA':;

SECTION_NUMBER 1
 '@S9S_MB_2U_LIB.S9S_MB_2U(SCH_1):PAGE146_I173@PURE_QUANTA.Q_CAP(CHIPS)':
 C_PATH='@s9s_mb_2u_lib.s9s_mb_2u(sch_1):page146_i173@pure_quanta.q_cap(chips)',
 P_PATH='@s9s_mb_2u_lib.s9s_mb_2u(sch_1):page159_i173@pure_quanta.q_cap(chips)',
 PATH='I173',
 DRAWING='@S9S_MB_2U_LIB.S9S_MB_2U(SCH_1):PAGE146',
 PHYS_PAGE='159',
 XY='(7925,-250)',
 ROT='0',
 VER='1',
 PACK_TYPE='0402',
 CDS_LIB='pure_quanta',
 CDS_PART_NAME='Q_CAP_0402-0.1UF,25V,10%,X7R,CA',
 TOLERANCE='10%',
 MATERIAL='X7R',
 VOLTAGE='25V',
 VALUE='0.1UF',
 PRIM_FILE='./archive_libs/logical/q_cap/chips/chips.prt';

PART_NAME
 C1836 'Q_CAP_0402-0.1UF,25V,10%,X7R,CA':;

SECTION_NUMBER 1
 '@S9S_MB_2U_LIB.S9S_MB_2U(SCH_1):PAGE146_I174@PURE_QUANTA.Q_CAP(CHIPS)':
 C_PATH='@s9s_mb_2u_lib.s9s_mb_2u(sch_1):page146_i174@pure_quanta.q_cap(chips)',
 P_PATH='@s9s_mb_2u_lib.s9s_mb_2u(sch_1):page159_i174@pure_quanta.q_cap(chips)',
 PATH='I174',
 DRAWING='@S9S_MB_2U_LIB.S9S_MB_2U(SCH_1):PAGE146',
 PHYS_PAGE='159',
 XY='(8175,-250)',
 ROT='0',
 VER='1',
 PACK_TYPE='0402',
 CDS_LIB='pure_quanta',
 CDS_PART_NAME='Q_CAP_0402-0.1UF,25V,10%,X7R,CA',
 TOLERANCE='10%',
 MATERIAL='X7R',
 VOLTAGE='25V',
 VALUE='0.1UF',
 PRIM_FILE='./archive_libs/logical/q_cap/chips/chips.prt';

PART_NAME
 C1837 'Q_CAP_0402-0.1UF,25V,10%,X7R,CA':;

SECTION_NUMBER 1
 '@S9S_MB_2U_LIB.S9S_MB_2U(SCH_1):PAGE146_I175@PURE_QUANTA.Q_CAP(CHIPS)':
 C_PATH='@s9s_mb_2u_lib.s9s_mb_2u(sch_1):page146_i175@pure_quanta.q_cap(chips)',
 P_PATH='@s9s_mb_2u_lib.s9s_mb_2u(sch_1):page159_i175@pure_quanta.q_cap(chips)',
 PATH='I175',
 DRAWING='@S9S_MB_2U_LIB.S9S_MB_2U(SCH_1):PAGE146',
 PHYS_PAGE='159',
 XY='(8450,-250)',
 ROT='0',
 VER='1',
 PACK_TYPE='0402',
 CDS_LIB='pure_quanta',
 CDS_PART_NAME='Q_CAP_0402-0.1UF,25V,10%,X7R,CA',
 TOLERANCE='10%',
 MATERIAL='X7R',
 VOLTAGE='25V',
 VALUE='0.1UF',
 PRIM_FILE='./archive_libs/logical/q_cap/chips/chips.prt';

PART_NAME
 C1838 'Q_CAP_0402-0.1UF,25V,10%,X7R,CA':;

SECTION_NUMBER 1
 '@S9S_MB_2U_LIB.S9S_MB_2U(SCH_1):PAGE146_I177@PURE_QUANTA.Q_CAP(CHIPS)':
 C_PATH='@s9s_mb_2u_lib.s9s_mb_2u(sch_1):page146_i177@pure_quanta.q_cap(chips)',
 P_PATH='@s9s_mb_2u_lib.s9s_mb_2u(sch_1):page159_i177@pure_quanta.q_cap(chips)',
 PATH='I177',
 DRAWING='@S9S_MB_2U_LIB.S9S_MB_2U(SCH_1):PAGE146',
 PHYS_PAGE='159',
 XY='(8725,-250)',
 ROT='0',
 VER='1',
 PACK_TYPE='0402',
 CDS_LIB='pure_quanta',
 CDS_PART_NAME='Q_CAP_0402-0.1UF,25V,10%,X7R,CA',
 TOLERANCE='10%',
 MATERIAL='X7R',
 VOLTAGE='25V',
 VALUE='0.1UF',
 PRIM_FILE='./archive_libs/logical/q_cap/chips/chips.prt';

PART_NAME
 C1839 'Q_CAP_0402-0.1UF,25V,10%,X7R,CA':;

SECTION_NUMBER 1
 '@S9S_MB_2U_LIB.S9S_MB_2U(SCH_1):PAGE146_I180@PURE_QUANTA.Q_CAP(CHIPS)':
 C_PATH='@s9s_mb_2u_lib.s9s_mb_2u(sch_1):page146_i180@pure_quanta.q_cap(chips)',
 P_PATH='@s9s_mb_2u_lib.s9s_mb_2u(sch_1):page159_i180@pure_quanta.q_cap(chips)',
 PATH='I180',
 DRAWING='@S9S_MB_2U_LIB.S9S_MB_2U(SCH_1):PAGE146',
 PHYS_PAGE='159',
 XY='(7175,-250)',
 ROT='0',
 VER='1',
 PACK_TYPE='0402',
 CDS_LIB='pure_quanta',
 CDS_PART_NAME='Q_CAP_0402-0.1UF,25V,10%,X7R,CA',
 TOLERANCE='10%',
 MATERIAL='X7R',
 VOLTAGE='25V',
 VALUE='0.1UF',
 PRIM_FILE='./archive_libs/logical/q_cap/chips/chips.prt';

PART_NAME
 C1840 'Q_CAP_0402-0.1UF,25V,10%,X7R,CA':;

SECTION_NUMBER 1
 '@S9S_MB_2U_LIB.S9S_MB_2U(SCH_1):PAGE151_I8@PURE_QUANTA.Q_CAP(CHIPS)':
 C_PATH='@s9s_mb_2u_lib.s9s_mb_2u(sch_1):page151_i8@pure_quanta.q_cap(chips)',
 P_PATH='@s9s_mb_2u_lib.s9s_mb_2u(sch_1):page154_i8@pure_quanta.q_cap(chips)',
 PATH='I8',
 DRAWING='@S9S_MB_2U_LIB.S9S_MB_2U(SCH_1):PAGE151',
 PHYS_PAGE='154',
 XY='(-3750,2425)',
 ROT='2',
 VER='1',
 PACK_TYPE='0402',
 CDS_LIB='pure_quanta',
 CDS_PART_NAME='Q_CAP_0402-0.1UF,25V,10%,X7R,CA',
 TOLERANCE='10%',
 MATERIAL='X7R',
 VOLTAGE='25V',
 VALUE='0.1UF',
 PRIM_FILE='./archive_libs/logical/q_cap/chips/chips.prt';

PART_NAME
 C1841 'Q_CAP_0402-0.1UF,25V,10%,X7R,CA':;

SECTION_NUMBER 1
 '@S9S_MB_2U_LIB.S9S_MB_2U(SCH_1):PAGE156_I65@PURE_QUANTA.Q_CAP(CHIPS)':
 C_PATH='@s9s_mb_2u_lib.s9s_mb_2u(sch_1):page156_i65@pure_quanta.q_cap(chips)',
 P_PATH='@s9s_mb_2u_lib.s9s_mb_2u(sch_1):page161_i65@pure_quanta.q_cap(chips)',
 PATH='I65',
 DRAWING='@S9S_MB_2U_LIB.S9S_MB_2U(SCH_1):PAGE156',
 PHYS_PAGE='161',
 XY='(5700,-2750)',
 ROT='2',
 VER='1',
 PACK_TYPE='0402',
 CDS_LIB='pure_quanta',
 CDS_PART_NAME='Q_CAP_0402-0.1UF,25V,10%,X7R,CA',
 TOLERANCE='10%',
 MATERIAL='X7R',
 VOLTAGE='25V',
 VALUE='0.1UF',
 PRIM_FILE='./archive_libs/logical/q_cap/chips/chips.prt';

PART_NAME
 C1842 'Q_CAP_C0402-10UF,6.3V,20%,X6S,A':;

SECTION_NUMBER 1
 '@S9S_MB_2U_LIB.S9S_MB_2U(SCH_1):PAGE202_I107@PURE_QUANTA.Q_CAP(CHIPS)':
 C_PATH='@s9s_mb_2u_lib.s9s_mb_2u(sch_1):page202_i107@pure_quanta.q_cap(chips)',
 P_PATH='@s9s_mb_2u_lib.s9s_mb_2u(sch_1):page217_i107@pure_quanta.q_cap(chips)',
 PATH='I107',
 DRAWING='@S9S_MB_2U_LIB.S9S_MB_2U(SCH_1):PAGE202',
 PHYS_PAGE='217',
 XY='(-5150,-2100)',
 ROT='0',
 VER='1',
 PACK_TYPE='C0402',
 CDS_LIB='pure_quanta',
 CDS_PART_NAME='Q_CAP_C0402-10UF,6.3V,20%,X6S,A',
 TOLERANCE='20%',
 MATERIAL='X6S',
 VOLTAGE='6.3V',
 VALUE='10UF',
 PRIM_FILE='./archive_libs/logical/q_cap/chips/chips.prt';

PART_NAME
 C1859 'Q_CAP_0402-0.1UF,25V,10%,X7R,CA':;

SECTION_NUMBER 1
 '@S9S_MB_2U_LIB.S9S_MB_2U(SCH_1):PAGE216_I10@PURE_QUANTA.Q_CAP(CHIPS)':
 C_PATH='@s9s_mb_2u_lib.s9s_mb_2u(sch_1):page216_i10@pure_quanta.q_cap(chips)',
 P_PATH='@s9s_mb_2u_lib.s9s_mb_2u(sch_1):page238_i10@pure_quanta.q_cap(chips)',
 PATH='I10',
 DRAWING='@S9S_MB_2U_LIB.S9S_MB_2U(SCH_1):PAGE216',
 PHYS_PAGE='238',
 XY='(-8075,3900)',
 ROT='0',
 VER='1',
 PACK_TYPE='0402',
 CDS_LIB='pure_quanta',
 CDS_PART_NAME='Q_CAP_0402-0.1UF,25V,10%,X7R,CA',
 TOLERANCE='10%',
 MATERIAL='X7R',
 VOLTAGE='25V',
 VALUE='0.1UF',
 PRIM_FILE='./archive_libs/logical/q_cap/chips/chips.prt';

PART_NAME
 C1860 'Q_CAP_0402-0.1UF,25V,10%,X7R,CA':;

SECTION_NUMBER 1
 '@S9S_MB_2U_LIB.S9S_MB_2U(SCH_1):PAGE216_I17@PURE_QUANTA.Q_CAP(CHIPS)':
 C_PATH='@s9s_mb_2u_lib.s9s_mb_2u(sch_1):page216_i17@pure_quanta.q_cap(chips)',
 P_PATH='@s9s_mb_2u_lib.s9s_mb_2u(sch_1):page238_i17@pure_quanta.q_cap(chips)',
 PATH='I17',
 DRAWING='@S9S_MB_2U_LIB.S9S_MB_2U(SCH_1):PAGE216',
 PHYS_PAGE='238',
 XY='(-8050,5725)',
 ROT='0',
 VER='1',
 PACK_TYPE='0402',
 CDS_LIB='pure_quanta',
 CDS_PART_NAME='Q_CAP_0402-0.1UF,25V,10%,X7R,CA',
 TOLERANCE='10%',
 MATERIAL='X7R',
 VOLTAGE='25V',
 VALUE='0.1UF',
 PRIM_FILE='./archive_libs/logical/q_cap/chips/chips.prt';

PART_NAME
 C1861 'Q_CAP_0402-0.1UF,25V,10%,X7R,CA':;

SECTION_NUMBER 1
 '@S9S_MB_2U_LIB.S9S_MB_2U(SCH_1):PAGE216_I11@PURE_QUANTA.Q_CAP(CHIPS)':
 C_PATH='@s9s_mb_2u_lib.s9s_mb_2u(sch_1):page216_i11@pure_quanta.q_cap(chips)',
 P_PATH='@s9s_mb_2u_lib.s9s_mb_2u(sch_1):page238_i11@pure_quanta.q_cap(chips)',
 PATH='I11',
 DRAWING='@S9S_MB_2U_LIB.S9S_MB_2U(SCH_1):PAGE216',
 PHYS_PAGE='238',
 XY='(-6400,3900)',
 ROT='0',
 VER='1',
 PACK_TYPE='0402',
 CDS_LIB='pure_quanta',
 CDS_PART_NAME='Q_CAP_0402-0.1UF,25V,10%,X7R,CA',
 TOLERANCE='10%',
 MATERIAL='X7R',
 VOLTAGE='25V',
 VALUE='0.1UF',
 PRIM_FILE='./archive_libs/logical/q_cap/chips/chips.prt';

PART_NAME
 C1862 'Q_CAP_0402-0.1UF,25V,10%,X7R,CA':;

SECTION_NUMBER 1
 '@S9S_MB_2U_LIB.S9S_MB_2U(SCH_1):PAGE216_I23@PURE_QUANTA.Q_CAP(CHIPS)':
 C_PATH='@s9s_mb_2u_lib.s9s_mb_2u(sch_1):page216_i23@pure_quanta.q_cap(chips)',
 P_PATH='@s9s_mb_2u_lib.s9s_mb_2u(sch_1):page238_i23@pure_quanta.q_cap(chips)',
 PATH='I23',
 DRAWING='@S9S_MB_2U_LIB.S9S_MB_2U(SCH_1):PAGE216',
 PHYS_PAGE='238',
 XY='(-6375,5725)',
 ROT='0',
 VER='1',
 PACK_TYPE='0402',
 CDS_LIB='pure_quanta',
 CDS_PART_NAME='Q_CAP_0402-0.1UF,25V,10%,X7R,CA',
 TOLERANCE='10%',
 MATERIAL='X7R',
 VOLTAGE='25V',
 VALUE='0.1UF',
 PRIM_FILE='./archive_libs/logical/q_cap/chips/chips.prt';

PART_NAME
 C1863 'Q_CAP_0402-0.1UF,25V,10%,X7R,CA':
 ROOM='PCIE REDRIVER1_BOM1';

SECTION_NUMBER 1
 '@S9S_MB_2U_LIB.S9S_MB_2U(SCH_1):PAGE136_I49@PURE_QUANTA.Q_CAP(CHIPS)':
 C_PATH='@s9s_mb_2u_lib.s9s_mb_2u(sch_1):page136_i49@pure_quanta.q_cap(chips)',
 P_PATH='@s9s_mb_2u_lib.s9s_mb_2u(sch_1):page166_i49@pure_quanta.q_cap(chips)',
 PATH='I49',
 DRAWING='@S9S_MB_2U_LIB.S9S_MB_2U(SCH_1):PAGE136',
 PHYS_PAGE='166',
 XY='(-2900,2350)',
 ROT='0',
 VER='1',
 PACK_TYPE='0402',
 CDS_LIB='pure_quanta',
 CDS_PART_NAME='Q_CAP_0402-0.1UF,25V,10%,X7R,CA',
 TOLERANCE='10%',
 MATERIAL='X7R',
 VOLTAGE='25V',
 ROOM='PCIE REDRIVER1_BOM1',
 VALUE='0.1UF',
 PRIM_FILE='./archive_libs/logical/q_cap/chips/chips.prt';

PART_NAME
 C1864 'Q_CAP_0402-0.1UF,25V,10%,X7R,CA':
 ROOM='PCIE REDRIVER1_BOM1';

SECTION_NUMBER 1
 '@S9S_MB_2U_LIB.S9S_MB_2U(SCH_1):PAGE136_I51@PURE_QUANTA.Q_CAP(CHIPS)':
 C_PATH='@s9s_mb_2u_lib.s9s_mb_2u(sch_1):page136_i51@pure_quanta.q_cap(chips)',
 P_PATH='@s9s_mb_2u_lib.s9s_mb_2u(sch_1):page166_i51@pure_quanta.q_cap(chips)',
 PATH='I51',
 DRAWING='@S9S_MB_2U_LIB.S9S_MB_2U(SCH_1):PAGE136',
 PHYS_PAGE='166',
 XY='(-2625,2350)',
 ROT='0',
 VER='1',
 PACK_TYPE='0402',
 CDS_LIB='pure_quanta',
 CDS_PART_NAME='Q_CAP_0402-0.1UF,25V,10%,X7R,CA',
 TOLERANCE='10%',
 MATERIAL='X7R',
 VOLTAGE='25V',
 ROOM='PCIE REDRIVER1_BOM1',
 VALUE='0.1UF',
 PRIM_FILE='./archive_libs/logical/q_cap/chips/chips.prt';

PART_NAME
 C1865 'Q_CAP_0402-0.1UF,25V,10%,X7R,CA':
 ROOM='PCIE REDRIVER1_BOM1';

SECTION_NUMBER 1
 '@S9S_MB_2U_LIB.S9S_MB_2U(SCH_1):PAGE136_I52@PURE_QUANTA.Q_CAP(CHIPS)':
 C_PATH='@s9s_mb_2u_lib.s9s_mb_2u(sch_1):page136_i52@pure_quanta.q_cap(chips)',
 P_PATH='@s9s_mb_2u_lib.s9s_mb_2u(sch_1):page166_i52@pure_quanta.q_cap(chips)',
 PATH='I52',
 DRAWING='@S9S_MB_2U_LIB.S9S_MB_2U(SCH_1):PAGE136',
 PHYS_PAGE='166',
 XY='(-2350,2350)',
 ROT='0',
 VER='1',
 PACK_TYPE='0402',
 CDS_LIB='pure_quanta',
 CDS_PART_NAME='Q_CAP_0402-0.1UF,25V,10%,X7R,CA',
 TOLERANCE='10%',
 MATERIAL='X7R',
 VOLTAGE='25V',
 ROOM='PCIE REDRIVER1_BOM1',
 VALUE='0.1UF',
 PRIM_FILE='./archive_libs/logical/q_cap/chips/chips.prt';

PART_NAME
 C1866 'Q_CAP_0402-0.1UF,25V,10%,X7R,CA':
 ROOM='PCIE REDRIVER1_BOM1';

SECTION_NUMBER 1
 '@S9S_MB_2U_LIB.S9S_MB_2U(SCH_1):PAGE136_I53@PURE_QUANTA.Q_CAP(CHIPS)':
 C_PATH='@s9s_mb_2u_lib.s9s_mb_2u(sch_1):page136_i53@pure_quanta.q_cap(chips)',
 P_PATH='@s9s_mb_2u_lib.s9s_mb_2u(sch_1):page166_i53@pure_quanta.q_cap(chips)',
 PATH='I53',
 DRAWING='@S9S_MB_2U_LIB.S9S_MB_2U(SCH_1):PAGE136',
 PHYS_PAGE='166',
 XY='(-2125,2350)',
 ROT='0',
 VER='1',
 PACK_TYPE='0402',
 CDS_LIB='pure_quanta',
 CDS_PART_NAME='Q_CAP_0402-0.1UF,25V,10%,X7R,CA',
 TOLERANCE='10%',
 MATERIAL='X7R',
 VOLTAGE='25V',
 ROOM='PCIE REDRIVER1_BOM1',
 VALUE='0.1UF',
 PRIM_FILE='./archive_libs/logical/q_cap/chips/chips.prt';

PART_NAME
 C1867 'Q_CAP_C0805-10UF,25V,10%,X6S,CA':
 ROOM='PCIE REDRIVER1_BOM1';

SECTION_NUMBER 1
 '@S9S_MB_2U_LIB.S9S_MB_2U(SCH_1):PAGE136_I48@PURE_QUANTA.Q_CAP(CHIPS)':
 C_PATH='@s9s_mb_2u_lib.s9s_mb_2u(sch_1):page136_i48@pure_quanta.q_cap(chips)',
 P_PATH='@s9s_mb_2u_lib.s9s_mb_2u(sch_1):page166_i48@pure_quanta.q_cap(chips)',
 PATH='I48',
 DRAWING='@S9S_MB_2U_LIB.S9S_MB_2U(SCH_1):PAGE136',
 PHYS_PAGE='166',
 XY='(-3275,2350)',
 ROT='0',
 VER='1',
 PACK_TYPE='C0805',
 CDS_LIB='pure_quanta',
 CDS_PART_NAME='Q_CAP_C0805-10UF,25V,10%,X6S,CA',
 TOLERANCE='10%',
 MATERIAL='X6S',
 VOLTAGE='25V',
 ROOM='PCIE REDRIVER1_BOM1',
 VALUE='10UF',
 PRIM_FILE='./archive_libs/logical/q_cap/chips/chips.prt';

PART_NAME
 C1868 'Q_CAP_0402-0.1UF,25V,10%,X7R,CA':
 ROOM='PCIE REDRIVER1_BOM1';

SECTION_NUMBER 1
 '@S9S_MB_2U_LIB.S9S_MB_2U(SCH_1):PAGE159_I29@PURE_QUANTA.Q_CAP(CHIPS)':
 C_PATH='@s9s_mb_2u_lib.s9s_mb_2u(sch_1):page159_i29@pure_quanta.q_cap(chips)',
 P_PATH='@s9s_mb_2u_lib.s9s_mb_2u(sch_1):page167_i29@pure_quanta.q_cap(chips)',
 PATH='I29',
 DRAWING='@S9S_MB_2U_LIB.S9S_MB_2U(SCH_1):PAGE159',
 PHYS_PAGE='167',
 XY='(-2825,250)',
 ROT='0',
 VER='2',
 PACK_TYPE='0402',
 CDS_LIB='pure_quanta',
 CDS_PART_NAME='Q_CAP_0402-0.1UF,25V,10%,X7R,CA',
 TOLERANCE='10%',
 MATERIAL='X7R',
 VOLTAGE='25V',
 ROOM='PCIE REDRIVER1_BOM1',
 VALUE='0.1UF',
 PRIM_FILE='./archive_libs/logical/q_cap/chips/chips.prt';

PART_NAME
 C1869 'Q_CAP_0402-0.1UF,25V,10%,X7R,CA':
 ROOM='PCIE REDRIVER1_BOM1';

SECTION_NUMBER 1
 '@S9S_MB_2U_LIB.S9S_MB_2U(SCH_1):PAGE159_I30@PURE_QUANTA.Q_CAP(CHIPS)':
 C_PATH='@s9s_mb_2u_lib.s9s_mb_2u(sch_1):page159_i30@pure_quanta.q_cap(chips)',
 P_PATH='@s9s_mb_2u_lib.s9s_mb_2u(sch_1):page167_i30@pure_quanta.q_cap(chips)',
 PATH='I30',
 DRAWING='@S9S_MB_2U_LIB.S9S_MB_2U(SCH_1):PAGE159',
 PHYS_PAGE='167',
 XY='(-2825,200)',
 ROT='0',
 VER='2',
 PACK_TYPE='0402',
 CDS_LIB='pure_quanta',
 CDS_PART_NAME='Q_CAP_0402-0.1UF,25V,10%,X7R,CA',
 TOLERANCE='10%',
 MATERIAL='X7R',
 VOLTAGE='25V',
 ROOM='PCIE REDRIVER1_BOM1',
 VALUE='0.1UF',
 PRIM_FILE='./archive_libs/logical/q_cap/chips/chips.prt';

PART_NAME
 C1870 'Q_CAP_0402-0.1UF,25V,10%,X7R,CA':
 ROOM='PCIE REDRIVER1_BOM1';

SECTION_NUMBER 1
 '@S9S_MB_2U_LIB.S9S_MB_2U(SCH_1):PAGE159_I33@PURE_QUANTA.Q_CAP(CHIPS)':
 C_PATH='@s9s_mb_2u_lib.s9s_mb_2u(sch_1):page159_i33@pure_quanta.q_cap(chips)',
 P_PATH='@s9s_mb_2u_lib.s9s_mb_2u(sch_1):page167_i33@pure_quanta.q_cap(chips)',
 PATH='I33',
 DRAWING='@S9S_MB_2U_LIB.S9S_MB_2U(SCH_1):PAGE159',
 PHYS_PAGE='167',
 XY='(-2825,875)',
 ROT='0',
 VER='2',
 PACK_TYPE='0402',
 CDS_LIB='pure_quanta',
 CDS_PART_NAME='Q_CAP_0402-0.1UF,25V,10%,X7R,CA',
 TOLERANCE='10%',
 MATERIAL='X7R',
 VOLTAGE='25V',
 ROOM='PCIE REDRIVER1_BOM1',
 VALUE='0.1UF',
 PRIM_FILE='./archive_libs/logical/q_cap/chips/chips.prt';

PART_NAME
 C1871 'Q_CAP_0402-0.1UF,25V,10%,X7R,CA':
 ROOM='PCIE REDRIVER1_BOM1';

SECTION_NUMBER 1
 '@S9S_MB_2U_LIB.S9S_MB_2U(SCH_1):PAGE159_I34@PURE_QUANTA.Q_CAP(CHIPS)':
 C_PATH='@s9s_mb_2u_lib.s9s_mb_2u(sch_1):page159_i34@pure_quanta.q_cap(chips)',
 P_PATH='@s9s_mb_2u_lib.s9s_mb_2u(sch_1):page167_i34@pure_quanta.q_cap(chips)',
 PATH='I34',
 DRAWING='@S9S_MB_2U_LIB.S9S_MB_2U(SCH_1):PAGE159',
 PHYS_PAGE='167',
 XY='(-2825,825)',
 ROT='0',
 VER='2',
 PACK_TYPE='0402',
 CDS_LIB='pure_quanta',
 CDS_PART_NAME='Q_CAP_0402-0.1UF,25V,10%,X7R,CA',
 TOLERANCE='10%',
 MATERIAL='X7R',
 VOLTAGE='25V',
 ROOM='PCIE REDRIVER1_BOM1',
 VALUE='0.1UF',
 PRIM_FILE='./archive_libs/logical/q_cap/chips/chips.prt';

PART_NAME
 C1873 'Q_CAP_0402-0.1UF,25V,10%,X7R,CA':;

SECTION_NUMBER 1
 '@S9S_MB_2U_LIB.S9S_MB_2U(SCH_1):PAGE182_I308@PURE_QUANTA.Q_CAP(CHIPS)':
 C_PATH='@s9s_mb_2u_lib.s9s_mb_2u(sch_1):page182_i308@pure_quanta.q_cap(chips)',
 P_PATH='@s9s_mb_2u_lib.s9s_mb_2u(sch_1):page190_i308@pure_quanta.q_cap(chips)',
 PATH='I308',
 DRAWING='@S9S_MB_2U_LIB.S9S_MB_2U(SCH_1):PAGE182',
 BOM_COST='VR_SYSTEM ',
 PHYS_PAGE='190',
 XY='(9600,1525)',
 ROT='0',
 VER='1',
 PACK_TYPE='0402',
 CDS_LIB='pure_quanta',
 CDS_PART_NAME='Q_CAP_0402-0.1UF,25V,10%,X7R,CA',
 TOLERANCE='10%',
 MATERIAL='X7R',
 VOLTAGE='25V',
 VALUE='0.1UF',
 PRIM_FILE='./archive_libs/logical/q_cap/chips/chips.prt';

PART_NAME
 C1874 'Q_CAP_0402-0.1UF,25V,10%,X7R,CA':;

SECTION_NUMBER 1
 '@S9S_MB_2U_LIB.S9S_MB_2U(SCH_1):PAGE170_I22@PURE_QUANTA.Q_CAP(CHIPS)':
 C_PATH='@s9s_mb_2u_lib.s9s_mb_2u(sch_1):page170_i22@pure_quanta.q_cap(chips)',
 P_PATH='@s9s_mb_2u_lib.s9s_mb_2u(sch_1):page165_i22@pure_quanta.q_cap(chips)',
 PATH='I22',
 DRAWING='@S9S_MB_2U_LIB.S9S_MB_2U(SCH_1):PAGE170',
 PHYS_PAGE='165',
 XY='(-1600,3250)',
 ROT='0',
 VER='1',
 PACK_TYPE='0402',
 CDS_LIB='pure_quanta',
 CDS_PART_NAME='Q_CAP_0402-0.1UF,25V,10%,X7R,CA',
 TOLERANCE='10%',
 MATERIAL='X7R',
 VOLTAGE='25V',
 VALUE='0.1UF',
 PRIM_FILE='./archive_libs/logical/q_cap/chips/chips.prt';

PART_NAME
 C1875 'Q_CAP_0402-0.1UF,25V,10%,X7R,CA':;

SECTION_NUMBER 1
 '@S9S_MB_2U_LIB.S9S_MB_2U(SCH_1):PAGE170_I21@PURE_QUANTA.Q_CAP(CHIPS)':
 C_PATH='@s9s_mb_2u_lib.s9s_mb_2u(sch_1):page170_i21@pure_quanta.q_cap(chips)',
 P_PATH='@s9s_mb_2u_lib.s9s_mb_2u(sch_1):page165_i21@pure_quanta.q_cap(chips)',
 PATH='I21',
 DRAWING='@S9S_MB_2U_LIB.S9S_MB_2U(SCH_1):PAGE170',
 PHYS_PAGE='165',
 XY='(-1500,1175)',
 ROT='0',
 VER='1',
 PACK_TYPE='0402',
 CDS_LIB='pure_quanta',
 CDS_PART_NAME='Q_CAP_0402-0.1UF,25V,10%,X7R,CA',
 TOLERANCE='10%',
 MATERIAL='X7R',
 VOLTAGE='25V',
 VALUE='0.1UF',
 PRIM_FILE='./archive_libs/logical/q_cap/chips/chips.prt';

PART_NAME
 C1876 'Q_CAP_0402-0.1UF,25V,10%,X7R,CA':;

SECTION_NUMBER 1
 '@S9S_MB_2U_LIB.S9S_MB_2U(SCH_1):PAGE170_I41@PURE_QUANTA.Q_CAP(CHIPS)':
 C_PATH='@s9s_mb_2u_lib.s9s_mb_2u(sch_1):page170_i41@pure_quanta.q_cap(chips)',
 P_PATH='@s9s_mb_2u_lib.s9s_mb_2u(sch_1):page165_i41@pure_quanta.q_cap(chips)',
 PATH='I41',
 DRAWING='@S9S_MB_2U_LIB.S9S_MB_2U(SCH_1):PAGE170',
 PHYS_PAGE='165',
 XY='(-325,2850)',
 ROT='0',
 VER='1',
 PACK_TYPE='0402',
 CDS_LIB='pure_quanta',
 CDS_PART_NAME='Q_CAP_0402-0.1UF,25V,10%,X7R,CA',
 TOLERANCE='10%',
 MATERIAL='X7R',
 VOLTAGE='25V',
 VALUE='0.1UF',
 PRIM_FILE='./archive_libs/logical/q_cap/chips/chips.prt';

PART_NAME
 C1877 'Q_CAP_0402-0.1UF,25V,10%,X7R,CA':;

SECTION_NUMBER 1
 '@S9S_MB_2U_LIB.S9S_MB_2U(SCH_1):PAGE170_I34@PURE_QUANTA.Q_CAP(CHIPS)':
 C_PATH='@s9s_mb_2u_lib.s9s_mb_2u(sch_1):page170_i34@pure_quanta.q_cap(chips)',
 P_PATH='@s9s_mb_2u_lib.s9s_mb_2u(sch_1):page165_i34@pure_quanta.q_cap(chips)',
 PATH='I34',
 DRAWING='@S9S_MB_2U_LIB.S9S_MB_2U(SCH_1):PAGE170',
 PHYS_PAGE='165',
 XY='(1325,2775)',
 ROT='0',
 VER='1',
 PACK_TYPE='0402',
 CDS_LIB='pure_quanta',
 CDS_PART_NAME='Q_CAP_0402-0.1UF,25V,10%,X7R,CA',
 TOLERANCE='10%',
 MATERIAL='X7R',
 VOLTAGE='25V',
 VALUE='0.1UF',
 PRIM_FILE='./archive_libs/logical/q_cap/chips/chips.prt';

PART_NAME
 C1878 'Q_CAP_0402-0.1UF,25V,10%,X7R,CA':;

SECTION_NUMBER 1
 '@S9S_MB_2U_LIB.S9S_MB_2U(SCH_1):PAGE170_I37@PURE_QUANTA.Q_CAP(CHIPS)':
 C_PATH='@s9s_mb_2u_lib.s9s_mb_2u(sch_1):page170_i37@pure_quanta.q_cap(chips)',
 P_PATH='@s9s_mb_2u_lib.s9s_mb_2u(sch_1):page165_i37@pure_quanta.q_cap(chips)',
 PATH='I37',
 DRAWING='@S9S_MB_2U_LIB.S9S_MB_2U(SCH_1):PAGE170',
 PHYS_PAGE='165',
 XY='(1350,1925)',
 ROT='0',
 VER='1',
 PACK_TYPE='0402',
 CDS_LIB='pure_quanta',
 CDS_PART_NAME='Q_CAP_0402-0.1UF,25V,10%,X7R,CA',
 TOLERANCE='10%',
 MATERIAL='X7R',
 VOLTAGE='25V',
 VALUE='0.1UF',
 PRIM_FILE='./archive_libs/logical/q_cap/chips/chips.prt';

PART_NAME
 C1879 'Q_CAP_0402-0.1UF,25V,10%,X7R,CA':;

SECTION_NUMBER 1
 '@S9S_MB_2U_LIB.S9S_MB_2U(SCH_1):PAGE170_I31@PURE_QUANTA.Q_CAP(CHIPS)':
 C_PATH='@s9s_mb_2u_lib.s9s_mb_2u(sch_1):page170_i31@pure_quanta.q_cap(chips)',
 P_PATH='@s9s_mb_2u_lib.s9s_mb_2u(sch_1):page165_i31@pure_quanta.q_cap(chips)',
 PATH='I31',
 DRAWING='@S9S_MB_2U_LIB.S9S_MB_2U(SCH_1):PAGE170',
 PHYS_PAGE='165',
 XY='(1525,-250)',
 ROT='0',
 VER='1',
 PACK_TYPE='0402',
 CDS_LIB='pure_quanta',
 CDS_PART_NAME='Q_CAP_0402-0.1UF,25V,10%,X7R,CA',
 TOLERANCE='10%',
 MATERIAL='X7R',
 VOLTAGE='25V',
 VALUE='0.1UF',
 PRIM_FILE='./archive_libs/logical/q_cap/chips/chips.prt';

PART_NAME
 C1880 'Q_CAP_0402-0.1UF,25V,10%,X7R,CA':;

SECTION_NUMBER 1
 '@S9S_MB_2U_LIB.S9S_MB_2U(SCH_1):PAGE170_I27@PURE_QUANTA.Q_CAP(CHIPS)':
 C_PATH='@s9s_mb_2u_lib.s9s_mb_2u(sch_1):page170_i27@pure_quanta.q_cap(chips)',
 P_PATH='@s9s_mb_2u_lib.s9s_mb_2u(sch_1):page165_i27@pure_quanta.q_cap(chips)',
 PATH='I27',
 DRAWING='@S9S_MB_2U_LIB.S9S_MB_2U(SCH_1):PAGE170',
 PHYS_PAGE='165',
 XY='(1525,575)',
 ROT='0',
 VER='1',
 PACK_TYPE='0402',
 CDS_LIB='pure_quanta',
 CDS_PART_NAME='Q_CAP_0402-0.1UF,25V,10%,X7R,CA',
 TOLERANCE='10%',
 MATERIAL='X7R',
 VOLTAGE='25V',
 VALUE='0.1UF',
 PRIM_FILE='./archive_libs/logical/q_cap/chips/chips.prt';

PART_NAME
 C1881 'Q_CAP_0402-1000PF,50V,5%,EMPTYA':;

SECTION_NUMBER 1
 '@S9S_MB_2U_LIB.S9S_MB_2U(SCH_1):PAGE145_I156@PURE_QUANTA.Q_CAP(CHIPS)':
 C_PATH='@s9s_mb_2u_lib.s9s_mb_2u(sch_1):page145_i156@pure_quanta.q_cap(chips)',
 P_PATH='@s9s_mb_2u_lib.s9s_mb_2u(sch_1):page148_i156@pure_quanta.q_cap(chips)',
 PATH='I156',
 DRAWING='@S9S_MB_2U_LIB.S9S_MB_2U(SCH_1):PAGE145',
 PHYS_PAGE='148',
 XY='(2900,3325)',
 ROT='0',
 VER='1',
 PACK_TYPE='0402',
 CDS_LIB='pure_quanta',
 CDS_PART_NAME='Q_CAP_0402-1000PF,50V,5%,EMPTYA',
 TOLERANCE='5%',
 MATERIAL='EMPTY',
 VOLTAGE='50V',
 VALUE='1000PF',
 PRIM_FILE='./archive_libs/logical/q_cap/chips/chips.prt';

PART_NAME
 C1882 'Q_CAP_0402-0.1UF,25V,10%,X7R,CA':;

SECTION_NUMBER 1
 '@S9S_MB_2U_LIB.S9S_MB_2U(SCH_1):PAGE201_I80@PURE_QUANTA.Q_CAP(CHIPS)':
 C_PATH='@s9s_mb_2u_lib.s9s_mb_2u(sch_1):page201_i80@pure_quanta.q_cap(chips)',
 P_PATH='@s9s_mb_2u_lib.s9s_mb_2u(sch_1):page212_i80@pure_quanta.q_cap(chips)',
 PATH='I80',
 DRAWING='@S9S_MB_2U_LIB.S9S_MB_2U(SCH_1):PAGE201',
 PHYS_PAGE='212',
 XY='(-2375,1925)',
 ROT='0',
 VER='1',
 PACK_TYPE='0402',
 CDS_LIB='pure_quanta',
 CDS_PART_NAME='Q_CAP_0402-0.1UF,25V,10%,X7R,CA',
 TOLERANCE='10%',
 MATERIAL='X7R',
 VOLTAGE='25V',
 VALUE='0.1UF',
 PRIM_FILE='./archive_libs/logical/q_cap/chips/chips.prt';

PART_NAME
 C1883 'Q_CAP_C0805-10UF,25V,10%,X6S,CA':;

SECTION_NUMBER 1
 '@S9S_MB_2U_LIB.S9S_MB_2U(SCH_1):PAGE201_I16@PURE_QUANTA.Q_CAP(CHIPS)':
 C_PATH='@s9s_mb_2u_lib.s9s_mb_2u(sch_1):page201_i16@pure_quanta.q_cap(chips)',
 P_PATH='@s9s_mb_2u_lib.s9s_mb_2u(sch_1):page212_i16@pure_quanta.q_cap(chips)',
 PATH='I16',
 DRAWING='@S9S_MB_2U_LIB.S9S_MB_2U(SCH_1):PAGE201',
 PHYS_PAGE='212',
 XY='(-2800,5000)',
 ROT='0',
 VER='1',
 PACK_TYPE='C0805',
 CDS_LIB='pure_quanta',
 CDS_PART_NAME='Q_CAP_C0805-10UF,25V,10%,X6S,CA',
 TOLERANCE='10%',
 MATERIAL='X6S',
 VOLTAGE='25V',
 VALUE='10UF',
 PRIM_FILE='./archive_libs/logical/q_cap/chips/chips.prt';

PART_NAME
 C1884 'Q_CAP_C0402-1UF,25V,10%,X6S,CHA':;

SECTION_NUMBER 1
 '@S9S_MB_2U_LIB.S9S_MB_2U(SCH_1):PAGE201_I103@PURE_QUANTA.Q_CAP(CHIPS)':
 C_PATH='@s9s_mb_2u_lib.s9s_mb_2u(sch_1):page201_i103@pure_quanta.q_cap(chips)',
 P_PATH='@s9s_mb_2u_lib.s9s_mb_2u(sch_1):page212_i103@pure_quanta.q_cap(chips)',
 PATH='I103',
 DRAWING='@S9S_MB_2U_LIB.S9S_MB_2U(SCH_1):PAGE201',
 BOM_COST='VR_SYSTEM ',
 PHYS_PAGE='212',
 XY='(-1050,4975)',
 ROT='0',
 VER='1',
 PACK_TYPE='C0402',
 CDS_LIB='pure_quanta',
 CDS_PART_NAME='Q_CAP_C0402-1UF,25V,10%,X6S,CHA',
 TOLERANCE='10%',
 MATERIAL='X6S',
 VOLTAGE='25V',
 VALUE='1UF',
 PRIM_FILE='./archive_libs/logical/q_cap/chips/chips.prt';

PART_NAME
 C1886 'Q_CAP_0402-0.1UF,25V,10%,X7R,CA':;

SECTION_NUMBER 1
 '@S9S_MB_2U_LIB.S9S_MB_2U(SCH_1):PAGE201_I18@PURE_QUANTA.Q_CAP(CHIPS)':
 C_PATH='@s9s_mb_2u_lib.s9s_mb_2u(sch_1):page201_i18@pure_quanta.q_cap(chips)',
 P_PATH='@s9s_mb_2u_lib.s9s_mb_2u(sch_1):page212_i18@pure_quanta.q_cap(chips)',
 PATH='I18',
 DRAWING='@S9S_MB_2U_LIB.S9S_MB_2U(SCH_1):PAGE201',
 PHYS_PAGE='212',
 XY='(-2075,5000)',
 ROT='0',
 VER='1',
 PACK_TYPE='0402',
 CDS_LIB='pure_quanta',
 CDS_PART_NAME='Q_CAP_0402-0.1UF,25V,10%,X7R,CA',
 TOLERANCE='10%',
 MATERIAL='X7R',
 VOLTAGE='25V',
 VALUE='0.1UF',
 PRIM_FILE='./archive_libs/logical/q_cap/chips/chips.prt';

PART_NAME
 C1889 'Q_CAP_0402-0.1UF,25V,10%,X7R,CA':;

SECTION_NUMBER 1
 '@S9S_MB_2U_LIB.S9S_MB_2U(SCH_1):PAGE201_I19@PURE_QUANTA.Q_CAP(CHIPS)':
 C_PATH='@s9s_mb_2u_lib.s9s_mb_2u(sch_1):page201_i19@pure_quanta.q_cap(chips)',
 P_PATH='@s9s_mb_2u_lib.s9s_mb_2u(sch_1):page212_i19@pure_quanta.q_cap(chips)',
 PATH='I19',
 DRAWING='@S9S_MB_2U_LIB.S9S_MB_2U(SCH_1):PAGE201',
 PHYS_PAGE='212',
 XY='(-1850,5000)',
 ROT='0',
 VER='1',
 PACK_TYPE='0402',
 CDS_LIB='pure_quanta',
 CDS_PART_NAME='Q_CAP_0402-0.1UF,25V,10%,X7R,CA',
 TOLERANCE='10%',
 MATERIAL='X7R',
 VOLTAGE='25V',
 VALUE='0.1UF',
 PRIM_FILE='./archive_libs/logical/q_cap/chips/chips.prt';

PART_NAME
 C1893 'Q_CAP_C0402-0.01UF,50V,10%,X7RA':;

SECTION_NUMBER 1
 '@S9S_MB_2U_LIB.S9S_MB_2U(SCH_1):PAGE202_I76@PURE_QUANTA.Q_CAP(CHIPS)':
 C_PATH='@s9s_mb_2u_lib.s9s_mb_2u(sch_1):page202_i76@pure_quanta.q_cap(chips)',
 P_PATH='@s9s_mb_2u_lib.s9s_mb_2u(sch_1):page217_i76@pure_quanta.q_cap(chips)',
 PATH='I76',
 DRAWING='@S9S_MB_2U_LIB.S9S_MB_2U(SCH_1):PAGE202',
 PHYS_PAGE='217',
 XY='(-1475,-2175)',
 ROT='0',
 VER='1',
 PACK_TYPE='C0402',
 CDS_LIB='pure_quanta',
 CDS_PART_NAME='Q_CAP_C0402-0.01UF,50V,10%,X7RA',
 TOLERANCE='10%',
 MATERIAL='X7R',
 VOLTAGE='50V',
 VALUE='0.01UF',
 PRIM_FILE='./archive_libs/logical/q_cap/chips/chips.prt';

PART_NAME
 C1894 'Q_CAP_C0402-0.01UF,50V,10%,X7RA':;

SECTION_NUMBER 1
 '@S9S_MB_2U_LIB.S9S_MB_2U(SCH_1):PAGE202_I58@PURE_QUANTA.Q_CAP(CHIPS)':
 C_PATH='@s9s_mb_2u_lib.s9s_mb_2u(sch_1):page202_i58@pure_quanta.q_cap(chips)',
 P_PATH='@s9s_mb_2u_lib.s9s_mb_2u(sch_1):page217_i58@pure_quanta.q_cap(chips)',
 PATH='I58',
 DRAWING='@S9S_MB_2U_LIB.S9S_MB_2U(SCH_1):PAGE202',
 PHYS_PAGE='217',
 XY='(-300,-1000)',
 ROT='0',
 VER='1',
 PACK_TYPE='C0402',
 CDS_LIB='pure_quanta',
 CDS_PART_NAME='Q_CAP_C0402-0.01UF,50V,10%,X7RA',
 TOLERANCE='10%',
 MATERIAL='X7R',
 VOLTAGE='50V',
 VALUE='0.01UF',
 PRIM_FILE='./archive_libs/logical/q_cap/chips/chips.prt';

PART_NAME
 C1895 'Q_CAP_C0402-0.01UF,50V,10%,X7RA':;

SECTION_NUMBER 1
 '@S9S_MB_2U_LIB.S9S_MB_2U(SCH_1):PAGE202_I43@PURE_QUANTA.Q_CAP(CHIPS)':
 C_PATH='@s9s_mb_2u_lib.s9s_mb_2u(sch_1):page202_i43@pure_quanta.q_cap(chips)',
 P_PATH='@s9s_mb_2u_lib.s9s_mb_2u(sch_1):page217_i43@pure_quanta.q_cap(chips)',
 PATH='I43',
 DRAWING='@S9S_MB_2U_LIB.S9S_MB_2U(SCH_1):PAGE202',
 PHYS_PAGE='217',
 XY='(-250,1150)',
 ROT='0',
 VER='1',
 PACK_TYPE='C0402',
 CDS_LIB='pure_quanta',
 CDS_PART_NAME='Q_CAP_C0402-0.01UF,50V,10%,X7RA',
 TOLERANCE='10%',
 MATERIAL='X7R',
 VOLTAGE='50V',
 VALUE='0.01UF',
 PRIM_FILE='./archive_libs/logical/q_cap/chips/chips.prt';

PART_NAME
 C1896 'Q_CAP_C0402-0.01UF,50V,10%,X7RA':;

SECTION_NUMBER 1
 '@S9S_MB_2U_LIB.S9S_MB_2U(SCH_1):PAGE202_I47@PURE_QUANTA.Q_CAP(CHIPS)':
 C_PATH='@s9s_mb_2u_lib.s9s_mb_2u(sch_1):page202_i47@pure_quanta.q_cap(chips)',
 P_PATH='@s9s_mb_2u_lib.s9s_mb_2u(sch_1):page217_i47@pure_quanta.q_cap(chips)',
 PATH='I47',
 DRAWING='@S9S_MB_2U_LIB.S9S_MB_2U(SCH_1):PAGE202',
 PHYS_PAGE='217',
 XY='(-325,125)',
 ROT='0',
 VER='1',
 PACK_TYPE='C0402',
 CDS_LIB='pure_quanta',
 CDS_PART_NAME='Q_CAP_C0402-0.01UF,50V,10%,X7RA',
 TOLERANCE='10%',
 MATERIAL='X7R',
 VOLTAGE='50V',
 VALUE='0.01UF',
 PRIM_FILE='./archive_libs/logical/q_cap/chips/chips.prt';

PART_NAME
 C1897 'Q_CAP_C0402-0.01UF,50V,10%,X7RA':;

SECTION_NUMBER 1
 '@S9S_MB_2U_LIB.S9S_MB_2U(SCH_1):PAGE202_I27@PURE_QUANTA.Q_CAP(CHIPS)':
 C_PATH='@s9s_mb_2u_lib.s9s_mb_2u(sch_1):page202_i27@pure_quanta.q_cap(chips)',
 P_PATH='@s9s_mb_2u_lib.s9s_mb_2u(sch_1):page217_i27@pure_quanta.q_cap(chips)',
 PATH='I27',
 DRAWING='@S9S_MB_2U_LIB.S9S_MB_2U(SCH_1):PAGE202',
 PHYS_PAGE='217',
 XY='(-300,2375)',
 ROT='0',
 VER='1',
 PACK_TYPE='C0402',
 CDS_LIB='pure_quanta',
 CDS_PART_NAME='Q_CAP_C0402-0.01UF,50V,10%,X7RA',
 TOLERANCE='10%',
 MATERIAL='X7R',
 VOLTAGE='50V',
 VALUE='0.01UF',
 PRIM_FILE='./archive_libs/logical/q_cap/chips/chips.prt';

PART_NAME
 C1898 'Q_CAP_C0402-0.01UF,50V,10%,X7RA':;

SECTION_NUMBER 1
 '@S9S_MB_2U_LIB.S9S_MB_2U(SCH_1):PAGE202_I20@PURE_QUANTA.Q_CAP(CHIPS)':
 C_PATH='@s9s_mb_2u_lib.s9s_mb_2u(sch_1):page202_i20@pure_quanta.q_cap(chips)',
 P_PATH='@s9s_mb_2u_lib.s9s_mb_2u(sch_1):page217_i20@pure_quanta.q_cap(chips)',
 PATH='I20',
 DRAWING='@S9S_MB_2U_LIB.S9S_MB_2U(SCH_1):PAGE202',
 PHYS_PAGE='217',
 XY='(1500,-2225)',
 ROT='0',
 VER='1',
 PACK_TYPE='C0402',
 CDS_LIB='pure_quanta',
 CDS_PART_NAME='Q_CAP_C0402-0.01UF,50V,10%,X7RA',
 TOLERANCE='10%',
 MATERIAL='X7R',
 VOLTAGE='50V',
 VALUE='0.01UF',
 PRIM_FILE='./archive_libs/logical/q_cap/chips/chips.prt';

PART_NAME
 C1899 'Q_CAP_C0402-0.01UF,50V,10%,X7RA':;

SECTION_NUMBER 1
 '@S9S_MB_2U_LIB.S9S_MB_2U(SCH_1):PAGE202_I74@PURE_QUANTA.Q_CAP(CHIPS)':
 C_PATH='@s9s_mb_2u_lib.s9s_mb_2u(sch_1):page202_i74@pure_quanta.q_cap(chips)',
 P_PATH='@s9s_mb_2u_lib.s9s_mb_2u(sch_1):page217_i74@pure_quanta.q_cap(chips)',
 PATH='I74',
 DRAWING='@S9S_MB_2U_LIB.S9S_MB_2U(SCH_1):PAGE202',
 PHYS_PAGE='217',
 XY='(-1225,-2175)',
 ROT='0',
 VER='1',
 PACK_TYPE='C0402',
 CDS_LIB='pure_quanta',
 CDS_PART_NAME='Q_CAP_C0402-0.01UF,50V,10%,X7RA',
 TOLERANCE='10%',
 MATERIAL='X7R',
 VOLTAGE='50V',
 VALUE='0.01UF',
 PRIM_FILE='./archive_libs/logical/q_cap/chips/chips.prt';

PART_NAME
 C1900 'Q_CAP_C0402-0.01UF,50V,10%,X7RA':;

SECTION_NUMBER 1
 '@S9S_MB_2U_LIB.S9S_MB_2U(SCH_1):PAGE202_I57@PURE_QUANTA.Q_CAP(CHIPS)':
 C_PATH='@s9s_mb_2u_lib.s9s_mb_2u(sch_1):page202_i57@pure_quanta.q_cap(chips)',
 P_PATH='@s9s_mb_2u_lib.s9s_mb_2u(sch_1):page217_i57@pure_quanta.q_cap(chips)',
 PATH='I57',
 DRAWING='@S9S_MB_2U_LIB.S9S_MB_2U(SCH_1):PAGE202',
 PHYS_PAGE='217',
 XY='(-50,-1000)',
 ROT='0',
 VER='1',
 PACK_TYPE='C0402',
 CDS_LIB='pure_quanta',
 CDS_PART_NAME='Q_CAP_C0402-0.01UF,50V,10%,X7RA',
 TOLERANCE='10%',
 MATERIAL='X7R',
 VOLTAGE='50V',
 VALUE='0.01UF',
 PRIM_FILE='./archive_libs/logical/q_cap/chips/chips.prt';

PART_NAME
 C1901 'Q_CAP_C0402-0.01UF,50V,10%,X7RA':;

SECTION_NUMBER 1
 '@S9S_MB_2U_LIB.S9S_MB_2U(SCH_1):PAGE202_I42@PURE_QUANTA.Q_CAP(CHIPS)':
 C_PATH='@s9s_mb_2u_lib.s9s_mb_2u(sch_1):page202_i42@pure_quanta.q_cap(chips)',
 P_PATH='@s9s_mb_2u_lib.s9s_mb_2u(sch_1):page217_i42@pure_quanta.q_cap(chips)',
 PATH='I42',
 DRAWING='@S9S_MB_2U_LIB.S9S_MB_2U(SCH_1):PAGE202',
 PHYS_PAGE='217',
 XY='(0,1150)',
 ROT='0',
 VER='1',
 PACK_TYPE='C0402',
 CDS_LIB='pure_quanta',
 CDS_PART_NAME='Q_CAP_C0402-0.01UF,50V,10%,X7RA',
 TOLERANCE='10%',
 MATERIAL='X7R',
 VOLTAGE='50V',
 VALUE='0.01UF',
 PRIM_FILE='./archive_libs/logical/q_cap/chips/chips.prt';

PART_NAME
 C1902 'Q_CAP_C0402-0.01UF,50V,10%,X7RA':;

SECTION_NUMBER 1
 '@S9S_MB_2U_LIB.S9S_MB_2U(SCH_1):PAGE202_I46@PURE_QUANTA.Q_CAP(CHIPS)':
 C_PATH='@s9s_mb_2u_lib.s9s_mb_2u(sch_1):page202_i46@pure_quanta.q_cap(chips)',
 P_PATH='@s9s_mb_2u_lib.s9s_mb_2u(sch_1):page217_i46@pure_quanta.q_cap(chips)',
 PATH='I46',
 DRAWING='@S9S_MB_2U_LIB.S9S_MB_2U(SCH_1):PAGE202',
 PHYS_PAGE='217',
 XY='(-75,125)',
 ROT='0',
 VER='1',
 PACK_TYPE='C0402',
 CDS_LIB='pure_quanta',
 CDS_PART_NAME='Q_CAP_C0402-0.01UF,50V,10%,X7RA',
 TOLERANCE='10%',
 MATERIAL='X7R',
 VOLTAGE='50V',
 VALUE='0.01UF',
 PRIM_FILE='./archive_libs/logical/q_cap/chips/chips.prt';

PART_NAME
 C1903 'Q_CAP_C0402-0.01UF,50V,10%,X7RA':;

SECTION_NUMBER 1
 '@S9S_MB_2U_LIB.S9S_MB_2U(SCH_1):PAGE202_I26@PURE_QUANTA.Q_CAP(CHIPS)':
 C_PATH='@s9s_mb_2u_lib.s9s_mb_2u(sch_1):page202_i26@pure_quanta.q_cap(chips)',
 P_PATH='@s9s_mb_2u_lib.s9s_mb_2u(sch_1):page217_i26@pure_quanta.q_cap(chips)',
 PATH='I26',
 DRAWING='@S9S_MB_2U_LIB.S9S_MB_2U(SCH_1):PAGE202',
 PHYS_PAGE='217',
 XY='(-50,2375)',
 ROT='0',
 VER='1',
 PACK_TYPE='C0402',
 CDS_LIB='pure_quanta',
 CDS_PART_NAME='Q_CAP_C0402-0.01UF,50V,10%,X7RA',
 TOLERANCE='10%',
 MATERIAL='X7R',
 VOLTAGE='50V',
 VALUE='0.01UF',
 PRIM_FILE='./archive_libs/logical/q_cap/chips/chips.prt';

PART_NAME
 C1904 'Q_CAP_C0402-0.01UF,50V,10%,X7RA':;

SECTION_NUMBER 1
 '@S9S_MB_2U_LIB.S9S_MB_2U(SCH_1):PAGE202_I18@PURE_QUANTA.Q_CAP(CHIPS)':
 C_PATH='@s9s_mb_2u_lib.s9s_mb_2u(sch_1):page202_i18@pure_quanta.q_cap(chips)',
 P_PATH='@s9s_mb_2u_lib.s9s_mb_2u(sch_1):page217_i18@pure_quanta.q_cap(chips)',
 PATH='I18',
 DRAWING='@S9S_MB_2U_LIB.S9S_MB_2U(SCH_1):PAGE202',
 PHYS_PAGE='217',
 XY='(1750,-2225)',
 ROT='0',
 VER='1',
 PACK_TYPE='C0402',
 CDS_LIB='pure_quanta',
 CDS_PART_NAME='Q_CAP_C0402-0.01UF,50V,10%,X7RA',
 TOLERANCE='10%',
 MATERIAL='X7R',
 VOLTAGE='50V',
 VALUE='0.01UF',
 PRIM_FILE='./archive_libs/logical/q_cap/chips/chips.prt';

PART_NAME
 C1905 'Q_CAP_0402-0.1UF,25V,10%,X7R,CA':;

SECTION_NUMBER 1
 '@S9S_MB_2U_LIB.S9S_MB_2U(SCH_1):PAGE202_I41@PURE_QUANTA.Q_CAP(CHIPS)':
 C_PATH='@s9s_mb_2u_lib.s9s_mb_2u(sch_1):page202_i41@pure_quanta.q_cap(chips)',
 P_PATH='@s9s_mb_2u_lib.s9s_mb_2u(sch_1):page217_i41@pure_quanta.q_cap(chips)',
 PATH='I41',
 DRAWING='@S9S_MB_2U_LIB.S9S_MB_2U(SCH_1):PAGE202',
 PHYS_PAGE='217',
 XY='(250,1150)',
 ROT='0',
 VER='1',
 PACK_TYPE='0402',
 CDS_LIB='pure_quanta',
 CDS_PART_NAME='Q_CAP_0402-0.1UF,25V,10%,X7R,CA',
 TOLERANCE='10%',
 MATERIAL='X7R',
 VOLTAGE='25V',
 VALUE='0.1UF',
 PRIM_FILE='./archive_libs/logical/q_cap/chips/chips.prt';

PART_NAME
 C1906 'Q_CAP_0402-0.1UF,25V,10%,X7R,CA':;

SECTION_NUMBER 1
 '@S9S_MB_2U_LIB.S9S_MB_2U(SCH_1):PAGE202_I45@PURE_QUANTA.Q_CAP(CHIPS)':
 C_PATH='@s9s_mb_2u_lib.s9s_mb_2u(sch_1):page202_i45@pure_quanta.q_cap(chips)',
 P_PATH='@s9s_mb_2u_lib.s9s_mb_2u(sch_1):page217_i45@pure_quanta.q_cap(chips)',
 PATH='I45',
 DRAWING='@S9S_MB_2U_LIB.S9S_MB_2U(SCH_1):PAGE202',
 PHYS_PAGE='217',
 XY='(175,125)',
 ROT='0',
 VER='1',
 PACK_TYPE='0402',
 CDS_LIB='pure_quanta',
 CDS_PART_NAME='Q_CAP_0402-0.1UF,25V,10%,X7R,CA',
 TOLERANCE='10%',
 MATERIAL='X7R',
 VOLTAGE='25V',
 VALUE='0.1UF',
 PRIM_FILE='./archive_libs/logical/q_cap/chips/chips.prt';

PART_NAME
 C1907 'Q_CAP_0402-0.1UF,25V,10%,X7R,CA':;

SECTION_NUMBER 1
 '@S9S_MB_2U_LIB.S9S_MB_2U(SCH_1):PAGE202_I25@PURE_QUANTA.Q_CAP(CHIPS)':
 C_PATH='@s9s_mb_2u_lib.s9s_mb_2u(sch_1):page202_i25@pure_quanta.q_cap(chips)',
 P_PATH='@s9s_mb_2u_lib.s9s_mb_2u(sch_1):page217_i25@pure_quanta.q_cap(chips)',
 PATH='I25',
 DRAWING='@S9S_MB_2U_LIB.S9S_MB_2U(SCH_1):PAGE202',
 PHYS_PAGE='217',
 XY='(200,2375)',
 ROT='0',
 VER='1',
 PACK_TYPE='0402',
 CDS_LIB='pure_quanta',
 CDS_PART_NAME='Q_CAP_0402-0.1UF,25V,10%,X7R,CA',
 TOLERANCE='10%',
 MATERIAL='X7R',
 VOLTAGE='25V',
 VALUE='0.1UF',
 PRIM_FILE='./archive_libs/logical/q_cap/chips/chips.prt';

PART_NAME
 C1908 'Q_CAP_C0402-0.01UF,50V,10%,X7RA':;

SECTION_NUMBER 1
 '@S9S_MB_2U_LIB.S9S_MB_2U(SCH_1):PAGE202_I77@PURE_QUANTA.Q_CAP(CHIPS)':
 C_PATH='@s9s_mb_2u_lib.s9s_mb_2u(sch_1):page202_i77@pure_quanta.q_cap(chips)',
 P_PATH='@s9s_mb_2u_lib.s9s_mb_2u(sch_1):page217_i77@pure_quanta.q_cap(chips)',
 PATH='I77',
 DRAWING='@S9S_MB_2U_LIB.S9S_MB_2U(SCH_1):PAGE202',
 PHYS_PAGE='217',
 XY='(-1750,-2175)',
 ROT='0',
 VER='1',
 PACK_TYPE='C0402',
 CDS_LIB='pure_quanta',
 CDS_PART_NAME='Q_CAP_C0402-0.01UF,50V,10%,X7RA',
 TOLERANCE='10%',
 MATERIAL='X7R',
 VOLTAGE='50V',
 VALUE='0.01UF',
 PRIM_FILE='./archive_libs/logical/q_cap/chips/chips.prt';

PART_NAME
 C1909 'Q_CAP_C0402-0.01UF,50V,10%,X7RA':;

SECTION_NUMBER 1
 '@S9S_MB_2U_LIB.S9S_MB_2U(SCH_1):PAGE202_I59@PURE_QUANTA.Q_CAP(CHIPS)':
 C_PATH='@s9s_mb_2u_lib.s9s_mb_2u(sch_1):page202_i59@pure_quanta.q_cap(chips)',
 P_PATH='@s9s_mb_2u_lib.s9s_mb_2u(sch_1):page217_i59@pure_quanta.q_cap(chips)',
 PATH='I59',
 DRAWING='@S9S_MB_2U_LIB.S9S_MB_2U(SCH_1):PAGE202',
 PHYS_PAGE='217',
 XY='(-575,-1000)',
 ROT='0',
 VER='1',
 PACK_TYPE='C0402',
 CDS_LIB='pure_quanta',
 CDS_PART_NAME='Q_CAP_C0402-0.01UF,50V,10%,X7RA',
 TOLERANCE='10%',
 MATERIAL='X7R',
 VOLTAGE='50V',
 VALUE='0.01UF',
 PRIM_FILE='./archive_libs/logical/q_cap/chips/chips.prt';

PART_NAME
 C1910 'Q_CAP_C0402-0.01UF,50V,10%,X7RA':;

SECTION_NUMBER 1
 '@S9S_MB_2U_LIB.S9S_MB_2U(SCH_1):PAGE202_I44@PURE_QUANTA.Q_CAP(CHIPS)':
 C_PATH='@s9s_mb_2u_lib.s9s_mb_2u(sch_1):page202_i44@pure_quanta.q_cap(chips)',
 P_PATH='@s9s_mb_2u_lib.s9s_mb_2u(sch_1):page217_i44@pure_quanta.q_cap(chips)',
 PATH='I44',
 DRAWING='@S9S_MB_2U_LIB.S9S_MB_2U(SCH_1):PAGE202',
 PHYS_PAGE='217',
 XY='(-525,1150)',
 ROT='0',
 VER='1',
 PACK_TYPE='C0402',
 CDS_LIB='pure_quanta',
 CDS_PART_NAME='Q_CAP_C0402-0.01UF,50V,10%,X7RA',
 TOLERANCE='10%',
 MATERIAL='X7R',
 VOLTAGE='50V',
 VALUE='0.01UF',
 PRIM_FILE='./archive_libs/logical/q_cap/chips/chips.prt';

PART_NAME
 C1911 'Q_CAP_C0402-0.01UF,50V,10%,X7RA':;

SECTION_NUMBER 1
 '@S9S_MB_2U_LIB.S9S_MB_2U(SCH_1):PAGE202_I48@PURE_QUANTA.Q_CAP(CHIPS)':
 C_PATH='@s9s_mb_2u_lib.s9s_mb_2u(sch_1):page202_i48@pure_quanta.q_cap(chips)',
 P_PATH='@s9s_mb_2u_lib.s9s_mb_2u(sch_1):page217_i48@pure_quanta.q_cap(chips)',
 PATH='I48',
 DRAWING='@S9S_MB_2U_LIB.S9S_MB_2U(SCH_1):PAGE202',
 PHYS_PAGE='217',
 XY='(-600,125)',
 ROT='0',
 VER='1',
 PACK_TYPE='C0402',
 CDS_LIB='pure_quanta',
 CDS_PART_NAME='Q_CAP_C0402-0.01UF,50V,10%,X7RA',
 TOLERANCE='10%',
 MATERIAL='X7R',
 VOLTAGE='50V',
 VALUE='0.01UF',
 PRIM_FILE='./archive_libs/logical/q_cap/chips/chips.prt';

PART_NAME
 C1912 'Q_CAP_C0402-0.01UF,50V,10%,X7RA':;

SECTION_NUMBER 1
 '@S9S_MB_2U_LIB.S9S_MB_2U(SCH_1):PAGE202_I28@PURE_QUANTA.Q_CAP(CHIPS)':
 C_PATH='@s9s_mb_2u_lib.s9s_mb_2u(sch_1):page202_i28@pure_quanta.q_cap(chips)',
 P_PATH='@s9s_mb_2u_lib.s9s_mb_2u(sch_1):page217_i28@pure_quanta.q_cap(chips)',
 PATH='I28',
 DRAWING='@S9S_MB_2U_LIB.S9S_MB_2U(SCH_1):PAGE202',
 PHYS_PAGE='217',
 XY='(-575,2400)',
 ROT='0',
 VER='1',
 PACK_TYPE='C0402',
 CDS_LIB='pure_quanta',
 CDS_PART_NAME='Q_CAP_C0402-0.01UF,50V,10%,X7RA',
 TOLERANCE='10%',
 MATERIAL='X7R',
 VOLTAGE='50V',
 VALUE='0.01UF',
 PRIM_FILE='./archive_libs/logical/q_cap/chips/chips.prt';

PART_NAME
 C1913 'Q_CAP_C0402-0.01UF,50V,10%,X7RA':;

SECTION_NUMBER 1
 '@S9S_MB_2U_LIB.S9S_MB_2U(SCH_1):PAGE202_I53@PURE_QUANTA.Q_CAP(CHIPS)':
 C_PATH='@s9s_mb_2u_lib.s9s_mb_2u(sch_1):page202_i53@pure_quanta.q_cap(chips)',
 P_PATH='@s9s_mb_2u_lib.s9s_mb_2u(sch_1):page217_i53@pure_quanta.q_cap(chips)',
 PATH='I53',
 DRAWING='@S9S_MB_2U_LIB.S9S_MB_2U(SCH_1):PAGE202',
 PHYS_PAGE='217',
 XY='(1225,-2225)',
 ROT='0',
 VER='1',
 PACK_TYPE='C0402',
 CDS_LIB='pure_quanta',
 CDS_PART_NAME='Q_CAP_C0402-0.01UF,50V,10%,X7RA',
 TOLERANCE='10%',
 MATERIAL='X7R',
 VOLTAGE='50V',
 VALUE='0.01UF',
 PRIM_FILE='./archive_libs/logical/q_cap/chips/chips.prt';

PART_NAME
 C1914 'Q_CAP_C0402-0.01UF,50V,10%,X7RA':;

SECTION_NUMBER 1
 '@S9S_MB_2U_LIB.S9S_MB_2U(SCH_1):PAGE202_I36@PURE_QUANTA.Q_CAP(CHIPS)':
 C_PATH='@s9s_mb_2u_lib.s9s_mb_2u(sch_1):page202_i36@pure_quanta.q_cap(chips)',
 P_PATH='@s9s_mb_2u_lib.s9s_mb_2u(sch_1):page217_i36@pure_quanta.q_cap(chips)',
 PATH='I36',
 DRAWING='@S9S_MB_2U_LIB.S9S_MB_2U(SCH_1):PAGE202',
 PHYS_PAGE='217',
 XY='(500,1150)',
 ROT='0',
 VER='1',
 PACK_TYPE='C0402',
 CDS_LIB='pure_quanta',
 CDS_PART_NAME='Q_CAP_C0402-0.01UF,50V,10%,X7RA',
 TOLERANCE='10%',
 MATERIAL='X7R',
 VOLTAGE='50V',
 VALUE='0.01UF',
 PRIM_FILE='./archive_libs/logical/q_cap/chips/chips.prt';

PART_NAME
 C1915 'Q_CAP_C0402-0.01UF,50V,10%,X7RA':;

SECTION_NUMBER 1
 '@S9S_MB_2U_LIB.S9S_MB_2U(SCH_1):PAGE202_I40@PURE_QUANTA.Q_CAP(CHIPS)':
 C_PATH='@s9s_mb_2u_lib.s9s_mb_2u(sch_1):page202_i40@pure_quanta.q_cap(chips)',
 P_PATH='@s9s_mb_2u_lib.s9s_mb_2u(sch_1):page217_i40@pure_quanta.q_cap(chips)',
 PATH='I40',
 DRAWING='@S9S_MB_2U_LIB.S9S_MB_2U(SCH_1):PAGE202',
 PHYS_PAGE='217',
 XY='(425,125)',
 ROT='0',
 VER='1',
 PACK_TYPE='C0402',
 CDS_LIB='pure_quanta',
 CDS_PART_NAME='Q_CAP_C0402-0.01UF,50V,10%,X7RA',
 TOLERANCE='10%',
 MATERIAL='X7R',
 VOLTAGE='50V',
 VALUE='0.01UF',
 PRIM_FILE='./archive_libs/logical/q_cap/chips/chips.prt';

PART_NAME
 C1916 'Q_CAP_C0402-0.01UF,50V,10%,X7RA':;

SECTION_NUMBER 1
 '@S9S_MB_2U_LIB.S9S_MB_2U(SCH_1):PAGE202_I24@PURE_QUANTA.Q_CAP(CHIPS)':
 C_PATH='@s9s_mb_2u_lib.s9s_mb_2u(sch_1):page202_i24@pure_quanta.q_cap(chips)',
 P_PATH='@s9s_mb_2u_lib.s9s_mb_2u(sch_1):page217_i24@pure_quanta.q_cap(chips)',
 PATH='I24',
 DRAWING='@S9S_MB_2U_LIB.S9S_MB_2U(SCH_1):PAGE202',
 PHYS_PAGE='217',
 XY='(450,2375)',
 ROT='0',
 VER='1',
 PACK_TYPE='C0402',
 CDS_LIB='pure_quanta',
 CDS_PART_NAME='Q_CAP_C0402-0.01UF,50V,10%,X7RA',
 TOLERANCE='10%',
 MATERIAL='X7R',
 VOLTAGE='50V',
 VALUE='0.01UF',
 PRIM_FILE='./archive_libs/logical/q_cap/chips/chips.prt';

PART_NAME
 C1917 'Q_CAP_C0402-0.01UF,50V,10%,X7RA':;

SECTION_NUMBER 1
 '@S9S_MB_2U_LIB.S9S_MB_2U(SCH_1):PAGE202_I35@PURE_QUANTA.Q_CAP(CHIPS)':
 C_PATH='@s9s_mb_2u_lib.s9s_mb_2u(sch_1):page202_i35@pure_quanta.q_cap(chips)',
 P_PATH='@s9s_mb_2u_lib.s9s_mb_2u(sch_1):page217_i35@pure_quanta.q_cap(chips)',
 PATH='I35',
 DRAWING='@S9S_MB_2U_LIB.S9S_MB_2U(SCH_1):PAGE202',
 PHYS_PAGE='217',
 XY='(750,1150)',
 ROT='0',
 VER='1',
 PACK_TYPE='C0402',
 CDS_LIB='pure_quanta',
 CDS_PART_NAME='Q_CAP_C0402-0.01UF,50V,10%,X7RA',
 TOLERANCE='10%',
 MATERIAL='X7R',
 VOLTAGE='50V',
 VALUE='0.01UF',
 PRIM_FILE='./archive_libs/logical/q_cap/chips/chips.prt';

PART_NAME
 C1918 'Q_CAP_C0402-0.01UF,50V,10%,X7RA':;

SECTION_NUMBER 1
 '@S9S_MB_2U_LIB.S9S_MB_2U(SCH_1):PAGE202_I39@PURE_QUANTA.Q_CAP(CHIPS)':
 C_PATH='@s9s_mb_2u_lib.s9s_mb_2u(sch_1):page202_i39@pure_quanta.q_cap(chips)',
 P_PATH='@s9s_mb_2u_lib.s9s_mb_2u(sch_1):page217_i39@pure_quanta.q_cap(chips)',
 PATH='I39',
 DRAWING='@S9S_MB_2U_LIB.S9S_MB_2U(SCH_1):PAGE202',
 PHYS_PAGE='217',
 XY='(675,125)',
 ROT='0',
 VER='1',
 PACK_TYPE='C0402',
 CDS_LIB='pure_quanta',
 CDS_PART_NAME='Q_CAP_C0402-0.01UF,50V,10%,X7RA',
 TOLERANCE='10%',
 MATERIAL='X7R',
 VOLTAGE='50V',
 VALUE='0.01UF',
 PRIM_FILE='./archive_libs/logical/q_cap/chips/chips.prt';

PART_NAME
 C1919 'Q_CAP_C0402-0.01UF,50V,10%,X7RA':;

SECTION_NUMBER 1
 '@S9S_MB_2U_LIB.S9S_MB_2U(SCH_1):PAGE202_I23@PURE_QUANTA.Q_CAP(CHIPS)':
 C_PATH='@s9s_mb_2u_lib.s9s_mb_2u(sch_1):page202_i23@pure_quanta.q_cap(chips)',
 P_PATH='@s9s_mb_2u_lib.s9s_mb_2u(sch_1):page217_i23@pure_quanta.q_cap(chips)',
 PATH='I23',
 DRAWING='@S9S_MB_2U_LIB.S9S_MB_2U(SCH_1):PAGE202',
 PHYS_PAGE='217',
 XY='(700,2375)',
 ROT='0',
 VER='1',
 PACK_TYPE='C0402',
 CDS_LIB='pure_quanta',
 CDS_PART_NAME='Q_CAP_C0402-0.01UF,50V,10%,X7RA',
 TOLERANCE='10%',
 MATERIAL='X7R',
 VOLTAGE='50V',
 VALUE='0.01UF',
 PRIM_FILE='./archive_libs/logical/q_cap/chips/chips.prt';

PART_NAME
 C1920 'Q_CAP_C0603-22UF,6.3V,20%,X6S,A':;

SECTION_NUMBER 1
 '@S9S_MB_2U_LIB.S9S_MB_2U(SCH_1):PAGE182_I88@PURE_QUANTA.Q_CAP(CHIPS)':
 C_PATH='@s9s_mb_2u_lib.s9s_mb_2u(sch_1):page182_i88@pure_quanta.q_cap(chips)',
 P_PATH='@s9s_mb_2u_lib.s9s_mb_2u(sch_1):page190_i88@pure_quanta.q_cap(chips)',
 PATH='I88',
 DRAWING='@S9S_MB_2U_LIB.S9S_MB_2U(SCH_1):PAGE182',
 PHYS_PAGE='190',
 XY='(11275,4275)',
 ROT='0',
 VER='1',
 PACK_TYPE='C0603',
 LOCATION='C1920',
 CDS_LIB='pure_quanta',
 CDS_PART_NAME='Q_CAP_C0603-22UF,6.3V,20%,X6S,A',
 TOLERANCE='20%',
 MATERIAL='X6S',
 VOLTAGE='6.3V',
 VALUE='22UF',
 PRIM_FILE='./archive_libs/logical/q_cap/chips/chips.prt';

PART_NAME
 C1921 'Q_CAP_C0603-22UF,6.3V,20%,X6S,A':;

SECTION_NUMBER 1
 '@S9S_MB_2U_LIB.S9S_MB_2U(SCH_1):PAGE182_I90@PURE_QUANTA.Q_CAP(CHIPS)':
 C_PATH='@s9s_mb_2u_lib.s9s_mb_2u(sch_1):page182_i90@pure_quanta.q_cap(chips)',
 P_PATH='@s9s_mb_2u_lib.s9s_mb_2u(sch_1):page190_i90@pure_quanta.q_cap(chips)',
 PATH='I90',
 DRAWING='@S9S_MB_2U_LIB.S9S_MB_2U(SCH_1):PAGE182',
 PHYS_PAGE='190',
 XY='(11675,4275)',
 ROT='0',
 VER='1',
 PACK_TYPE='C0603',
 LOCATION='C1921',
 CDS_LIB='pure_quanta',
 CDS_PART_NAME='Q_CAP_C0603-22UF,6.3V,20%,X6S,A',
 TOLERANCE='20%',
 MATERIAL='X6S',
 VOLTAGE='6.3V',
 VALUE='22UF',
 PRIM_FILE='./archive_libs/logical/q_cap/chips/chips.prt';

PART_NAME
 C1922 'Q_CAP_C0603-22UF,6.3V,20%,X6S,A':;

SECTION_NUMBER 1
 '@S9S_MB_2U_LIB.S9S_MB_2U(SCH_1):PAGE182_I96@PURE_QUANTA.Q_CAP(CHIPS)':
 C_PATH='@s9s_mb_2u_lib.s9s_mb_2u(sch_1):page182_i96@pure_quanta.q_cap(chips)',
 P_PATH='@s9s_mb_2u_lib.s9s_mb_2u(sch_1):page190_i96@pure_quanta.q_cap(chips)',
 PATH='I96',
 DRAWING='@S9S_MB_2U_LIB.S9S_MB_2U(SCH_1):PAGE182',
 PHYS_PAGE='190',
 XY='(12075,4275)',
 ROT='0',
 VER='1',
 PACK_TYPE='C0603',
 LOCATION='C1922',
 CDS_LIB='pure_quanta',
 CDS_PART_NAME='Q_CAP_C0603-22UF,6.3V,20%,X6S,A',
 TOLERANCE='20%',
 MATERIAL='X6S',
 VOLTAGE='6.3V',
 VALUE='22UF',
 PRIM_FILE='./archive_libs/logical/q_cap/chips/chips.prt';

PART_NAME
 C1923 'Q_CAP_0402-0.1UF,25V,10%,X7R,CA':;

SECTION_NUMBER 1
 '@S9S_MB_2U_LIB.S9S_MB_2U(SCH_1):PAGE182_I97@PURE_QUANTA.Q_CAP(CHIPS)':
 C_PATH='@s9s_mb_2u_lib.s9s_mb_2u(sch_1):page182_i97@pure_quanta.q_cap(chips)',
 P_PATH='@s9s_mb_2u_lib.s9s_mb_2u(sch_1):page190_i97@pure_quanta.q_cap(chips)',
 PATH='I97',
 DRAWING='@S9S_MB_2U_LIB.S9S_MB_2U(SCH_1):PAGE182',
 PHYS_PAGE='190',
 XY='(12475,4275)',
 ROT='0',
 VER='1',
 PACK_TYPE='0402',
 LOCATION='C1923',
 CDS_LIB='pure_quanta',
 CDS_PART_NAME='Q_CAP_0402-0.1UF,25V,10%,X7R,CA',
 TOLERANCE='10%',
 MATERIAL='X7R',
 VOLTAGE='25V',
 VALUE='0.1UF',
 PRIM_FILE='./archive_libs/logical/q_cap/chips/chips.prt';

PART_NAME
 C1924 'Q_CAP_0402-0.1UF,25V,10%,X7R,CA':;

SECTION_NUMBER 1
 '@S9S_MB_2U_LIB.S9S_MB_2U(SCH_1):PAGE182_I98@PURE_QUANTA.Q_CAP(CHIPS)':
 C_PATH='@s9s_mb_2u_lib.s9s_mb_2u(sch_1):page182_i98@pure_quanta.q_cap(chips)',
 P_PATH='@s9s_mb_2u_lib.s9s_mb_2u(sch_1):page190_i98@pure_quanta.q_cap(chips)',
 PATH='I98',
 DRAWING='@S9S_MB_2U_LIB.S9S_MB_2U(SCH_1):PAGE182',
 PHYS_PAGE='190',
 XY='(12875,4275)',
 ROT='0',
 VER='1',
 PACK_TYPE='0402',
 LOCATION='C1924',
 CDS_LIB='pure_quanta',
 CDS_PART_NAME='Q_CAP_0402-0.1UF,25V,10%,X7R,CA',
 TOLERANCE='10%',
 MATERIAL='X7R',
 VOLTAGE='25V',
 VALUE='0.1UF',
 PRIM_FILE='./archive_libs/logical/q_cap/chips/chips.prt';

PART_NAME
 C1925 'Q_CAP_0402-0.1UF,25V,10%,X7R,CA':;

SECTION_NUMBER 1
 '@S9S_MB_2U_LIB.S9S_MB_2U(SCH_1):PAGE182_I100@PURE_QUANTA.Q_CAP(CHIPS)':
 C_PATH='@s9s_mb_2u_lib.s9s_mb_2u(sch_1):page182_i100@pure_quanta.q_cap(chips)',
 P_PATH='@s9s_mb_2u_lib.s9s_mb_2u(sch_1):page190_i100@pure_quanta.q_cap(chips)',
 PATH='I100',
 DRAWING='@S9S_MB_2U_LIB.S9S_MB_2U(SCH_1):PAGE182',
 PHYS_PAGE='190',
 XY='(13275,4275)',
 ROT='0',
 VER='1',
 PACK_TYPE='0402',
 LOCATION='C1925',
 CDS_LIB='pure_quanta',
 CDS_PART_NAME='Q_CAP_0402-0.1UF,25V,10%,X7R,CA',
 TOLERANCE='10%',
 MATERIAL='X7R',
 VOLTAGE='25V',
 VALUE='0.1UF',
 PRIM_FILE='./archive_libs/logical/q_cap/chips/chips.prt';

PART_NAME
 C1926 'Q_CAP_C0402-0.01UF,50V,10%,X7RA':;

SECTION_NUMBER 1
 '@S9S_MB_2U_LIB.S9S_MB_2U(SCH_1):PAGE202_I34@PURE_QUANTA.Q_CAP(CHIPS)':
 C_PATH='@s9s_mb_2u_lib.s9s_mb_2u(sch_1):page202_i34@pure_quanta.q_cap(chips)',
 P_PATH='@s9s_mb_2u_lib.s9s_mb_2u(sch_1):page217_i34@pure_quanta.q_cap(chips)',
 PATH='I34',
 DRAWING='@S9S_MB_2U_LIB.S9S_MB_2U(SCH_1):PAGE202',
 PHYS_PAGE='217',
 XY='(1000,1150)',
 ROT='0',
 VER='1',
 PACK_TYPE='C0402',
 CDS_LIB='pure_quanta',
 CDS_PART_NAME='Q_CAP_C0402-0.01UF,50V,10%,X7RA',
 TOLERANCE='10%',
 MATERIAL='X7R',
 VOLTAGE='50V',
 VALUE='0.01UF',
 PRIM_FILE='./archive_libs/logical/q_cap/chips/chips.prt';

PART_NAME
 C1927 'Q_CAP_C0402-0.01UF,50V,10%,X7RA':;

SECTION_NUMBER 1
 '@S9S_MB_2U_LIB.S9S_MB_2U(SCH_1):PAGE202_I38@PURE_QUANTA.Q_CAP(CHIPS)':
 C_PATH='@s9s_mb_2u_lib.s9s_mb_2u(sch_1):page202_i38@pure_quanta.q_cap(chips)',
 P_PATH='@s9s_mb_2u_lib.s9s_mb_2u(sch_1):page217_i38@pure_quanta.q_cap(chips)',
 PATH='I38',
 DRAWING='@S9S_MB_2U_LIB.S9S_MB_2U(SCH_1):PAGE202',
 PHYS_PAGE='217',
 XY='(925,125)',
 ROT='0',
 VER='1',
 PACK_TYPE='C0402',
 CDS_LIB='pure_quanta',
 CDS_PART_NAME='Q_CAP_C0402-0.01UF,50V,10%,X7RA',
 TOLERANCE='10%',
 MATERIAL='X7R',
 VOLTAGE='50V',
 VALUE='0.01UF',
 PRIM_FILE='./archive_libs/logical/q_cap/chips/chips.prt';

PART_NAME
 C1928 'Q_CAP_C0402-0.01UF,50V,10%,X7RA':;

SECTION_NUMBER 1
 '@S9S_MB_2U_LIB.S9S_MB_2U(SCH_1):PAGE202_I22@PURE_QUANTA.Q_CAP(CHIPS)':
 C_PATH='@s9s_mb_2u_lib.s9s_mb_2u(sch_1):page202_i22@pure_quanta.q_cap(chips)',
 P_PATH='@s9s_mb_2u_lib.s9s_mb_2u(sch_1):page217_i22@pure_quanta.q_cap(chips)',
 PATH='I22',
 DRAWING='@S9S_MB_2U_LIB.S9S_MB_2U(SCH_1):PAGE202',
 PHYS_PAGE='217',
 XY='(950,2375)',
 ROT='0',
 VER='1',
 PACK_TYPE='C0402',
 CDS_LIB='pure_quanta',
 CDS_PART_NAME='Q_CAP_C0402-0.01UF,50V,10%,X7RA',
 TOLERANCE='10%',
 MATERIAL='X7R',
 VOLTAGE='50V',
 VALUE='0.01UF',
 PRIM_FILE='./archive_libs/logical/q_cap/chips/chips.prt';

PART_NAME
 C1929 'Q_CAP_C0402-0.01UF,50V,10%,X7RA':;

SECTION_NUMBER 1
 '@S9S_MB_2U_LIB.S9S_MB_2U(SCH_1):PAGE202_I33@PURE_QUANTA.Q_CAP(CHIPS)':
 C_PATH='@s9s_mb_2u_lib.s9s_mb_2u(sch_1):page202_i33@pure_quanta.q_cap(chips)',
 P_PATH='@s9s_mb_2u_lib.s9s_mb_2u(sch_1):page217_i33@pure_quanta.q_cap(chips)',
 PATH='I33',
 DRAWING='@S9S_MB_2U_LIB.S9S_MB_2U(SCH_1):PAGE202',
 PHYS_PAGE='217',
 XY='(1250,1150)',
 ROT='0',
 VER='1',
 PACK_TYPE='C0402',
 CDS_LIB='pure_quanta',
 CDS_PART_NAME='Q_CAP_C0402-0.01UF,50V,10%,X7RA',
 TOLERANCE='10%',
 MATERIAL='X7R',
 VOLTAGE='50V',
 VALUE='0.01UF',
 PRIM_FILE='./archive_libs/logical/q_cap/chips/chips.prt';

PART_NAME
 C1930 'Q_CAP_C0402-0.01UF,50V,10%,X7RA':;

SECTION_NUMBER 1
 '@S9S_MB_2U_LIB.S9S_MB_2U(SCH_1):PAGE202_I37@PURE_QUANTA.Q_CAP(CHIPS)':
 C_PATH='@s9s_mb_2u_lib.s9s_mb_2u(sch_1):page202_i37@pure_quanta.q_cap(chips)',
 P_PATH='@s9s_mb_2u_lib.s9s_mb_2u(sch_1):page217_i37@pure_quanta.q_cap(chips)',
 PATH='I37',
 DRAWING='@S9S_MB_2U_LIB.S9S_MB_2U(SCH_1):PAGE202',
 PHYS_PAGE='217',
 XY='(1175,125)',
 ROT='0',
 VER='1',
 PACK_TYPE='C0402',
 CDS_LIB='pure_quanta',
 CDS_PART_NAME='Q_CAP_C0402-0.01UF,50V,10%,X7RA',
 TOLERANCE='10%',
 MATERIAL='X7R',
 VOLTAGE='50V',
 VALUE='0.01UF',
 PRIM_FILE='./archive_libs/logical/q_cap/chips/chips.prt';

PART_NAME
 C1931 'Q_CAP_C0402-0.01UF,50V,10%,X7RA':;

SECTION_NUMBER 1
 '@S9S_MB_2U_LIB.S9S_MB_2U(SCH_1):PAGE202_I21@PURE_QUANTA.Q_CAP(CHIPS)':
 C_PATH='@s9s_mb_2u_lib.s9s_mb_2u(sch_1):page202_i21@pure_quanta.q_cap(chips)',
 P_PATH='@s9s_mb_2u_lib.s9s_mb_2u(sch_1):page217_i21@pure_quanta.q_cap(chips)',
 PATH='I21',
 DRAWING='@S9S_MB_2U_LIB.S9S_MB_2U(SCH_1):PAGE202',
 PHYS_PAGE='217',
 XY='(1200,2375)',
 ROT='0',
 VER='1',
 PACK_TYPE='C0402',
 CDS_LIB='pure_quanta',
 CDS_PART_NAME='Q_CAP_C0402-0.01UF,50V,10%,X7RA',
 TOLERANCE='10%',
 MATERIAL='X7R',
 VOLTAGE='50V',
 VALUE='0.01UF',
 PRIM_FILE='./archive_libs/logical/q_cap/chips/chips.prt';

PART_NAME
 C1932 'Q_CAP_C0402-0.01UF,50V,10%,X7RA':;

SECTION_NUMBER 1
 '@S9S_MB_2U_LIB.S9S_MB_2U(SCH_1):PAGE202_I9@PURE_QUANTA.Q_CAP(CHIPS)':
 C_PATH='@s9s_mb_2u_lib.s9s_mb_2u(sch_1):page202_i9@pure_quanta.q_cap(chips)',
 P_PATH='@s9s_mb_2u_lib.s9s_mb_2u(sch_1):page217_i9@pure_quanta.q_cap(chips)',
 PATH='I9',
 DRAWING='@S9S_MB_2U_LIB.S9S_MB_2U(SCH_1):PAGE202',
 PHYS_PAGE='217',
 XY='(1500,1150)',
 ROT='0',
 VER='1',
 PACK_TYPE='C0402',
 CDS_LIB='pure_quanta',
 CDS_PART_NAME='Q_CAP_C0402-0.01UF,50V,10%,X7RA',
 TOLERANCE='10%',
 MATERIAL='X7R',
 VOLTAGE='50V',
 VALUE='0.01UF',
 PRIM_FILE='./archive_libs/logical/q_cap/chips/chips.prt';

PART_NAME
 C1933 'Q_CAP_C0402-0.01UF,50V,10%,X7RA':;

SECTION_NUMBER 1
 '@S9S_MB_2U_LIB.S9S_MB_2U(SCH_1):PAGE202_I12@PURE_QUANTA.Q_CAP(CHIPS)':
 C_PATH='@s9s_mb_2u_lib.s9s_mb_2u(sch_1):page202_i12@pure_quanta.q_cap(chips)',
 P_PATH='@s9s_mb_2u_lib.s9s_mb_2u(sch_1):page217_i12@pure_quanta.q_cap(chips)',
 PATH='I12',
 DRAWING='@S9S_MB_2U_LIB.S9S_MB_2U(SCH_1):PAGE202',
 PHYS_PAGE='217',
 XY='(1425,125)',
 ROT='0',
 VER='1',
 PACK_TYPE='C0402',
 CDS_LIB='pure_quanta',
 CDS_PART_NAME='Q_CAP_C0402-0.01UF,50V,10%,X7RA',
 TOLERANCE='10%',
 MATERIAL='X7R',
 VOLTAGE='50V',
 VALUE='0.01UF',
 PRIM_FILE='./archive_libs/logical/q_cap/chips/chips.prt';

PART_NAME
 C1934 'Q_CAP_C0402-0.01UF,50V,10%,X7RA':;

SECTION_NUMBER 1
 '@S9S_MB_2U_LIB.S9S_MB_2U(SCH_1):PAGE202_I120@PURE_QUANTA.Q_CAP(CHIPS)':
 C_PATH='@s9s_mb_2u_lib.s9s_mb_2u(sch_1):page202_i120@pure_quanta.q_cap(chips)',
 P_PATH='@s9s_mb_2u_lib.s9s_mb_2u(sch_1):page217_i120@pure_quanta.q_cap(chips)',
 PATH='I120',
 DRAWING='@S9S_MB_2U_LIB.S9S_MB_2U(SCH_1):PAGE202',
 PHYS_PAGE='217',
 XY='(1700,2375)',
 ROT='0',
 VER='1',
 PACK_TYPE='C0402',
 CDS_LIB='pure_quanta',
 CDS_PART_NAME='Q_CAP_C0402-0.01UF,50V,10%,X7RA',
 TOLERANCE='10%',
 MATERIAL='X7R',
 VOLTAGE='50V',
 VALUE='0.01UF',
 PRIM_FILE='./archive_libs/logical/q_cap/chips/chips.prt';

PART_NAME
 C1935 'Q_CAP_C0402-10UF,6.3V,20%,X6S,A':;

SECTION_NUMBER 1
 '@S9S_MB_2U_LIB.S9S_MB_2U(SCH_1):PAGE202_I82@PURE_QUANTA.Q_CAP(CHIPS)':
 C_PATH='@s9s_mb_2u_lib.s9s_mb_2u(sch_1):page202_i82@pure_quanta.q_cap(chips)',
 P_PATH='@s9s_mb_2u_lib.s9s_mb_2u(sch_1):page217_i82@pure_quanta.q_cap(chips)',
 PATH='I82',
 DRAWING='@S9S_MB_2U_LIB.S9S_MB_2U(SCH_1):PAGE202',
 PHYS_PAGE='217',
 XY='(-2400,-2150)',
 ROT='0',
 VER='1',
 PACK_TYPE='C0402',
 CDS_LIB='pure_quanta',
 CDS_PART_NAME='Q_CAP_C0402-10UF,6.3V,20%,X6S,A',
 TOLERANCE='20%',
 MATERIAL='X6S',
 VOLTAGE='6.3V',
 VALUE='10UF',
 PRIM_FILE='./archive_libs/logical/q_cap/chips/chips.prt';

PART_NAME
 C1936 'Q_CAP_C0402-10UF,6.3V,20%,X6S,A':;

SECTION_NUMBER 1
 '@S9S_MB_2U_LIB.S9S_MB_2U(SCH_1):PAGE202_I30@PURE_QUANTA.Q_CAP(CHIPS)':
 C_PATH='@s9s_mb_2u_lib.s9s_mb_2u(sch_1):page202_i30@pure_quanta.q_cap(chips)',
 P_PATH='@s9s_mb_2u_lib.s9s_mb_2u(sch_1):page217_i30@pure_quanta.q_cap(chips)',
 PATH='I30',
 DRAWING='@S9S_MB_2U_LIB.S9S_MB_2U(SCH_1):PAGE202',
 PHYS_PAGE='217',
 XY='(-1275,2400)',
 ROT='0',
 VER='1',
 PACK_TYPE='C0402',
 CDS_LIB='pure_quanta',
 CDS_PART_NAME='Q_CAP_C0402-10UF,6.3V,20%,X6S,A',
 TOLERANCE='20%',
 MATERIAL='X6S',
 VOLTAGE='6.3V',
 VALUE='10UF',
 PRIM_FILE='./archive_libs/logical/q_cap/chips/chips.prt';

PART_NAME
 C1937 'Q_CAP_C0402-10UF,6.3V,20%,X6S,A':;

SECTION_NUMBER 1
 '@S9S_MB_2U_LIB.S9S_MB_2U(SCH_1):PAGE202_I71@PURE_QUANTA.Q_CAP(CHIPS)':
 C_PATH='@s9s_mb_2u_lib.s9s_mb_2u(sch_1):page202_i71@pure_quanta.q_cap(chips)',
 P_PATH='@s9s_mb_2u_lib.s9s_mb_2u(sch_1):page217_i71@pure_quanta.q_cap(chips)',
 PATH='I71',
 DRAWING='@S9S_MB_2U_LIB.S9S_MB_2U(SCH_1):PAGE202',
 PHYS_PAGE='217',
 XY='(-1225,-975)',
 ROT='0',
 VER='1',
 PACK_TYPE='C0402',
 CDS_LIB='pure_quanta',
 CDS_PART_NAME='Q_CAP_C0402-10UF,6.3V,20%,X6S,A',
 TOLERANCE='20%',
 MATERIAL='X6S',
 VOLTAGE='6.3V',
 VALUE='10UF',
 PRIM_FILE='./archive_libs/logical/q_cap/chips/chips.prt';

PART_NAME
 C1938 'Q_CAP_C0402-10UF,6.3V,20%,X6S,A':;

SECTION_NUMBER 1
 '@S9S_MB_2U_LIB.S9S_MB_2U(SCH_1):PAGE202_I64@PURE_QUANTA.Q_CAP(CHIPS)':
 C_PATH='@s9s_mb_2u_lib.s9s_mb_2u(sch_1):page202_i64@pure_quanta.q_cap(chips)',
 P_PATH='@s9s_mb_2u_lib.s9s_mb_2u(sch_1):page217_i64@pure_quanta.q_cap(chips)',
 PATH='I64',
 DRAWING='@S9S_MB_2U_LIB.S9S_MB_2U(SCH_1):PAGE202',
 PHYS_PAGE='217',
 XY='(-1175,1175)',
 ROT='0',
 VER='1',
 PACK_TYPE='C0402',
 CDS_LIB='pure_quanta',
 CDS_PART_NAME='Q_CAP_C0402-10UF,6.3V,20%,X6S,A',
 TOLERANCE='20%',
 MATERIAL='X6S',
 VOLTAGE='6.3V',
 VALUE='10UF',
 PRIM_FILE='./archive_libs/logical/q_cap/chips/chips.prt';

PART_NAME
 C1939 'Q_CAP_C0402-10UF,6.3V,20%,X6S,A':;

SECTION_NUMBER 1
 '@S9S_MB_2U_LIB.S9S_MB_2U(SCH_1):PAGE202_I66@PURE_QUANTA.Q_CAP(CHIPS)':
 C_PATH='@s9s_mb_2u_lib.s9s_mb_2u(sch_1):page202_i66@pure_quanta.q_cap(chips)',
 P_PATH='@s9s_mb_2u_lib.s9s_mb_2u(sch_1):page217_i66@pure_quanta.q_cap(chips)',
 PATH='I66',
 DRAWING='@S9S_MB_2U_LIB.S9S_MB_2U(SCH_1):PAGE202',
 PHYS_PAGE='217',
 XY='(-1250,150)',
 ROT='0',
 VER='1',
 PACK_TYPE='C0402',
 CDS_LIB='pure_quanta',
 CDS_PART_NAME='Q_CAP_C0402-10UF,6.3V,20%,X6S,A',
 TOLERANCE='20%',
 MATERIAL='X6S',
 VOLTAGE='6.3V',
 VALUE='10UF',
 PRIM_FILE='./archive_libs/logical/q_cap/chips/chips.prt';

PART_NAME
 C1940 'Q_CAP_C0402-10UF,6.3V,20%,X6S,A':;

SECTION_NUMBER 1
 '@S9S_MB_2U_LIB.S9S_MB_2U(SCH_1):PAGE202_I55@PURE_QUANTA.Q_CAP(CHIPS)':
 C_PATH='@s9s_mb_2u_lib.s9s_mb_2u(sch_1):page202_i55@pure_quanta.q_cap(chips)',
 P_PATH='@s9s_mb_2u_lib.s9s_mb_2u(sch_1):page217_i55@pure_quanta.q_cap(chips)',
 PATH='I55',
 DRAWING='@S9S_MB_2U_LIB.S9S_MB_2U(SCH_1):PAGE202',
 PHYS_PAGE='217',
 XY='(575,-2200)',
 ROT='0',
 VER='1',
 PACK_TYPE='C0402',
 CDS_LIB='pure_quanta',
 CDS_PART_NAME='Q_CAP_C0402-10UF,6.3V,20%,X6S,A',
 TOLERANCE='20%',
 MATERIAL='X6S',
 VOLTAGE='6.3V',
 VALUE='10UF',
 PRIM_FILE='./archive_libs/logical/q_cap/chips/chips.prt';

PART_NAME
 C1941 'Q_CAP_0402-0.1UF,25V,10%,X7R,CA':;

SECTION_NUMBER 1
 '@S9S_MB_2U_LIB.S9S_MB_2U(SCH_1):PAGE202_I101@PURE_QUANTA.Q_CAP(CHIPS)':
 C_PATH='@s9s_mb_2u_lib.s9s_mb_2u(sch_1):page202_i101@pure_quanta.q_cap(chips)',
 P_PATH='@s9s_mb_2u_lib.s9s_mb_2u(sch_1):page217_i101@pure_quanta.q_cap(chips)',
 PATH='I101',
 DRAWING='@S9S_MB_2U_LIB.S9S_MB_2U(SCH_1):PAGE202',
 PHYS_PAGE='217',
 XY='(-4800,-2125)',
 ROT='0',
 VER='1',
 PACK_TYPE='0402',
 CDS_LIB='pure_quanta',
 CDS_PART_NAME='Q_CAP_0402-0.1UF,25V,10%,X7R,CA',
 TOLERANCE='10%',
 MATERIAL='X7R',
 VOLTAGE='25V',
 VALUE='0.1UF',
 PRIM_FILE='./archive_libs/logical/q_cap/chips/chips.prt';

PART_NAME
 C1942 'Q_CAP_0402-0.1UF,25V,10%,X7R,CA':;

SECTION_NUMBER 1
 '@S9S_MB_2U_LIB.S9S_MB_2U(SCH_1):PAGE202_I80@PURE_QUANTA.Q_CAP(CHIPS)':
 C_PATH='@s9s_mb_2u_lib.s9s_mb_2u(sch_1):page202_i80@pure_quanta.q_cap(chips)',
 P_PATH='@s9s_mb_2u_lib.s9s_mb_2u(sch_1):page217_i80@pure_quanta.q_cap(chips)',
 PATH='I80',
 DRAWING='@S9S_MB_2U_LIB.S9S_MB_2U(SCH_1):PAGE202',
 PHYS_PAGE='217',
 XY='(-2050,-2175)',
 ROT='0',
 VER='1',
 PACK_TYPE='0402',
 CDS_LIB='pure_quanta',
 CDS_PART_NAME='Q_CAP_0402-0.1UF,25V,10%,X7R,CA',
 TOLERANCE='10%',
 MATERIAL='X7R',
 VOLTAGE='25V',
 VALUE='0.1UF',
 PRIM_FILE='./archive_libs/logical/q_cap/chips/chips.prt';

PART_NAME
 C1943 'Q_CAP_0402-0.1UF,25V,10%,X7R,CA':;

SECTION_NUMBER 1
 '@S9S_MB_2U_LIB.S9S_MB_2U(SCH_1):PAGE202_I29@PURE_QUANTA.Q_CAP(CHIPS)':
 C_PATH='@s9s_mb_2u_lib.s9s_mb_2u(sch_1):page202_i29@pure_quanta.q_cap(chips)',
 P_PATH='@s9s_mb_2u_lib.s9s_mb_2u(sch_1):page217_i29@pure_quanta.q_cap(chips)',
 PATH='I29',
 DRAWING='@S9S_MB_2U_LIB.S9S_MB_2U(SCH_1):PAGE202',
 PHYS_PAGE='217',
 XY='(-925,2400)',
 ROT='0',
 VER='1',
 PACK_TYPE='0402',
 CDS_LIB='pure_quanta',
 CDS_PART_NAME='Q_CAP_0402-0.1UF,25V,10%,X7R,CA',
 TOLERANCE='10%',
 MATERIAL='X7R',
 VOLTAGE='25V',
 VALUE='0.1UF',
 PRIM_FILE='./archive_libs/logical/q_cap/chips/chips.prt';

PART_NAME
 C1944 'Q_CAP_0402-0.1UF,25V,10%,X7R,CA':;

SECTION_NUMBER 1
 '@S9S_MB_2U_LIB.S9S_MB_2U(SCH_1):PAGE202_I70@PURE_QUANTA.Q_CAP(CHIPS)':
 C_PATH='@s9s_mb_2u_lib.s9s_mb_2u(sch_1):page202_i70@pure_quanta.q_cap(chips)',
 P_PATH='@s9s_mb_2u_lib.s9s_mb_2u(sch_1):page217_i70@pure_quanta.q_cap(chips)',
 PATH='I70',
 DRAWING='@S9S_MB_2U_LIB.S9S_MB_2U(SCH_1):PAGE202',
 PHYS_PAGE='217',
 XY='(-875,-1000)',
 ROT='0',
 VER='1',
 PACK_TYPE='0402',
 CDS_LIB='pure_quanta',
 CDS_PART_NAME='Q_CAP_0402-0.1UF,25V,10%,X7R,CA',
 TOLERANCE='10%',
 MATERIAL='X7R',
 VOLTAGE='25V',
 VALUE='0.1UF',
 PRIM_FILE='./archive_libs/logical/q_cap/chips/chips.prt';

PART_NAME
 C1945 'Q_CAP_0402-0.1UF,25V,10%,X7R,CA':;

SECTION_NUMBER 1
 '@S9S_MB_2U_LIB.S9S_MB_2U(SCH_1):PAGE202_I62@PURE_QUANTA.Q_CAP(CHIPS)':
 C_PATH='@s9s_mb_2u_lib.s9s_mb_2u(sch_1):page202_i62@pure_quanta.q_cap(chips)',
 P_PATH='@s9s_mb_2u_lib.s9s_mb_2u(sch_1):page217_i62@pure_quanta.q_cap(chips)',
 PATH='I62',
 DRAWING='@S9S_MB_2U_LIB.S9S_MB_2U(SCH_1):PAGE202',
 PHYS_PAGE='217',
 XY='(-825,1150)',
 ROT='0',
 VER='1',
 PACK_TYPE='0402',
 CDS_LIB='pure_quanta',
 CDS_PART_NAME='Q_CAP_0402-0.1UF,25V,10%,X7R,CA',
 TOLERANCE='10%',
 MATERIAL='X7R',
 VOLTAGE='25V',
 VALUE='0.1UF',
 PRIM_FILE='./archive_libs/logical/q_cap/chips/chips.prt';

PART_NAME
 C1946 'Q_CAP_0402-0.1UF,25V,10%,X7R,CA':;

SECTION_NUMBER 1
 '@S9S_MB_2U_LIB.S9S_MB_2U(SCH_1):PAGE202_I65@PURE_QUANTA.Q_CAP(CHIPS)':
 C_PATH='@s9s_mb_2u_lib.s9s_mb_2u(sch_1):page202_i65@pure_quanta.q_cap(chips)',
 P_PATH='@s9s_mb_2u_lib.s9s_mb_2u(sch_1):page217_i65@pure_quanta.q_cap(chips)',
 PATH='I65',
 DRAWING='@S9S_MB_2U_LIB.S9S_MB_2U(SCH_1):PAGE202',
 PHYS_PAGE='217',
 XY='(-900,125)',
 ROT='0',
 VER='1',
 PACK_TYPE='0402',
 CDS_LIB='pure_quanta',
 CDS_PART_NAME='Q_CAP_0402-0.1UF,25V,10%,X7R,CA',
 TOLERANCE='10%',
 MATERIAL='X7R',
 VOLTAGE='25V',
 VALUE='0.1UF',
 PRIM_FILE='./archive_libs/logical/q_cap/chips/chips.prt';

PART_NAME
 C1947 'Q_CAP_0402-0.1UF,25V,10%,X7R,CA':;

SECTION_NUMBER 1
 '@S9S_MB_2U_LIB.S9S_MB_2U(SCH_1):PAGE202_I54@PURE_QUANTA.Q_CAP(CHIPS)':
 C_PATH='@s9s_mb_2u_lib.s9s_mb_2u(sch_1):page202_i54@pure_quanta.q_cap(chips)',
 P_PATH='@s9s_mb_2u_lib.s9s_mb_2u(sch_1):page217_i54@pure_quanta.q_cap(chips)',
 PATH='I54',
 DRAWING='@S9S_MB_2U_LIB.S9S_MB_2U(SCH_1):PAGE202',
 PHYS_PAGE='217',
 XY='(925,-2225)',
 ROT='0',
 VER='1',
 PACK_TYPE='0402',
 CDS_LIB='pure_quanta',
 CDS_PART_NAME='Q_CAP_0402-0.1UF,25V,10%,X7R,CA',
 TOLERANCE='10%',
 MATERIAL='X7R',
 VOLTAGE='25V',
 VALUE='0.1UF',
 PRIM_FILE='./archive_libs/logical/q_cap/chips/chips.prt';

PART_NAME
 C1957 'Q_CAP_0402-0.1UF,25V,10%,X7R,CA':;

SECTION_NUMBER 1
 '@S9S_MB_2U_LIB.S9S_MB_2U(SCH_1):PAGE160_I148@PURE_QUANTA.Q_CAP(CHIPS)':
 C_PATH='@s9s_mb_2u_lib.s9s_mb_2u(sch_1):page160_i148@pure_quanta.q_cap(chips)',
 P_PATH='@s9s_mb_2u_lib.s9s_mb_2u(sch_1):page149_i148@pure_quanta.q_cap(chips)',
 PATH='I148',
 DRAWING='@S9S_MB_2U_LIB.S9S_MB_2U(SCH_1):PAGE160',
 PHYS_PAGE='149',
 XY='(-6075,2175)',
 ROT='0',
 VER='1',
 PACK_TYPE='0402',
 CDS_LIB='pure_quanta',
 CDS_PART_NAME='Q_CAP_0402-0.1UF,25V,10%,X7R,CA',
 TOLERANCE='10%',
 MATERIAL='X7R',
 VOLTAGE='25V',
 VALUE='0.1UF',
 PRIM_FILE='./archive_libs/logical/q_cap/chips/chips.prt';

PART_NAME
 C1958 'Q_CAP_0402-0.1UF,25V,10%,X7R,CA':;

SECTION_NUMBER 1
 '@S9S_MB_2U_LIB.S9S_MB_2U(SCH_1):PAGE160_I29@PURE_QUANTA.Q_CAP(CHIPS)':
 C_PATH='@s9s_mb_2u_lib.s9s_mb_2u(sch_1):page160_i29@pure_quanta.q_cap(chips)',
 P_PATH='@s9s_mb_2u_lib.s9s_mb_2u(sch_1):page149_i29@pure_quanta.q_cap(chips)',
 PATH='I29',
 DRAWING='@S9S_MB_2U_LIB.S9S_MB_2U(SCH_1):PAGE160',
 PHYS_PAGE='149',
 XY='(-5975,4500)',
 ROT='0',
 VER='1',
 PACK_TYPE='0402',
 CDS_LIB='pure_quanta',
 CDS_PART_NAME='Q_CAP_0402-0.1UF,25V,10%,X7R,CA',
 TOLERANCE='10%',
 MATERIAL='X7R',
 VOLTAGE='25V',
 VALUE='0.1UF',
 PRIM_FILE='./archive_libs/logical/q_cap/chips/chips.prt';

PART_NAME
 C1963 'Q_CAP_0402-0.1UF,25V,10%,X7R,CA':;

SECTION_NUMBER 1
 '@S9S_MB_2U_LIB.S9S_MB_2U(SCH_1):PAGE296_I13@PURE_QUANTA.Q_CAP(CHIPS)':
 C_PATH='@s9s_mb_2u_lib.s9s_mb_2u(sch_1):page296_i13@pure_quanta.q_cap(chips)',
 P_PATH='@s9s_mb_2u_lib.s9s_mb_2u(sch_1):page150_i13@pure_quanta.q_cap(chips)',
 PATH='I13',
 DRAWING='@S9S_MB_2U_LIB.S9S_MB_2U(SCH_1):PAGE296',
 PHYS_PAGE='150',
 XY='(1350,3550)',
 ROT='0',
 VER='1',
 PACK_TYPE='0402',
 CDS_LIB='pure_quanta',
 CDS_PART_NAME='Q_CAP_0402-0.1UF,25V,10%,X7R,CA',
 TOLERANCE='10%',
 MATERIAL='X7R',
 VOLTAGE='25V',
 VALUE='0.1UF',
 PRIM_FILE='./archive_libs/logical/q_cap/chips/chips.prt';

PART_NAME
 C1973 'Q_CAP_0402-1000PF,50V,5%,EMPTYA':;

SECTION_NUMBER 1
 '@S9S_MB_2U_LIB.S9S_MB_2U(SCH_1):PAGE299_I71@PURE_QUANTA.Q_CAP(CHIPS)':
 C_PATH='@s9s_mb_2u_lib.s9s_mb_2u(sch_1):page299_i71@pure_quanta.q_cap(chips)',
 P_PATH='@s9s_mb_2u_lib.s9s_mb_2u(sch_1):page147_i71@pure_quanta.q_cap(chips)',
 PATH='I71',
 DRAWING='@S9S_MB_2U_LIB.S9S_MB_2U(SCH_1):PAGE299',
 PHYS_PAGE='147',
 XY='(50,2650)',
 ROT='0',
 VER='1',
 PACK_TYPE='0402',
 CDS_LIB='pure_quanta',
 CDS_PART_NAME='Q_CAP_0402-1000PF,50V,5%,EMPTYA',
 TOLERANCE='5%',
 MATERIAL='EMPTY',
 VOLTAGE='50V',
 VALUE='1000PF',
 PRIM_FILE='./archive_libs/logical/q_cap/chips/chips.prt';

PART_NAME
 C1974 'Q_CAP_0402-1000PF,50V,5%,EMPTYA':;

SECTION_NUMBER 1
 '@S9S_MB_2U_LIB.S9S_MB_2U(SCH_1):PAGE299_I74@PURE_QUANTA.Q_CAP(CHIPS)':
 C_PATH='@s9s_mb_2u_lib.s9s_mb_2u(sch_1):page299_i74@pure_quanta.q_cap(chips)',
 P_PATH='@s9s_mb_2u_lib.s9s_mb_2u(sch_1):page147_i74@pure_quanta.q_cap(chips)',
 PATH='I74',
 DRAWING='@S9S_MB_2U_LIB.S9S_MB_2U(SCH_1):PAGE299',
 PHYS_PAGE='147',
 XY='(100,4025)',
 ROT='0',
 VER='1',
 PACK_TYPE='0402',
 CDS_LIB='pure_quanta',
 CDS_PART_NAME='Q_CAP_0402-1000PF,50V,5%,EMPTYA',
 TOLERANCE='5%',
 MATERIAL='EMPTY',
 VOLTAGE='50V',
 VALUE='1000PF',
 PRIM_FILE='./archive_libs/logical/q_cap/chips/chips.prt';

PART_NAME
 C1975 'Q_CAP_0402-1000PF,50V,5%,EMPTYA':;

SECTION_NUMBER 1
 '@S9S_MB_2U_LIB.S9S_MB_2U(SCH_1):PAGE299_I129@PURE_QUANTA.Q_CAP(CHIPS)':
 C_PATH='@s9s_mb_2u_lib.s9s_mb_2u(sch_1):page299_i129@pure_quanta.q_cap(chips)',
 P_PATH='@s9s_mb_2u_lib.s9s_mb_2u(sch_1):page147_i129@pure_quanta.q_cap(chips)',
 PATH='I129',
 DRAWING='@S9S_MB_2U_LIB.S9S_MB_2U(SCH_1):PAGE299',
 PHYS_PAGE='147',
 XY='(100,1300)',
 ROT='0',
 VER='1',
 PACK_TYPE='0402',
 CDS_LIB='pure_quanta',
 CDS_PART_NAME='Q_CAP_0402-1000PF,50V,5%,EMPTYA',
 TOLERANCE='5%',
 MATERIAL='EMPTY',
 VOLTAGE='50V',
 VALUE='1000PF',
 PRIM_FILE='./archive_libs/logical/q_cap/chips/chips.prt';

PART_NAME
 C1976 'Q_CAP_0402-1000PF,50V,5%,EMPTYA':;

SECTION_NUMBER 1
 '@S9S_MB_2U_LIB.S9S_MB_2U(SCH_1):PAGE299_I30@PURE_QUANTA.Q_CAP(CHIPS)':
 C_PATH='@s9s_mb_2u_lib.s9s_mb_2u(sch_1):page299_i30@pure_quanta.q_cap(chips)',
 P_PATH='@s9s_mb_2u_lib.s9s_mb_2u(sch_1):page147_i30@pure_quanta.q_cap(chips)',
 PATH='I30',
 DRAWING='@S9S_MB_2U_LIB.S9S_MB_2U(SCH_1):PAGE299',
 PHYS_PAGE='147',
 XY='(100,-450)',
 ROT='0',
 VER='1',
 PACK_TYPE='0402',
 CDS_LIB='pure_quanta',
 CDS_PART_NAME='Q_CAP_0402-1000PF,50V,5%,EMPTYA',
 TOLERANCE='5%',
 MATERIAL='EMPTY',
 VOLTAGE='50V',
 VALUE='1000PF',
 PRIM_FILE='./archive_libs/logical/q_cap/chips/chips.prt';

PART_NAME
 C1977 'Q_CAP_0402-0.1UF,25V,10%,X7R,CA':;

SECTION_NUMBER 1
 '@S9S_MB_2U_LIB.S9S_MB_2U(SCH_1):PAGE160_I175@PURE_QUANTA.Q_CAP(CHIPS)':
 C_PATH='@s9s_mb_2u_lib.s9s_mb_2u(sch_1):page160_i175@pure_quanta.q_cap(chips)',
 P_PATH='@s9s_mb_2u_lib.s9s_mb_2u(sch_1):page149_i175@pure_quanta.q_cap(chips)',
 PATH='I175',
 DRAWING='@S9S_MB_2U_LIB.S9S_MB_2U(SCH_1):PAGE160',
 PHYS_PAGE='149',
 XY='(-6175,300)',
 ROT='0',
 VER='1',
 PACK_TYPE='0402',
 CDS_LIB='pure_quanta',
 CDS_PART_NAME='Q_CAP_0402-0.1UF,25V,10%,X7R,CA',
 TOLERANCE='10%',
 MATERIAL='X7R',
 VOLTAGE='25V',
 VALUE='0.1UF',
 PRIM_FILE='./archive_libs/logical/q_cap/chips/chips.prt';

PART_NAME
 C1978 'Q_CAP_0402-1000PF,50V,5%,EMPTYA':;

SECTION_NUMBER 1
 '@S9S_MB_2U_LIB.S9S_MB_2U(SCH_1):PAGE299_I152@PURE_QUANTA.Q_CAP(CHIPS)':
 C_PATH='@s9s_mb_2u_lib.s9s_mb_2u(sch_1):page299_i152@pure_quanta.q_cap(chips)',
 P_PATH='@s9s_mb_2u_lib.s9s_mb_2u(sch_1):page147_i152@pure_quanta.q_cap(chips)',
 PATH='I152',
 DRAWING='@S9S_MB_2U_LIB.S9S_MB_2U(SCH_1):PAGE299',
 PHYS_PAGE='147',
 XY='(4800,2650)',
 ROT='0',
 VER='1',
 PACK_TYPE='0402',
 CDS_LIB='pure_quanta',
 CDS_PART_NAME='Q_CAP_0402-1000PF,50V,5%,EMPTYA',
 TOLERANCE='5%',
 MATERIAL='EMPTY',
 VOLTAGE='50V',
 VALUE='1000PF',
 PRIM_FILE='./archive_libs/logical/q_cap/chips/chips.prt';

PART_NAME
 C1979 'Q_CAP_0402-0.1UF,25V,10%,X7R,CA':;

SECTION_NUMBER 1
 '@S9S_MB_2U_LIB.S9S_MB_2U(SCH_1):PAGE296_I67@PURE_QUANTA.Q_CAP(CHIPS)':
 C_PATH='@s9s_mb_2u_lib.s9s_mb_2u(sch_1):page296_i67@pure_quanta.q_cap(chips)',
 P_PATH='@s9s_mb_2u_lib.s9s_mb_2u(sch_1):page150_i67@pure_quanta.q_cap(chips)',
 PATH='I67',
 DRAWING='@S9S_MB_2U_LIB.S9S_MB_2U(SCH_1):PAGE296',
 PHYS_PAGE='150',
 XY='(1350,1050)',
 ROT='0',
 VER='1',
 PACK_TYPE='0402',
 CDS_LIB='pure_quanta',
 CDS_PART_NAME='Q_CAP_0402-0.1UF,25V,10%,X7R,CA',
 TOLERANCE='10%',
 MATERIAL='X7R',
 VOLTAGE='25V',
 VALUE='0.1UF',
 PRIM_FILE='./archive_libs/logical/q_cap/chips/chips.prt';

PART_NAME
 C1988 'Q_CAP_0402-1000PF,50V,5%,EMPTYA':;

SECTION_NUMBER 1
 '@S9S_MB_2U_LIB.S9S_MB_2U(SCH_1):PAGE299_I171@PURE_QUANTA.Q_CAP(CHIPS)':
 C_PATH='@s9s_mb_2u_lib.s9s_mb_2u(sch_1):page299_i171@pure_quanta.q_cap(chips)',
 P_PATH='@s9s_mb_2u_lib.s9s_mb_2u(sch_1):page147_i171@pure_quanta.q_cap(chips)',
 PATH='I171',
 DRAWING='@S9S_MB_2U_LIB.S9S_MB_2U(SCH_1):PAGE299',
 PHYS_PAGE='147',
 XY='(4775,1025)',
 ROT='0',
 VER='1',
 PACK_TYPE='0402',
 CDS_LIB='pure_quanta',
 CDS_PART_NAME='Q_CAP_0402-1000PF,50V,5%,EMPTYA',
 TOLERANCE='5%',
 MATERIAL='EMPTY',
 VOLTAGE='50V',
 VALUE='1000PF',
 PRIM_FILE='./archive_libs/logical/q_cap/chips/chips.prt';

PART_NAME
 C1989 'Q_CAP_DIFFBUS_C0201-DIFF BUS_0A':;

SECTION_NUMBER 1
 '@S9S_MB_2U_LIB.S9S_MB_2U(SCH_1):PAGE173_I75@PURE_QUANTA.Q_CAP_DIFFBUS(CHIPS)':
 C_PATH='@s9s_mb_2u_lib.s9s_mb_2u(sch_1):page173_i75@pure_quanta.q_cap_diffbus(c~
hips)',
 P_PATH='@s9s_mb_2u_lib.s9s_mb_2u(sch_1):page181_i75@pure_quanta.q_cap_diffbus(c~
hips)',
 PATH='I75',
 DRAWING='@S9S_MB_2U_LIB.S9S_MB_2U(SCH_1):PAGE173',
 PIN_NAMES_ROTATE='TRUE',
 PHYS_PAGE='181',
 XY='(3025,1675)',
 ROT='0',
 VER='2',
 PACK_TYPE='C0201',
 CDS_LIB='pure_quanta',
 CDS_PART_NAME='Q_CAP_DIFFBUS_C0201-DIFF BUS_0A',
 TOLERANCE='20%',
 MATERIAL='X6S',
 VOLTAGE='6.3V',
 VALUE='DIFF BUS_0.22UF',
 PRIM_FILE='./archive_libs/logical/q_cap_diffbus/chips/chips.prt';

PART_NAME
 C1990 'Q_CAP_DIFFBUS_C0201-DIFF BUS_0A':;

SECTION_NUMBER 1
 '@S9S_MB_2U_LIB.S9S_MB_2U(SCH_1):PAGE173_I74@PURE_QUANTA.Q_CAP_DIFFBUS(CHIPS)':
 C_PATH='@s9s_mb_2u_lib.s9s_mb_2u(sch_1):page173_i74@pure_quanta.q_cap_diffbus(c~
hips)',
 P_PATH='@s9s_mb_2u_lib.s9s_mb_2u(sch_1):page181_i74@pure_quanta.q_cap_diffbus(c~
hips)',
 PATH='I74',
 DRAWING='@S9S_MB_2U_LIB.S9S_MB_2U(SCH_1):PAGE173',
 PIN_NAMES_ROTATE='TRUE',
 PHYS_PAGE='181',
 XY='(3025,1625)',
 ROT='0',
 VER='2',
 PACK_TYPE='C0201',
 CDS_LIB='pure_quanta',
 CDS_PART_NAME='Q_CAP_DIFFBUS_C0201-DIFF BUS_0A',
 TOLERANCE='20%',
 MATERIAL='X6S',
 VOLTAGE='6.3V',
 VALUE='DIFF BUS_0.22UF',
 PRIM_FILE='./archive_libs/logical/q_cap_diffbus/chips/chips.prt';

PART_NAME
 C1991 'Q_CAP_DIFFBUS_C0201-DIFF BUS_0A':;

SECTION_NUMBER 1
 '@S9S_MB_2U_LIB.S9S_MB_2U(SCH_1):PAGE173_I73@PURE_QUANTA.Q_CAP_DIFFBUS(CHIPS)':
 C_PATH='@s9s_mb_2u_lib.s9s_mb_2u(sch_1):page173_i73@pure_quanta.q_cap_diffbus(c~
hips)',
 P_PATH='@s9s_mb_2u_lib.s9s_mb_2u(sch_1):page181_i73@pure_quanta.q_cap_diffbus(c~
hips)',
 PATH='I73',
 DRAWING='@S9S_MB_2U_LIB.S9S_MB_2U(SCH_1):PAGE173',
 PIN_NAMES_ROTATE='TRUE',
 PHYS_PAGE='181',
 XY='(3025,1575)',
 ROT='0',
 VER='2',
 PACK_TYPE='C0201',
 CDS_LIB='pure_quanta',
 CDS_PART_NAME='Q_CAP_DIFFBUS_C0201-DIFF BUS_0A',
 TOLERANCE='20%',
 MATERIAL='X6S',
 VOLTAGE='6.3V',
 VALUE='DIFF BUS_0.22UF',
 PRIM_FILE='./archive_libs/logical/q_cap_diffbus/chips/chips.prt';

PART_NAME
 C1992 'Q_CAP_DIFFBUS_C0201-DIFF BUS_0A':;

SECTION_NUMBER 1
 '@S9S_MB_2U_LIB.S9S_MB_2U(SCH_1):PAGE173_I72@PURE_QUANTA.Q_CAP_DIFFBUS(CHIPS)':
 C_PATH='@s9s_mb_2u_lib.s9s_mb_2u(sch_1):page173_i72@pure_quanta.q_cap_diffbus(c~
hips)',
 P_PATH='@s9s_mb_2u_lib.s9s_mb_2u(sch_1):page181_i72@pure_quanta.q_cap_diffbus(c~
hips)',
 PATH='I72',
 DRAWING='@S9S_MB_2U_LIB.S9S_MB_2U(SCH_1):PAGE173',
 PIN_NAMES_ROTATE='TRUE',
 PHYS_PAGE='181',
 XY='(3025,1525)',
 ROT='0',
 VER='2',
 PACK_TYPE='C0201',
 CDS_LIB='pure_quanta',
 CDS_PART_NAME='Q_CAP_DIFFBUS_C0201-DIFF BUS_0A',
 TOLERANCE='20%',
 MATERIAL='X6S',
 VOLTAGE='6.3V',
 VALUE='DIFF BUS_0.22UF',
 PRIM_FILE='./archive_libs/logical/q_cap_diffbus/chips/chips.prt';

PART_NAME
 C1993 'Q_CAP_DIFFBUS_C0201-DIFF BUS_0A':;

SECTION_NUMBER 1
 '@S9S_MB_2U_LIB.S9S_MB_2U(SCH_1):PAGE173_I71@PURE_QUANTA.Q_CAP_DIFFBUS(CHIPS)':
 C_PATH='@s9s_mb_2u_lib.s9s_mb_2u(sch_1):page173_i71@pure_quanta.q_cap_diffbus(c~
hips)',
 P_PATH='@s9s_mb_2u_lib.s9s_mb_2u(sch_1):page181_i71@pure_quanta.q_cap_diffbus(c~
hips)',
 PATH='I71',
 DRAWING='@S9S_MB_2U_LIB.S9S_MB_2U(SCH_1):PAGE173',
 PIN_NAMES_ROTATE='TRUE',
 PHYS_PAGE='181',
 XY='(3025,1475)',
 ROT='0',
 VER='2',
 PACK_TYPE='C0201',
 CDS_LIB='pure_quanta',
 CDS_PART_NAME='Q_CAP_DIFFBUS_C0201-DIFF BUS_0A',
 TOLERANCE='20%',
 MATERIAL='X6S',
 VOLTAGE='6.3V',
 VALUE='DIFF BUS_0.22UF',
 PRIM_FILE='./archive_libs/logical/q_cap_diffbus/chips/chips.prt';

PART_NAME
 C1994 'Q_CAP_DIFFBUS_C0201-DIFF BUS_0A':;

SECTION_NUMBER 1
 '@S9S_MB_2U_LIB.S9S_MB_2U(SCH_1):PAGE173_I70@PURE_QUANTA.Q_CAP_DIFFBUS(CHIPS)':
 C_PATH='@s9s_mb_2u_lib.s9s_mb_2u(sch_1):page173_i70@pure_quanta.q_cap_diffbus(c~
hips)',
 P_PATH='@s9s_mb_2u_lib.s9s_mb_2u(sch_1):page181_i70@pure_quanta.q_cap_diffbus(c~
hips)',
 PATH='I70',
 DRAWING='@S9S_MB_2U_LIB.S9S_MB_2U(SCH_1):PAGE173',
 PIN_NAMES_ROTATE='TRUE',
 PHYS_PAGE='181',
 XY='(3025,1425)',
 ROT='0',
 VER='2',
 PACK_TYPE='C0201',
 CDS_LIB='pure_quanta',
 CDS_PART_NAME='Q_CAP_DIFFBUS_C0201-DIFF BUS_0A',
 TOLERANCE='20%',
 MATERIAL='X6S',
 VOLTAGE='6.3V',
 VALUE='DIFF BUS_0.22UF',
 PRIM_FILE='./archive_libs/logical/q_cap_diffbus/chips/chips.prt';

PART_NAME
 C1995 'Q_CAP_DIFFBUS_C0201-DIFF BUS_0A':;

SECTION_NUMBER 1
 '@S9S_MB_2U_LIB.S9S_MB_2U(SCH_1):PAGE173_I69@PURE_QUANTA.Q_CAP_DIFFBUS(CHIPS)':
 C_PATH='@s9s_mb_2u_lib.s9s_mb_2u(sch_1):page173_i69@pure_quanta.q_cap_diffbus(c~
hips)',
 P_PATH='@s9s_mb_2u_lib.s9s_mb_2u(sch_1):page181_i69@pure_quanta.q_cap_diffbus(c~
hips)',
 PATH='I69',
 DRAWING='@S9S_MB_2U_LIB.S9S_MB_2U(SCH_1):PAGE173',
 PIN_NAMES_ROTATE='TRUE',
 PHYS_PAGE='181',
 XY='(3025,1375)',
 ROT='0',
 VER='2',
 PACK_TYPE='C0201',
 CDS_LIB='pure_quanta',
 CDS_PART_NAME='Q_CAP_DIFFBUS_C0201-DIFF BUS_0A',
 TOLERANCE='20%',
 MATERIAL='X6S',
 VOLTAGE='6.3V',
 VALUE='DIFF BUS_0.22UF',
 PRIM_FILE='./archive_libs/logical/q_cap_diffbus/chips/chips.prt';

PART_NAME
 C1996 'Q_CAP_DIFFBUS_C0201-DIFF BUS_0A':;

SECTION_NUMBER 1
 '@S9S_MB_2U_LIB.S9S_MB_2U(SCH_1):PAGE173_I68@PURE_QUANTA.Q_CAP_DIFFBUS(CHIPS)':
 C_PATH='@s9s_mb_2u_lib.s9s_mb_2u(sch_1):page173_i68@pure_quanta.q_cap_diffbus(c~
hips)',
 P_PATH='@s9s_mb_2u_lib.s9s_mb_2u(sch_1):page181_i68@pure_quanta.q_cap_diffbus(c~
hips)',
 PATH='I68',
 DRAWING='@S9S_MB_2U_LIB.S9S_MB_2U(SCH_1):PAGE173',
 PIN_NAMES_ROTATE='TRUE',
 PHYS_PAGE='181',
 XY='(3025,1325)',
 ROT='0',
 VER='2',
 PACK_TYPE='C0201',
 CDS_LIB='pure_quanta',
 CDS_PART_NAME='Q_CAP_DIFFBUS_C0201-DIFF BUS_0A',
 TOLERANCE='20%',
 MATERIAL='X6S',
 VOLTAGE='6.3V',
 VALUE='DIFF BUS_0.22UF',
 PRIM_FILE='./archive_libs/logical/q_cap_diffbus/chips/chips.prt';

PART_NAME
 C1997 'Q_CAP_0402-0.1UF,25V,10%,X7R,CA':;

SECTION_NUMBER 1
 '@S9S_MB_2U_LIB.S9S_MB_2U(SCH_1):PAGE183_I89@PURE_QUANTA.Q_CAP(CHIPS)':
 C_PATH='@s9s_mb_2u_lib.s9s_mb_2u(sch_1):page183_i89@pure_quanta.q_cap(chips)',
 P_PATH='@s9s_mb_2u_lib.s9s_mb_2u(sch_1):page194_i89@pure_quanta.q_cap(chips)',
 PATH='I89',
 DRAWING='@S9S_MB_2U_LIB.S9S_MB_2U(SCH_1):PAGE183',
 PHYS_PAGE='194',
 XY='(-350,1625)',
 ROT='2',
 VER='1',
 PACK_TYPE='0402',
 CDS_LIB='pure_quanta',
 CDS_PART_NAME='Q_CAP_0402-0.1UF,25V,10%,X7R,CA',
 TOLERANCE='10%',
 MATERIAL='X7R',
 VOLTAGE='25V',
 VALUE='0.1UF',
 PRIM_FILE='./archive_libs/logical/q_cap/chips/chips.prt';

PART_NAME
 C1998 'Q_CAP_0402-0.1UF,25V,10%,X7R,CA':;

SECTION_NUMBER 1
 '@S9S_MB_2U_LIB.S9S_MB_2U(SCH_1):PAGE183_I82@PURE_QUANTA.Q_CAP(CHIPS)':
 C_PATH='@s9s_mb_2u_lib.s9s_mb_2u(sch_1):page183_i82@pure_quanta.q_cap(chips)',
 P_PATH='@s9s_mb_2u_lib.s9s_mb_2u(sch_1):page194_i82@pure_quanta.q_cap(chips)',
 PATH='I82',
 DRAWING='@S9S_MB_2U_LIB.S9S_MB_2U(SCH_1):PAGE183',
 PHYS_PAGE='194',
 XY='(1600,1650)',
 ROT='0',
 VER='1',
 PACK_TYPE='0402',
 CDS_LIB='pure_quanta',
 CDS_PART_NAME='Q_CAP_0402-0.1UF,25V,10%,X7R,CA',
 TOLERANCE='10%',
 MATERIAL='X7R',
 VOLTAGE='25V',
 VALUE='0.1UF',
 PRIM_FILE='./archive_libs/logical/q_cap/chips/chips.prt';

PART_NAME
 C2007 'Q_CAP_C0402-1UF,25V,10%,X6S,CHA':;

SECTION_NUMBER 1
 '@S9S_MB_2U_LIB.S9S_MB_2U(SCH_1):PAGE182_I326@PURE_QUANTA.Q_CAP(CHIPS)':
 C_PATH='@s9s_mb_2u_lib.s9s_mb_2u(sch_1):page182_i326@pure_quanta.q_cap(chips)',
 P_PATH='@s9s_mb_2u_lib.s9s_mb_2u(sch_1):page190_i326@pure_quanta.q_cap(chips)',
 PATH='I326',
 DRAWING='@S9S_MB_2U_LIB.S9S_MB_2U(SCH_1):PAGE182',
 BOM_COST='VR_SYSTEM ',
 PHYS_PAGE='190',
 XY='(8050,-750)',
 ROT='0',
 VER='1',
 PACK_TYPE='C0402',
 CDS_LIB='pure_quanta',
 CDS_PART_NAME='Q_CAP_C0402-1UF,25V,10%,X6S,CHA',
 TOLERANCE='10%',
 MATERIAL='X6S',
 VOLTAGE='25V',
 VALUE='1UF',
 PRIM_FILE='./archive_libs/logical/q_cap/chips/chips.prt';

PART_NAME
 C2010 'Q_CAP_0402-0.1UF,25V,10%,X7R,CA':;

SECTION_NUMBER 1
 '@S9S_MB_2U_LIB.S9S_MB_2U(SCH_1):PAGE161_I16@PURE_QUANTA.Q_CAP(CHIPS)':
 C_PATH='@s9s_mb_2u_lib.s9s_mb_2u(sch_1):page161_i16@pure_quanta.q_cap(chips)',
 P_PATH='@s9s_mb_2u_lib.s9s_mb_2u(sch_1):page170_i16@pure_quanta.q_cap(chips)',
 PATH='I16',
 DRAWING='@S9S_MB_2U_LIB.S9S_MB_2U(SCH_1):PAGE161',
 PHYS_PAGE='170',
 XY='(2600,1950)',
 ROT='2',
 VER='1',
 PACK_TYPE='0402',
 CDS_LIB='pure_quanta',
 CDS_PART_NAME='Q_CAP_0402-0.1UF,25V,10%,X7R,CA',
 TOLERANCE='10%',
 MATERIAL='X7R',
 VOLTAGE='25V',
 VALUE='0.1UF',
 PRIM_FILE='./archive_libs/logical/q_cap/chips/chips.prt';

PART_NAME
 C2012 'Q_CAP_0402-0.1UF,25V,10%,X7R,CA':;

SECTION_NUMBER 1
 '@S9S_MB_2U_LIB.S9S_MB_2U(SCH_1):PAGE163_I98@PURE_QUANTA.Q_CAP(CHIPS)':
 C_PATH='@s9s_mb_2u_lib.s9s_mb_2u(sch_1):page163_i98@pure_quanta.q_cap(chips)',
 P_PATH='@s9s_mb_2u_lib.s9s_mb_2u(sch_1):page172_i98@pure_quanta.q_cap(chips)',
 PATH='I98',
 DRAWING='@S9S_MB_2U_LIB.S9S_MB_2U(SCH_1):PAGE163',
 PHYS_PAGE='172',
 XY='(1025,725)',
 ROT='0',
 VER='1',
 PACK_TYPE='0402',
 CDS_LIB='pure_quanta',
 CDS_PART_NAME='Q_CAP_0402-0.1UF,25V,10%,X7R,CA',
 TOLERANCE='10%',
 MATERIAL='X7R',
 VOLTAGE='25V',
 VALUE='0.1UF',
 PRIM_FILE='./archive_libs/logical/q_cap/chips/chips.prt';

PART_NAME
 C2013 'Q_CAP_0402-0.1UF,25V,10%,X7R,CA':;

SECTION_NUMBER 1
 '@S9S_MB_2U_LIB.S9S_MB_2U(SCH_1):PAGE163_I42@PURE_QUANTA.Q_CAP(CHIPS)':
 C_PATH='@s9s_mb_2u_lib.s9s_mb_2u(sch_1):page163_i42@pure_quanta.q_cap(chips)',
 P_PATH='@s9s_mb_2u_lib.s9s_mb_2u(sch_1):page172_i42@pure_quanta.q_cap(chips)',
 PATH='I42',
 DRAWING='@S9S_MB_2U_LIB.S9S_MB_2U(SCH_1):PAGE163',
 PHYS_PAGE='172',
 XY='(600,-1375)',
 ROT='0',
 VER='1',
 PACK_TYPE='0402',
 CDS_LIB='pure_quanta',
 CDS_PART_NAME='Q_CAP_0402-0.1UF,25V,10%,X7R,CA',
 TOLERANCE='10%',
 MATERIAL='X7R',
 VOLTAGE='25V',
 VALUE='0.1UF',
 PRIM_FILE='./archive_libs/logical/q_cap/chips/chips.prt';

PART_NAME
 C2014 'Q_CAP_0402-0.1UF,25V,10%,X7R,CA':;

SECTION_NUMBER 1
 '@S9S_MB_2U_LIB.S9S_MB_2U(SCH_1):PAGE163_I65@PURE_QUANTA.Q_CAP(CHIPS)':
 C_PATH='@s9s_mb_2u_lib.s9s_mb_2u(sch_1):page163_i65@pure_quanta.q_cap(chips)',
 P_PATH='@s9s_mb_2u_lib.s9s_mb_2u(sch_1):page172_i65@pure_quanta.q_cap(chips)',
 PATH='I65',
 DRAWING='@S9S_MB_2U_LIB.S9S_MB_2U(SCH_1):PAGE163',
 PHYS_PAGE='172',
 XY='(725,-3525)',
 ROT='0',
 VER='1',
 PACK_TYPE='0402',
 CDS_LIB='pure_quanta',
 CDS_PART_NAME='Q_CAP_0402-0.1UF,25V,10%,X7R,CA',
 TOLERANCE='10%',
 MATERIAL='X7R',
 VOLTAGE='25V',
 VALUE='0.1UF',
 PRIM_FILE='./archive_libs/logical/q_cap/chips/chips.prt';

PART_NAME
 C2015 'Q_CAP_0402-0.1UF,25V,10%,X7R,CA':;

SECTION_NUMBER 1
 '@S9S_MB_2U_LIB.S9S_MB_2U(SCH_1):PAGE295_I34@PURE_QUANTA.Q_CAP(CHIPS)':
 C_PATH='@s9s_mb_2u_lib.s9s_mb_2u(sch_1):page295_i34@pure_quanta.q_cap(chips)',
 P_PATH='@s9s_mb_2u_lib.s9s_mb_2u(sch_1):page171_i34@pure_quanta.q_cap(chips)',
 PATH='I34',
 DRAWING='@S9S_MB_2U_LIB.S9S_MB_2U(SCH_1):PAGE295',
 PHYS_PAGE='171',
 XY='(2175,3675)',
 ROT='0',
 VER='1',
 PACK_TYPE='0402',
 CDS_LIB='pure_quanta',
 CDS_PART_NAME='Q_CAP_0402-0.1UF,25V,10%,X7R,CA',
 TOLERANCE='10%',
 MATERIAL='X7R',
 VOLTAGE='25V',
 VALUE='0.1UF',
 PRIM_FILE='./archive_libs/logical/q_cap/chips/chips.prt';

PART_NAME
 C2017 'Q_CAP_0402-0.1UF,25V,10%,X7R,CA':;

SECTION_NUMBER 1
 '@S9S_MB_2U_LIB.S9S_MB_2U(SCH_1):PAGE163_I114@PURE_QUANTA.Q_CAP(CHIPS)':
 C_PATH='@s9s_mb_2u_lib.s9s_mb_2u(sch_1):page163_i114@pure_quanta.q_cap(chips)',
 P_PATH='@s9s_mb_2u_lib.s9s_mb_2u(sch_1):page172_i114@pure_quanta.q_cap(chips)',
 PATH='I114',
 DRAWING='@S9S_MB_2U_LIB.S9S_MB_2U(SCH_1):PAGE163',
 PHYS_PAGE='172',
 XY='(-1650,300)',
 ROT='0',
 VER='1',
 PACK_TYPE='0402',
 CDS_LIB='pure_quanta',
 CDS_PART_NAME='Q_CAP_0402-0.1UF,25V,10%,X7R,CA',
 TOLERANCE='10%',
 MATERIAL='X7R',
 VOLTAGE='25V',
 VALUE='0.1UF',
 PRIM_FILE='./archive_libs/logical/q_cap/chips/chips.prt';

PART_NAME
 C2018 'Q_CAP_0402-0.1UF,25V,10%,X7R,CA':;

SECTION_NUMBER 1
 '@S9S_MB_2U_LIB.S9S_MB_2U(SCH_1):PAGE163_I26@PURE_QUANTA.Q_CAP(CHIPS)':
 C_PATH='@s9s_mb_2u_lib.s9s_mb_2u(sch_1):page163_i26@pure_quanta.q_cap(chips)',
 P_PATH='@s9s_mb_2u_lib.s9s_mb_2u(sch_1):page172_i26@pure_quanta.q_cap(chips)',
 PATH='I26',
 DRAWING='@S9S_MB_2U_LIB.S9S_MB_2U(SCH_1):PAGE163',
 PHYS_PAGE='172',
 XY='(-2075,-1800)',
 ROT='0',
 VER='1',
 PACK_TYPE='0402',
 CDS_LIB='pure_quanta',
 CDS_PART_NAME='Q_CAP_0402-0.1UF,25V,10%,X7R,CA',
 TOLERANCE='10%',
 MATERIAL='X7R',
 VOLTAGE='25V',
 VALUE='0.1UF',
 PRIM_FILE='./archive_libs/logical/q_cap/chips/chips.prt';

PART_NAME
 C2019 'Q_CAP_0402-0.1UF,25V,10%,X7R,CA':;

SECTION_NUMBER 1
 '@S9S_MB_2U_LIB.S9S_MB_2U(SCH_1):PAGE163_I49@PURE_QUANTA.Q_CAP(CHIPS)':
 C_PATH='@s9s_mb_2u_lib.s9s_mb_2u(sch_1):page163_i49@pure_quanta.q_cap(chips)',
 P_PATH='@s9s_mb_2u_lib.s9s_mb_2u(sch_1):page172_i49@pure_quanta.q_cap(chips)',
 PATH='I49',
 DRAWING='@S9S_MB_2U_LIB.S9S_MB_2U(SCH_1):PAGE163',
 PHYS_PAGE='172',
 XY='(-1950,-3950)',
 ROT='0',
 VER='1',
 PACK_TYPE='0402',
 CDS_LIB='pure_quanta',
 CDS_PART_NAME='Q_CAP_0402-0.1UF,25V,10%,X7R,CA',
 TOLERANCE='10%',
 MATERIAL='X7R',
 VOLTAGE='25V',
 VALUE='0.1UF',
 PRIM_FILE='./archive_libs/logical/q_cap/chips/chips.prt';

PART_NAME
 C2020 'Q_CAP_0402-0.1UF,25V,10%,X7R,CA':;

SECTION_NUMBER 1
 '@S9S_MB_2U_LIB.S9S_MB_2U(SCH_1):PAGE163_I108@PURE_QUANTA.Q_CAP(CHIPS)':
 C_PATH='@s9s_mb_2u_lib.s9s_mb_2u(sch_1):page163_i108@pure_quanta.q_cap(chips)',
 P_PATH='@s9s_mb_2u_lib.s9s_mb_2u(sch_1):page172_i108@pure_quanta.q_cap(chips)',
 PATH='I108',
 DRAWING='@S9S_MB_2U_LIB.S9S_MB_2U(SCH_1):PAGE163',
 PHYS_PAGE='172',
 XY='(500,-625)',
 ROT='0',
 VER='1',
 PACK_TYPE='0402',
 CDS_LIB='pure_quanta',
 CDS_PART_NAME='Q_CAP_0402-0.1UF,25V,10%,X7R,CA',
 TOLERANCE='10%',
 MATERIAL='X7R',
 VOLTAGE='25V',
 VALUE='0.1UF',
 PRIM_FILE='./archive_libs/logical/q_cap/chips/chips.prt';

PART_NAME
 C2021 'Q_CAP_0402-0.1UF,25V,10%,X7R,CA':;

SECTION_NUMBER 1
 '@S9S_MB_2U_LIB.S9S_MB_2U(SCH_1):PAGE163_I71@PURE_QUANTA.Q_CAP(CHIPS)':
 C_PATH='@s9s_mb_2u_lib.s9s_mb_2u(sch_1):page163_i71@pure_quanta.q_cap(chips)',
 P_PATH='@s9s_mb_2u_lib.s9s_mb_2u(sch_1):page172_i71@pure_quanta.q_cap(chips)',
 PATH='I71',
 DRAWING='@S9S_MB_2U_LIB.S9S_MB_2U(SCH_1):PAGE163',
 PHYS_PAGE='172',
 XY='(75,-2725)',
 ROT='0',
 VER='1',
 PACK_TYPE='0402',
 CDS_LIB='pure_quanta',
 CDS_PART_NAME='Q_CAP_0402-0.1UF,25V,10%,X7R,CA',
 TOLERANCE='10%',
 MATERIAL='X7R',
 VOLTAGE='25V',
 VALUE='0.1UF',
 PRIM_FILE='./archive_libs/logical/q_cap/chips/chips.prt';

PART_NAME
 C2022 'Q_CAP_0402-0.1UF,25V,10%,X7R,CA':;

SECTION_NUMBER 1
 '@S9S_MB_2U_LIB.S9S_MB_2U(SCH_1):PAGE163_I72@PURE_QUANTA.Q_CAP(CHIPS)':
 C_PATH='@s9s_mb_2u_lib.s9s_mb_2u(sch_1):page163_i72@pure_quanta.q_cap(chips)',
 P_PATH='@s9s_mb_2u_lib.s9s_mb_2u(sch_1):page172_i72@pure_quanta.q_cap(chips)',
 PATH='I72',
 DRAWING='@S9S_MB_2U_LIB.S9S_MB_2U(SCH_1):PAGE163',
 PHYS_PAGE='172',
 XY='(200,-4875)',
 ROT='0',
 VER='1',
 PACK_TYPE='0402',
 CDS_LIB='pure_quanta',
 CDS_PART_NAME='Q_CAP_0402-0.1UF,25V,10%,X7R,CA',
 TOLERANCE='10%',
 MATERIAL='X7R',
 VOLTAGE='25V',
 VALUE='0.1UF',
 PRIM_FILE='./archive_libs/logical/q_cap/chips/chips.prt';

PART_NAME
 C2024 'Q_CAP_0402-0.1UF,25V,10%,X7R,CA':;

SECTION_NUMBER 1
 '@S9S_MB_2U_LIB.S9S_MB_2U(SCH_1):PAGE295_I50@PURE_QUANTA.Q_CAP(CHIPS)':
 C_PATH='@s9s_mb_2u_lib.s9s_mb_2u(sch_1):page295_i50@pure_quanta.q_cap(chips)',
 P_PATH='@s9s_mb_2u_lib.s9s_mb_2u(sch_1):page171_i50@pure_quanta.q_cap(chips)',
 PATH='I50',
 DRAWING='@S9S_MB_2U_LIB.S9S_MB_2U(SCH_1):PAGE295',
 PHYS_PAGE='171',
 XY='(-500,3250)',
 ROT='0',
 VER='1',
 PACK_TYPE='0402',
 CDS_LIB='pure_quanta',
 CDS_PART_NAME='Q_CAP_0402-0.1UF,25V,10%,X7R,CA',
 TOLERANCE='10%',
 MATERIAL='X7R',
 VOLTAGE='25V',
 VALUE='0.1UF',
 PRIM_FILE='./archive_libs/logical/q_cap/chips/chips.prt';

PART_NAME
 C2027 'Q_CAP_0402-0.1UF,25V,10%,X7R,CA':;

SECTION_NUMBER 1
 '@S9S_MB_2U_LIB.S9S_MB_2U(SCH_1):PAGE295_I77@PURE_QUANTA.Q_CAP(CHIPS)':
 C_PATH='@s9s_mb_2u_lib.s9s_mb_2u(sch_1):page295_i77@pure_quanta.q_cap(chips)',
 P_PATH='@s9s_mb_2u_lib.s9s_mb_2u(sch_1):page171_i77@pure_quanta.q_cap(chips)',
 PATH='I77',
 DRAWING='@S9S_MB_2U_LIB.S9S_MB_2U(SCH_1):PAGE295',
 PHYS_PAGE='171',
 XY='(1650,2325)',
 ROT='0',
 VER='1',
 PACK_TYPE='0402',
 CDS_LIB='pure_quanta',
 CDS_PART_NAME='Q_CAP_0402-0.1UF,25V,10%,X7R,CA',
 TOLERANCE='10%',
 MATERIAL='X7R',
 VOLTAGE='25V',
 VALUE='0.1UF',
 PRIM_FILE='./archive_libs/logical/q_cap/chips/chips.prt';

PART_NAME
 C2029 'Q_CAP_0402-18PF,50V,5%,C0G,CH0A':
 ROOM='USB1_BOM1';

SECTION_NUMBER 1
 '@S9S_MB_2U_LIB.S9S_MB_2U(SCH_1):PAGE155_I210@PURE_QUANTA.Q_CAP(CHIPS)':
 C_PATH='@s9s_mb_2u_lib.s9s_mb_2u(sch_1):page155_i210@pure_quanta.q_cap(chips)',
 P_PATH='@s9s_mb_2u_lib.s9s_mb_2u(sch_1):page152_i210@pure_quanta.q_cap(chips)',
 PATH='I210',
 DRAWING='@S9S_MB_2U_LIB.S9S_MB_2U(SCH_1):PAGE155',
 PHYS_PAGE='152',
 XY='(3475,4375)',
 ROT='0',
 VER='1',
 PACK_TYPE='0402',
 LOCATION='C2029',
 CDS_LIB='pure_quanta',
 CDS_PART_NAME='Q_CAP_0402-18PF,50V,5%,C0G,CH0A',
 TOLERANCE='5%',
 MATERIAL='C0G',
 VOLTAGE='50V',
 ROOM='USB1_BOM1',
 VALUE='18PF',
 PRIM_FILE='./archive_libs/logical/q_cap/chips/chips.prt';

PART_NAME
 C2030 'Q_CAP_0402-18PF,50V,5%,C0G,CH0A':
 ROOM='USB1_BOM1';

SECTION_NUMBER 1
 '@S9S_MB_2U_LIB.S9S_MB_2U(SCH_1):PAGE155_I211@PURE_QUANTA.Q_CAP(CHIPS)':
 C_PATH='@s9s_mb_2u_lib.s9s_mb_2u(sch_1):page155_i211@pure_quanta.q_cap(chips)',
 P_PATH='@s9s_mb_2u_lib.s9s_mb_2u(sch_1):page152_i211@pure_quanta.q_cap(chips)',
 PATH='I211',
 DRAWING='@S9S_MB_2U_LIB.S9S_MB_2U(SCH_1):PAGE155',
 PHYS_PAGE='152',
 XY='(4475,4375)',
 ROT='0',
 VER='1',
 PACK_TYPE='0402',
 LOCATION='C2030',
 CDS_LIB='pure_quanta',
 CDS_PART_NAME='Q_CAP_0402-18PF,50V,5%,C0G,CH0A',
 TOLERANCE='5%',
 MATERIAL='C0G',
 VOLTAGE='50V',
 ROOM='USB1_BOM1',
 VALUE='18PF',
 PRIM_FILE='./archive_libs/logical/q_cap/chips/chips.prt';

PART_NAME
 C2031 'Q_CAP_C0402-1UF,25V,10%,X6S,CHA':
 ROOM='USB1_BOM1';

SECTION_NUMBER 1
 '@S9S_MB_2U_LIB.S9S_MB_2U(SCH_1):PAGE155_I148@PURE_QUANTA.Q_CAP(CHIPS)':
 C_PATH='@s9s_mb_2u_lib.s9s_mb_2u(sch_1):page155_i148@pure_quanta.q_cap(chips)',
 P_PATH='@s9s_mb_2u_lib.s9s_mb_2u(sch_1):page152_i148@pure_quanta.q_cap(chips)',
 PATH='I148',
 DRAWING='@S9S_MB_2U_LIB.S9S_MB_2U(SCH_1):PAGE155',
 PHYS_PAGE='152',
 XY='(-2300,4500)',
 ROT='0',
 VER='1',
 PACK_TYPE='C0402',
 CDS_LIB='pure_quanta',
 CDS_PART_NAME='Q_CAP_C0402-1UF,25V,10%,X6S,CHA',
 TOLERANCE='10%',
 MATERIAL='X6S',
 VOLTAGE='25V',
 ROOM='USB1_BOM1',
 VALUE='1UF',
 PRIM_FILE='./archive_libs/logical/q_cap/chips/chips.prt';

PART_NAME
 C2032 'Q_CAP_0402-0.1UF,25V,10%,X7R,CA':
 ROOM='USB1_BOM1';

SECTION_NUMBER 1
 '@S9S_MB_2U_LIB.S9S_MB_2U(SCH_1):PAGE155_I145@PURE_QUANTA.Q_CAP(CHIPS)':
 C_PATH='@s9s_mb_2u_lib.s9s_mb_2u(sch_1):page155_i145@pure_quanta.q_cap(chips)',
 P_PATH='@s9s_mb_2u_lib.s9s_mb_2u(sch_1):page152_i145@pure_quanta.q_cap(chips)',
 PATH='I145',
 DRAWING='@S9S_MB_2U_LIB.S9S_MB_2U(SCH_1):PAGE155',
 PHYS_PAGE='152',
 XY='(-1925,4500)',
 ROT='2',
 VER='1',
 PACK_TYPE='0402',
 CDS_LIB='pure_quanta',
 CDS_PART_NAME='Q_CAP_0402-0.1UF,25V,10%,X7R,CA',
 TOLERANCE='10%',
 MATERIAL='X7R',
 VOLTAGE='25V',
 ROOM='USB1_BOM1',
 VALUE='0.1UF',
 PRIM_FILE='./archive_libs/logical/q_cap/chips/chips.prt';

PART_NAME
 C2033 'Q_CAP_0402-0.1UF,25V,10%,X7R,CA':
 ROOM='USB1_BOM1';

SECTION_NUMBER 1
 '@S9S_MB_2U_LIB.S9S_MB_2U(SCH_1):PAGE155_I143@PURE_QUANTA.Q_CAP(CHIPS)':
 C_PATH='@s9s_mb_2u_lib.s9s_mb_2u(sch_1):page155_i143@pure_quanta.q_cap(chips)',
 P_PATH='@s9s_mb_2u_lib.s9s_mb_2u(sch_1):page152_i143@pure_quanta.q_cap(chips)',
 PATH='I143',
 DRAWING='@S9S_MB_2U_LIB.S9S_MB_2U(SCH_1):PAGE155',
 PHYS_PAGE='152',
 XY='(-1550,4500)',
 ROT='2',
 VER='1',
 PACK_TYPE='0402',
 CDS_LIB='pure_quanta',
 CDS_PART_NAME='Q_CAP_0402-0.1UF,25V,10%,X7R,CA',
 TOLERANCE='10%',
 MATERIAL='X7R',
 VOLTAGE='25V',
 ROOM='USB1_BOM1',
 VALUE='0.1UF',
 PRIM_FILE='./archive_libs/logical/q_cap/chips/chips.prt';

PART_NAME
 C2034 'Q_CAP_0402-0.1UF,25V,10%,X7R,CA':
 ROOM='USB1_BOM1';

SECTION_NUMBER 1
 '@S9S_MB_2U_LIB.S9S_MB_2U(SCH_1):PAGE155_I142@PURE_QUANTA.Q_CAP(CHIPS)':
 C_PATH='@s9s_mb_2u_lib.s9s_mb_2u(sch_1):page155_i142@pure_quanta.q_cap(chips)',
 P_PATH='@s9s_mb_2u_lib.s9s_mb_2u(sch_1):page152_i142@pure_quanta.q_cap(chips)',
 PATH='I142',
 DRAWING='@S9S_MB_2U_LIB.S9S_MB_2U(SCH_1):PAGE155',
 PHYS_PAGE='152',
 XY='(-1175,4500)',
 ROT='2',
 VER='1',
 PACK_TYPE='0402',
 CDS_LIB='pure_quanta',
 CDS_PART_NAME='Q_CAP_0402-0.1UF,25V,10%,X7R,CA',
 TOLERANCE='10%',
 MATERIAL='X7R',
 VOLTAGE='25V',
 ROOM='USB1_BOM1',
 VALUE='0.1UF',
 PRIM_FILE='./archive_libs/logical/q_cap/chips/chips.prt';

PART_NAME
 C2035 'Q_CAP_C0402-1UF,25V,10%,X6S,CHA':
 ROOM='USB1_BOM1';

SECTION_NUMBER 1
 '@S9S_MB_2U_LIB.S9S_MB_2U(SCH_1):PAGE155_I147@PURE_QUANTA.Q_CAP(CHIPS)':
 C_PATH='@s9s_mb_2u_lib.s9s_mb_2u(sch_1):page155_i147@pure_quanta.q_cap(chips)',
 P_PATH='@s9s_mb_2u_lib.s9s_mb_2u(sch_1):page152_i147@pure_quanta.q_cap(chips)',
 PATH='I147',
 DRAWING='@S9S_MB_2U_LIB.S9S_MB_2U(SCH_1):PAGE155',
 PHYS_PAGE='152',
 XY='(-825,4500)',
 ROT='0',
 VER='1',
 PACK_TYPE='C0402',
 CDS_LIB='pure_quanta',
 CDS_PART_NAME='Q_CAP_C0402-1UF,25V,10%,X6S,CHA',
 TOLERANCE='10%',
 MATERIAL='X6S',
 VOLTAGE='25V',
 ROOM='USB1_BOM1',
 VALUE='1UF',
 PRIM_FILE='./archive_libs/logical/q_cap/chips/chips.prt';

PART_NAME
 C2036 'Q_CAP_C0402-8.2PF,50V,0.1P,NP0A':;

SECTION_NUMBER 1
 '@S9S_MB_2U_LIB.S9S_MB_2U(SCH_1):PAGE197_I393@PURE_QUANTA.Q_CAP(CHIPS)':
 C_PATH='@s9s_mb_2u_lib.s9s_mb_2u(sch_1):page197_i393@pure_quanta.q_cap(chips)',
 P_PATH='@s9s_mb_2u_lib.s9s_mb_2u(sch_1):page208_i393@pure_quanta.q_cap(chips)',
 PATH='I393',
 DRAWING='@S9S_MB_2U_LIB.S9S_MB_2U(SCH_1):PAGE197',
 PHYS_PAGE='208',
 XY='(-5175,5475)',
 ROT='0',
 VER='1',
 PACK_TYPE='C0402',
 LOCATION='C2036',
 CDS_LIB='pure_quanta',
 CDS_PART_NAME='Q_CAP_C0402-8.2PF,50V,0.1P,NP0A',
 TOLERANCE='0.1P',
 MATERIAL='NP0',
 VOLTAGE='50V',
 VALUE='8.2PF',
 PRIM_FILE='./archive_libs/logical/q_cap/chips/chips.prt';

PART_NAME
 C2037 'Q_CAP_C0402-8.2PF,50V,0.1P,NP0A':;

SECTION_NUMBER 1
 '@S9S_MB_2U_LIB.S9S_MB_2U(SCH_1):PAGE197_I394@PURE_QUANTA.Q_CAP(CHIPS)':
 C_PATH='@s9s_mb_2u_lib.s9s_mb_2u(sch_1):page197_i394@pure_quanta.q_cap(chips)',
 P_PATH='@s9s_mb_2u_lib.s9s_mb_2u(sch_1):page208_i394@pure_quanta.q_cap(chips)',
 PATH='I394',
 DRAWING='@S9S_MB_2U_LIB.S9S_MB_2U(SCH_1):PAGE197',
 PHYS_PAGE='208',
 XY='(-4275,5475)',
 ROT='0',
 VER='1',
 PACK_TYPE='C0402',
 LOCATION='C2037',
 CDS_LIB='pure_quanta',
 CDS_PART_NAME='Q_CAP_C0402-8.2PF,50V,0.1P,NP0A',
 TOLERANCE='0.1P',
 MATERIAL='NP0',
 VOLTAGE='50V',
 VALUE='8.2PF',
 PRIM_FILE='./archive_libs/logical/q_cap/chips/chips.prt';

PART_NAME
 C2038 'Q_CAP_C0402-10UF,6.3V,20%,X6S,A':
 ROOM='USB1_BOM1';

SECTION_NUMBER 1
 '@S9S_MB_2U_LIB.S9S_MB_2U(SCH_1):PAGE155_I164@PURE_QUANTA.Q_CAP(CHIPS)':
 C_PATH='@s9s_mb_2u_lib.s9s_mb_2u(sch_1):page155_i164@pure_quanta.q_cap(chips)',
 P_PATH='@s9s_mb_2u_lib.s9s_mb_2u(sch_1):page152_i164@pure_quanta.q_cap(chips)',
 PATH='I164',
 DRAWING='@S9S_MB_2U_LIB.S9S_MB_2U(SCH_1):PAGE155',
 PHYS_PAGE='152',
 XY='(-3450,4500)',
 ROT='0',
 VER='1',
 PACK_TYPE='C0402',
 CDS_LIB='pure_quanta',
 CDS_PART_NAME='Q_CAP_C0402-10UF,6.3V,20%,X6S,A',
 TOLERANCE='20%',
 MATERIAL='X6S',
 VOLTAGE='6.3V',
 ROOM='USB1_BOM1',
 VALUE='10UF',
 PRIM_FILE='./archive_libs/logical/q_cap/chips/chips.prt';

PART_NAME
 C2039 'Q_CAP_0402-0.1UF,25V,10%,X7R,CA':
 ROOM='USB1_BOM1';

SECTION_NUMBER 1
 '@S9S_MB_2U_LIB.S9S_MB_2U(SCH_1):PAGE155_I163@PURE_QUANTA.Q_CAP(CHIPS)':
 C_PATH='@s9s_mb_2u_lib.s9s_mb_2u(sch_1):page155_i163@pure_quanta.q_cap(chips)',
 P_PATH='@s9s_mb_2u_lib.s9s_mb_2u(sch_1):page152_i163@pure_quanta.q_cap(chips)',
 PATH='I163',
 DRAWING='@S9S_MB_2U_LIB.S9S_MB_2U(SCH_1):PAGE155',
 PHYS_PAGE='152',
 XY='(-3075,4500)',
 ROT='2',
 VER='1',
 PACK_TYPE='0402',
 CDS_LIB='pure_quanta',
 CDS_PART_NAME='Q_CAP_0402-0.1UF,25V,10%,X7R,CA',
 TOLERANCE='10%',
 MATERIAL='X7R',
 VOLTAGE='25V',
 ROOM='USB1_BOM1',
 VALUE='0.1UF',
 PRIM_FILE='./archive_libs/logical/q_cap/chips/chips.prt';

PART_NAME
 C2040 'Q_CAP_0402-0.1UF,25V,10%,X7R,CA':
 ROOM='USB1_BOM1';

SECTION_NUMBER 1
 '@S9S_MB_2U_LIB.S9S_MB_2U(SCH_1):PAGE155_I162@PURE_QUANTA.Q_CAP(CHIPS)':
 C_PATH='@s9s_mb_2u_lib.s9s_mb_2u(sch_1):page155_i162@pure_quanta.q_cap(chips)',
 P_PATH='@s9s_mb_2u_lib.s9s_mb_2u(sch_1):page152_i162@pure_quanta.q_cap(chips)',
 PATH='I162',
 DRAWING='@S9S_MB_2U_LIB.S9S_MB_2U(SCH_1):PAGE155',
 PHYS_PAGE='152',
 XY='(-2675,4500)',
 ROT='2',
 VER='1',
 PACK_TYPE='0402',
 CDS_LIB='pure_quanta',
 CDS_PART_NAME='Q_CAP_0402-0.1UF,25V,10%,X7R,CA',
 TOLERANCE='10%',
 MATERIAL='X7R',
 VOLTAGE='25V',
 ROOM='USB1_BOM1',
 VALUE='0.1UF',
 PRIM_FILE='./archive_libs/logical/q_cap/chips/chips.prt';

PART_NAME
 C2041 'Q_CAP_C0402-1UF,25V,10%,X6S,CHA':
 ROOM='USB1_BOM1';

SECTION_NUMBER 1
 '@S9S_MB_2U_LIB.S9S_MB_2U(SCH_1):PAGE155_I158@PURE_QUANTA.Q_CAP(CHIPS)':
 C_PATH='@s9s_mb_2u_lib.s9s_mb_2u(sch_1):page155_i158@pure_quanta.q_cap(chips)',
 P_PATH='@s9s_mb_2u_lib.s9s_mb_2u(sch_1):page152_i158@pure_quanta.q_cap(chips)',
 PATH='I158',
 DRAWING='@S9S_MB_2U_LIB.S9S_MB_2U(SCH_1):PAGE155',
 PHYS_PAGE='152',
 XY='(-2275,3150)',
 ROT='0',
 VER='1',
 PACK_TYPE='C0402',
 CDS_LIB='pure_quanta',
 CDS_PART_NAME='Q_CAP_C0402-1UF,25V,10%,X6S,CHA',
 TOLERANCE='10%',
 MATERIAL='X6S',
 VOLTAGE='25V',
 ROOM='USB1_BOM1',
 VALUE='1UF',
 PRIM_FILE='./archive_libs/logical/q_cap/chips/chips.prt';

PART_NAME
 C2042 'Q_CAP_0402-100PF,50V,5%,EMPTY,A':
 ROOM='ADC1_BOM1';

SECTION_NUMBER 1
 '@S9S_MB_2U_LIB.S9S_MB_2U(SCH_1):PAGE239_I180@PURE_QUANTA.Q_CAP(CHIPS)':
 C_PATH='@s9s_mb_2u_lib.s9s_mb_2u(sch_1):page239_i180@pure_quanta.q_cap(chips)',
 P_PATH='@s9s_mb_2u_lib.s9s_mb_2u(sch_1):page250_i180@pure_quanta.q_cap(chips)',
 PATH='I180',
 DRAWING='@S9S_MB_2U_LIB.S9S_MB_2U(SCH_1):PAGE239',
 PHYS_PAGE='250',
 XY='(425,4775)',
 ROT='0',
 VER='1',
 PACK_TYPE='0402',
 CDS_LIB='pure_quanta',
 CDS_PART_NAME='Q_CAP_0402-100PF,50V,5%,EMPTY,A',
 TOLERANCE='5%',
 MATERIAL='EMPTY',
 VOLTAGE='50V',
 ROOM='ADC1_BOM1',
 VALUE='100PF',
 PRIM_FILE='./archive_libs/logical/q_cap/chips/chips.prt';

PART_NAME
 C2043 'Q_CAP_0402-100PF,50V,5%,EMPTY,A':
 ROOM='ADC1_BOM1';

SECTION_NUMBER 1
 '@S9S_MB_2U_LIB.S9S_MB_2U(SCH_1):PAGE239_I196@PURE_QUANTA.Q_CAP(CHIPS)':
 C_PATH='@s9s_mb_2u_lib.s9s_mb_2u(sch_1):page239_i196@pure_quanta.q_cap(chips)',
 P_PATH='@s9s_mb_2u_lib.s9s_mb_2u(sch_1):page250_i196@pure_quanta.q_cap(chips)',
 PATH='I196',
 DRAWING='@S9S_MB_2U_LIB.S9S_MB_2U(SCH_1):PAGE239',
 PHYS_PAGE='250',
 XY='(350,3425)',
 ROT='0',
 VER='1',
 PACK_TYPE='0402',
 CDS_LIB='pure_quanta',
 CDS_PART_NAME='Q_CAP_0402-100PF,50V,5%,EMPTY,A',
 TOLERANCE='5%',
 MATERIAL='EMPTY',
 VOLTAGE='50V',
 ROOM='ADC1_BOM1',
 VALUE='100PF',
 PRIM_FILE='./archive_libs/logical/q_cap/chips/chips.prt';

PART_NAME
 C2044 'Q_CAP_0402-100PF,50V,5%,EMPTY,A':
 ROOM='ADC1_BOM1';

SECTION_NUMBER 1
 '@S9S_MB_2U_LIB.S9S_MB_2U(SCH_1):PAGE239_I187@PURE_QUANTA.Q_CAP(CHIPS)':
 C_PATH='@s9s_mb_2u_lib.s9s_mb_2u(sch_1):page239_i187@pure_quanta.q_cap(chips)',
 P_PATH='@s9s_mb_2u_lib.s9s_mb_2u(sch_1):page250_i187@pure_quanta.q_cap(chips)',
 PATH='I187',
 DRAWING='@S9S_MB_2U_LIB.S9S_MB_2U(SCH_1):PAGE239',
 PHYS_PAGE='250',
 XY='(325,2275)',
 ROT='0',
 VER='1',
 PACK_TYPE='0402',
 CDS_LIB='pure_quanta',
 CDS_PART_NAME='Q_CAP_0402-100PF,50V,5%,EMPTY,A',
 TOLERANCE='5%',
 MATERIAL='EMPTY',
 VOLTAGE='50V',
 ROOM='ADC1_BOM1',
 VALUE='100PF',
 PRIM_FILE='./archive_libs/logical/q_cap/chips/chips.prt';

PART_NAME
 C2045 'Q_CAP_0402-100PF,50V,5%,EMPTY,A':
 ROOM='ADC1_BOM1';

SECTION_NUMBER 1
 '@S9S_MB_2U_LIB.S9S_MB_2U(SCH_1):PAGE239_I236@PURE_QUANTA.Q_CAP(CHIPS)':
 C_PATH='@s9s_mb_2u_lib.s9s_mb_2u(sch_1):page239_i236@pure_quanta.q_cap(chips)',
 P_PATH='@s9s_mb_2u_lib.s9s_mb_2u(sch_1):page250_i236@pure_quanta.q_cap(chips)',
 PATH='I236',
 DRAWING='@S9S_MB_2U_LIB.S9S_MB_2U(SCH_1):PAGE239',
 PHYS_PAGE='250',
 XY='(1375,75)',
 ROT='0',
 VER='1',
 PACK_TYPE='0402',
 CDS_LIB='pure_quanta',
 CDS_PART_NAME='Q_CAP_0402-100PF,50V,5%,EMPTY,A',
 TOLERANCE='5%',
 MATERIAL='EMPTY',
 VOLTAGE='50V',
 ROOM='ADC1_BOM1',
 VALUE='100PF',
 PRIM_FILE='./archive_libs/logical/q_cap/chips/chips.prt';

PART_NAME
 C2046 'Q_CAP_0402-0.1UF,25V,10%,X7R,CA':
 ROOM='ADC1_BOM2';

SECTION_NUMBER 1
 '@S9S_MB_2U_LIB.S9S_MB_2U(SCH_1):PAGE239_I207@PURE_QUANTA.Q_CAP(CHIPS)':
 C_PATH='@s9s_mb_2u_lib.s9s_mb_2u(sch_1):page239_i207@pure_quanta.q_cap(chips)',
 P_PATH='@s9s_mb_2u_lib.s9s_mb_2u(sch_1):page250_i207@pure_quanta.q_cap(chips)',
 PATH='I207',
 DRAWING='@S9S_MB_2U_LIB.S9S_MB_2U(SCH_1):PAGE239',
 PHYS_PAGE='250',
 XY='(350,975)',
 ROT='2',
 VER='1',
 PACK_TYPE='0402',
 CDS_LIB='pure_quanta',
 CDS_PART_NAME='Q_CAP_0402-0.1UF,25V,10%,X7R,CA',
 TOLERANCE='10%',
 MATERIAL='X7R',
 VOLTAGE='25V',
 ROOM='ADC1_BOM2',
 VALUE='0.1UF',
 PRIM_FILE='./archive_libs/logical/q_cap/chips/chips.prt';

PART_NAME
 C2047 'Q_CAP_0402-0.1UF,25V,10%,X7R,CA':
 ROOM='ADC1_BOM2';

SECTION_NUMBER 1
 '@S9S_MB_2U_LIB.S9S_MB_2U(SCH_1):PAGE239_I181@PURE_QUANTA.Q_CAP(CHIPS)':
 C_PATH='@s9s_mb_2u_lib.s9s_mb_2u(sch_1):page239_i181@pure_quanta.q_cap(chips)',
 P_PATH='@s9s_mb_2u_lib.s9s_mb_2u(sch_1):page250_i181@pure_quanta.q_cap(chips)',
 PATH='I181',
 DRAWING='@S9S_MB_2U_LIB.S9S_MB_2U(SCH_1):PAGE239',
 PHYS_PAGE='250',
 XY='(75,4775)',
 ROT='2',
 VER='1',
 PACK_TYPE='0402',
 CDS_LIB='pure_quanta',
 CDS_PART_NAME='Q_CAP_0402-0.1UF,25V,10%,X7R,CA',
 TOLERANCE='10%',
 MATERIAL='X7R',
 VOLTAGE='25V',
 ROOM='ADC1_BOM2',
 VALUE='0.1UF',
 PRIM_FILE='./archive_libs/logical/q_cap/chips/chips.prt';

PART_NAME
 C2048 'Q_CAP_0402-0.1UF,25V,10%,X7R,CA':
 ROOM='ADC1_BOM2';

SECTION_NUMBER 1
 '@S9S_MB_2U_LIB.S9S_MB_2U(SCH_1):PAGE239_I197@PURE_QUANTA.Q_CAP(CHIPS)':
 C_PATH='@s9s_mb_2u_lib.s9s_mb_2u(sch_1):page239_i197@pure_quanta.q_cap(chips)',
 P_PATH='@s9s_mb_2u_lib.s9s_mb_2u(sch_1):page250_i197@pure_quanta.q_cap(chips)',
 PATH='I197',
 DRAWING='@S9S_MB_2U_LIB.S9S_MB_2U(SCH_1):PAGE239',
 PHYS_PAGE='250',
 XY='(0,3425)',
 ROT='2',
 VER='1',
 PACK_TYPE='0402',
 CDS_LIB='pure_quanta',
 CDS_PART_NAME='Q_CAP_0402-0.1UF,25V,10%,X7R,CA',
 TOLERANCE='10%',
 MATERIAL='X7R',
 VOLTAGE='25V',
 ROOM='ADC1_BOM2',
 VALUE='0.1UF',
 PRIM_FILE='./archive_libs/logical/q_cap/chips/chips.prt';

PART_NAME
 C2049 'Q_CAP_0402-0.1UF,25V,10%,X7R,CA':
 ROOM='ADC1_BOM2';

SECTION_NUMBER 1
 '@S9S_MB_2U_LIB.S9S_MB_2U(SCH_1):PAGE239_I188@PURE_QUANTA.Q_CAP(CHIPS)':
 C_PATH='@s9s_mb_2u_lib.s9s_mb_2u(sch_1):page239_i188@pure_quanta.q_cap(chips)',
 P_PATH='@s9s_mb_2u_lib.s9s_mb_2u(sch_1):page250_i188@pure_quanta.q_cap(chips)',
 PATH='I188',
 DRAWING='@S9S_MB_2U_LIB.S9S_MB_2U(SCH_1):PAGE239',
 PHYS_PAGE='250',
 XY='(-25,2275)',
 ROT='2',
 VER='1',
 PACK_TYPE='0402',
 CDS_LIB='pure_quanta',
 CDS_PART_NAME='Q_CAP_0402-0.1UF,25V,10%,X7R,CA',
 TOLERANCE='10%',
 MATERIAL='X7R',
 VOLTAGE='25V',
 ROOM='ADC1_BOM2',
 VALUE='0.1UF',
 PRIM_FILE='./archive_libs/logical/q_cap/chips/chips.prt';

PART_NAME
 C2050 'Q_CAP_0402-0.1UF,25V,10%,X7R,CA':
 ROOM='ADC1_BOM2';

SECTION_NUMBER 1
 '@S9S_MB_2U_LIB.S9S_MB_2U(SCH_1):PAGE239_I238@PURE_QUANTA.Q_CAP(CHIPS)':
 C_PATH='@s9s_mb_2u_lib.s9s_mb_2u(sch_1):page239_i238@pure_quanta.q_cap(chips)',
 P_PATH='@s9s_mb_2u_lib.s9s_mb_2u(sch_1):page250_i238@pure_quanta.q_cap(chips)',
 PATH='I238',
 DRAWING='@S9S_MB_2U_LIB.S9S_MB_2U(SCH_1):PAGE239',
 PHYS_PAGE='250',
 XY='(1025,75)',
 ROT='2',
 VER='1',
 PACK_TYPE='0402',
 CDS_LIB='pure_quanta',
 CDS_PART_NAME='Q_CAP_0402-0.1UF,25V,10%,X7R,CA',
 TOLERANCE='10%',
 MATERIAL='X7R',
 VOLTAGE='25V',
 ROOM='ADC1_BOM2',
 VALUE='0.1UF',
 PRIM_FILE='./archive_libs/logical/q_cap/chips/chips.prt';

PART_NAME
 C2051 'Q_CAP_0402-0.1UF,25V,10%,X7R,CA':
 ROOM='ADC1_BOM2';

SECTION_NUMBER 1
 '@S9S_MB_2U_LIB.S9S_MB_2U(SCH_1):PAGE239_I127@PURE_QUANTA.Q_CAP(CHIPS)':
 C_PATH='@s9s_mb_2u_lib.s9s_mb_2u(sch_1):page239_i127@pure_quanta.q_cap(chips)',
 P_PATH='@s9s_mb_2u_lib.s9s_mb_2u(sch_1):page250_i127@pure_quanta.q_cap(chips)',
 PATH='I127',
 DRAWING='@S9S_MB_2U_LIB.S9S_MB_2U(SCH_1):PAGE239',
 PHYS_PAGE='250',
 XY='(3725,1700)',
 ROT='2',
 VER='1',
 PACK_TYPE='0402',
 CDS_LIB='pure_quanta',
 CDS_PART_NAME='Q_CAP_0402-0.1UF,25V,10%,X7R,CA',
 TOLERANCE='10%',
 MATERIAL='X7R',
 VOLTAGE='25V',
 ROOM='ADC1_BOM2',
 VALUE='0.1UF',
 PRIM_FILE='./archive_libs/logical/q_cap/chips/chips.prt';

PART_NAME
 C2052 'Q_CAP_0402-0.1UF,25V,10%,X7R,CA':
 ROOM='ADC1_BOM2';

SECTION_NUMBER 1
 '@S9S_MB_2U_LIB.S9S_MB_2U(SCH_1):PAGE239_I128@PURE_QUANTA.Q_CAP(CHIPS)':
 C_PATH='@s9s_mb_2u_lib.s9s_mb_2u(sch_1):page239_i128@pure_quanta.q_cap(chips)',
 P_PATH='@s9s_mb_2u_lib.s9s_mb_2u(sch_1):page250_i128@pure_quanta.q_cap(chips)',
 PATH='I128',
 DRAWING='@S9S_MB_2U_LIB.S9S_MB_2U(SCH_1):PAGE239',
 PHYS_PAGE='250',
 XY='(4050,1700)',
 ROT='0',
 VER='1',
 PACK_TYPE='0402',
 CDS_LIB='pure_quanta',
 CDS_PART_NAME='Q_CAP_0402-0.1UF,25V,10%,X7R,CA',
 TOLERANCE='10%',
 MATERIAL='X7R',
 VOLTAGE='25V',
 ROOM='ADC1_BOM2',
 VALUE='0.1UF',
 PRIM_FILE='./archive_libs/logical/q_cap/chips/chips.prt';

PART_NAME
 C2056 'Q_CAP_0402-0.1UF,25V,10%,X7R,CA':;

SECTION_NUMBER 1
 '@S9S_MB_2U_LIB.S9S_MB_2U(SCH_1):PAGE221_I106@PURE_QUANTA.Q_CAP(CHIPS)':
 C_PATH='@s9s_mb_2u_lib.s9s_mb_2u(sch_1):page221_i106@pure_quanta.q_cap(chips)',
 P_PATH='@s9s_mb_2u_lib.s9s_mb_2u(sch_1):page233_i106@pure_quanta.q_cap(chips)',
 PATH='I106',
 DRAWING='@S9S_MB_2U_LIB.S9S_MB_2U(SCH_1):PAGE221',
 PHYS_PAGE='233',
 XY='(-625,3275)',
 ROT='0',
 VER='1',
 PACK_TYPE='0402',
 CDS_LIB='pure_quanta',
 CDS_PART_NAME='Q_CAP_0402-0.1UF,25V,10%,X7R,CA',
 TOLERANCE='10%',
 MATERIAL='X7R',
 VOLTAGE='25V',
 VALUE='0.1UF',
 PRIM_FILE='./archive_libs/logical/q_cap/chips/chips.prt';

PART_NAME
 C2067 'Q_CAP_0402-0.1UF,25V,10%,X7R,CA':;

SECTION_NUMBER 1
 '@S9S_MB_2U_LIB.S9S_MB_2U(SCH_1):PAGE295_I125@PURE_QUANTA.Q_CAP(CHIPS)':
 C_PATH='@s9s_mb_2u_lib.s9s_mb_2u(sch_1):page295_i125@pure_quanta.q_cap(chips)',
 P_PATH='@s9s_mb_2u_lib.s9s_mb_2u(sch_1):page171_i125@pure_quanta.q_cap(chips)',
 PATH='I125',
 DRAWING='@S9S_MB_2U_LIB.S9S_MB_2U(SCH_1):PAGE295',
 PHYS_PAGE='171',
 XY='(2175,1075)',
 ROT='0',
 VER='1',
 PACK_TYPE='0402',
 CDS_LIB='pure_quanta',
 CDS_PART_NAME='Q_CAP_0402-0.1UF,25V,10%,X7R,CA',
 TOLERANCE='10%',
 MATERIAL='X7R',
 VOLTAGE='25V',
 VALUE='0.1UF',
 PRIM_FILE='./archive_libs/logical/q_cap/chips/chips.prt';

PART_NAME
 C2069 'Q_CAP_0402-0.1UF,25V,10%,X7R,CA':;

SECTION_NUMBER 1
 '@S9S_MB_2U_LIB.S9S_MB_2U(SCH_1):PAGE295_I142@PURE_QUANTA.Q_CAP(CHIPS)':
 C_PATH='@s9s_mb_2u_lib.s9s_mb_2u(sch_1):page295_i142@pure_quanta.q_cap(chips)',
 P_PATH='@s9s_mb_2u_lib.s9s_mb_2u(sch_1):page171_i142@pure_quanta.q_cap(chips)',
 PATH='I142',
 DRAWING='@S9S_MB_2U_LIB.S9S_MB_2U(SCH_1):PAGE295',
 PHYS_PAGE='171',
 XY='(-500,650)',
 ROT='0',
 VER='1',
 PACK_TYPE='0402',
 CDS_LIB='pure_quanta',
 CDS_PART_NAME='Q_CAP_0402-0.1UF,25V,10%,X7R,CA',
 TOLERANCE='10%',
 MATERIAL='X7R',
 VOLTAGE='25V',
 VALUE='0.1UF',
 PRIM_FILE='./archive_libs/logical/q_cap/chips/chips.prt';

PART_NAME
 C2071 'Q_CAP_0402-0.1UF,25V,10%,X7R,CA':;

SECTION_NUMBER 1
 '@S9S_MB_2U_LIB.S9S_MB_2U(SCH_1):PAGE295_I133@PURE_QUANTA.Q_CAP(CHIPS)':
 C_PATH='@s9s_mb_2u_lib.s9s_mb_2u(sch_1):page295_i133@pure_quanta.q_cap(chips)',
 P_PATH='@s9s_mb_2u_lib.s9s_mb_2u(sch_1):page171_i133@pure_quanta.q_cap(chips)',
 PATH='I133',
 DRAWING='@S9S_MB_2U_LIB.S9S_MB_2U(SCH_1):PAGE295',
 PHYS_PAGE='171',
 XY='(1650,-275)',
 ROT='0',
 VER='1',
 PACK_TYPE='0402',
 CDS_LIB='pure_quanta',
 CDS_PART_NAME='Q_CAP_0402-0.1UF,25V,10%,X7R,CA',
 TOLERANCE='10%',
 MATERIAL='X7R',
 VOLTAGE='25V',
 VALUE='0.1UF',
 PRIM_FILE='./archive_libs/logical/q_cap/chips/chips.prt';

PART_NAME
 C2073 'Q_CAP_DIFFBUS_C0201-DIFF BUS_0A':;

SECTION_NUMBER 1
 '@S9S_MB_2U_LIB.S9S_MB_2U(SCH_1):PAGE173_I83@PURE_QUANTA.Q_CAP_DIFFBUS(CHIPS)':
 C_PATH='@s9s_mb_2u_lib.s9s_mb_2u(sch_1):page173_i83@pure_quanta.q_cap_diffbus(c~
hips)',
 P_PATH='@s9s_mb_2u_lib.s9s_mb_2u(sch_1):page181_i83@pure_quanta.q_cap_diffbus(c~
hips)',
 PATH='I83',
 DRAWING='@S9S_MB_2U_LIB.S9S_MB_2U(SCH_1):PAGE173',
 PIN_NAMES_ROTATE='TRUE',
 PHYS_PAGE='181',
 XY='(3025,2075)',
 ROT='0',
 VER='2',
 PACK_TYPE='C0201',
 CDS_LIB='pure_quanta',
 CDS_PART_NAME='Q_CAP_DIFFBUS_C0201-DIFF BUS_0A',
 TOLERANCE='20%',
 MATERIAL='X6S',
 VOLTAGE='6.3V',
 VALUE='DIFF BUS_0.22UF',
 PRIM_FILE='./archive_libs/logical/q_cap_diffbus/chips/chips.prt';

PART_NAME
 C2074 'Q_CAP_DIFFBUS_C0201-DIFF BUS_0A':;

SECTION_NUMBER 1
 '@S9S_MB_2U_LIB.S9S_MB_2U(SCH_1):PAGE173_I82@PURE_QUANTA.Q_CAP_DIFFBUS(CHIPS)':
 C_PATH='@s9s_mb_2u_lib.s9s_mb_2u(sch_1):page173_i82@pure_quanta.q_cap_diffbus(c~
hips)',
 P_PATH='@s9s_mb_2u_lib.s9s_mb_2u(sch_1):page181_i82@pure_quanta.q_cap_diffbus(c~
hips)',
 PATH='I82',
 DRAWING='@S9S_MB_2U_LIB.S9S_MB_2U(SCH_1):PAGE173',
 PIN_NAMES_ROTATE='TRUE',
 PHYS_PAGE='181',
 XY='(3025,2025)',
 ROT='0',
 VER='2',
 PACK_TYPE='C0201',
 CDS_LIB='pure_quanta',
 CDS_PART_NAME='Q_CAP_DIFFBUS_C0201-DIFF BUS_0A',
 TOLERANCE='20%',
 MATERIAL='X6S',
 VOLTAGE='6.3V',
 VALUE='DIFF BUS_0.22UF',
 PRIM_FILE='./archive_libs/logical/q_cap_diffbus/chips/chips.prt';

PART_NAME
 C2075 'Q_CAP_DIFFBUS_C0201-DIFF BUS_0A':;

SECTION_NUMBER 1
 '@S9S_MB_2U_LIB.S9S_MB_2U(SCH_1):PAGE173_I81@PURE_QUANTA.Q_CAP_DIFFBUS(CHIPS)':
 C_PATH='@s9s_mb_2u_lib.s9s_mb_2u(sch_1):page173_i81@pure_quanta.q_cap_diffbus(c~
hips)',
 P_PATH='@s9s_mb_2u_lib.s9s_mb_2u(sch_1):page181_i81@pure_quanta.q_cap_diffbus(c~
hips)',
 PATH='I81',
 DRAWING='@S9S_MB_2U_LIB.S9S_MB_2U(SCH_1):PAGE173',
 PIN_NAMES_ROTATE='TRUE',
 PHYS_PAGE='181',
 XY='(3025,1975)',
 ROT='0',
 VER='2',
 PACK_TYPE='C0201',
 CDS_LIB='pure_quanta',
 CDS_PART_NAME='Q_CAP_DIFFBUS_C0201-DIFF BUS_0A',
 TOLERANCE='20%',
 MATERIAL='X6S',
 VOLTAGE='6.3V',
 VALUE='DIFF BUS_0.22UF',
 PRIM_FILE='./archive_libs/logical/q_cap_diffbus/chips/chips.prt';

PART_NAME
 C2076 'Q_CAP_DIFFBUS_C0201-DIFF BUS_0A':;

SECTION_NUMBER 1
 '@S9S_MB_2U_LIB.S9S_MB_2U(SCH_1):PAGE173_I79@PURE_QUANTA.Q_CAP_DIFFBUS(CHIPS)':
 C_PATH='@s9s_mb_2u_lib.s9s_mb_2u(sch_1):page173_i79@pure_quanta.q_cap_diffbus(c~
hips)',
 P_PATH='@s9s_mb_2u_lib.s9s_mb_2u(sch_1):page181_i79@pure_quanta.q_cap_diffbus(c~
hips)',
 PATH='I79',
 DRAWING='@S9S_MB_2U_LIB.S9S_MB_2U(SCH_1):PAGE173',
 PIN_NAMES_ROTATE='TRUE',
 PHYS_PAGE='181',
 XY='(3025,1925)',
 ROT='0',
 VER='2',
 PACK_TYPE='C0201',
 CDS_LIB='pure_quanta',
 CDS_PART_NAME='Q_CAP_DIFFBUS_C0201-DIFF BUS_0A',
 TOLERANCE='20%',
 MATERIAL='X6S',
 VOLTAGE='6.3V',
 VALUE='DIFF BUS_0.22UF',
 PRIM_FILE='./archive_libs/logical/q_cap_diffbus/chips/chips.prt';

PART_NAME
 C2077 'Q_CAP_DIFFBUS_C0201-DIFF BUS_0A':;

SECTION_NUMBER 1
 '@S9S_MB_2U_LIB.S9S_MB_2U(SCH_1):PAGE173_I77@PURE_QUANTA.Q_CAP_DIFFBUS(CHIPS)':
 C_PATH='@s9s_mb_2u_lib.s9s_mb_2u(sch_1):page173_i77@pure_quanta.q_cap_diffbus(c~
hips)',
 P_PATH='@s9s_mb_2u_lib.s9s_mb_2u(sch_1):page181_i77@pure_quanta.q_cap_diffbus(c~
hips)',
 PATH='I77',
 DRAWING='@S9S_MB_2U_LIB.S9S_MB_2U(SCH_1):PAGE173',
 PIN_NAMES_ROTATE='TRUE',
 PHYS_PAGE='181',
 XY='(3025,1775)',
 ROT='0',
 VER='2',
 PACK_TYPE='C0201',
 CDS_LIB='pure_quanta',
 CDS_PART_NAME='Q_CAP_DIFFBUS_C0201-DIFF BUS_0A',
 TOLERANCE='20%',
 MATERIAL='X6S',
 VOLTAGE='6.3V',
 VALUE='DIFF BUS_0.22UF',
 PRIM_FILE='./archive_libs/logical/q_cap_diffbus/chips/chips.prt';

PART_NAME
 C2078 'Q_CAP_DIFFBUS_C0201-DIFF BUS_0A':;

SECTION_NUMBER 1
 '@S9S_MB_2U_LIB.S9S_MB_2U(SCH_1):PAGE173_I76@PURE_QUANTA.Q_CAP_DIFFBUS(CHIPS)':
 C_PATH='@s9s_mb_2u_lib.s9s_mb_2u(sch_1):page173_i76@pure_quanta.q_cap_diffbus(c~
hips)',
 P_PATH='@s9s_mb_2u_lib.s9s_mb_2u(sch_1):page181_i76@pure_quanta.q_cap_diffbus(c~
hips)',
 PATH='I76',
 DRAWING='@S9S_MB_2U_LIB.S9S_MB_2U(SCH_1):PAGE173',
 PIN_NAMES_ROTATE='TRUE',
 PHYS_PAGE='181',
 XY='(3025,1725)',
 ROT='0',
 VER='2',
 PACK_TYPE='C0201',
 CDS_LIB='pure_quanta',
 CDS_PART_NAME='Q_CAP_DIFFBUS_C0201-DIFF BUS_0A',
 TOLERANCE='20%',
 MATERIAL='X6S',
 VOLTAGE='6.3V',
 VALUE='DIFF BUS_0.22UF',
 PRIM_FILE='./archive_libs/logical/q_cap_diffbus/chips/chips.prt';

PART_NAME
 C2148 'Q_CAP_C0402-0.01UF,50V,10%,EMPA':;

SECTION_NUMBER 1
 '@S9S_MB_2U_LIB.S9S_MB_2U(SCH_1):PAGE131_I73@PURE_QUANTA.Q_CAP(CHIPS)':
 C_PATH='@s9s_mb_2u_lib.s9s_mb_2u(sch_1):page131_i73@pure_quanta.q_cap(chips)',
 P_PATH='@s9s_mb_2u_lib.s9s_mb_2u(sch_1):page162_i73@pure_quanta.q_cap(chips)',
 PATH='I73',
 DRAWING='@S9S_MB_2U_LIB.S9S_MB_2U(SCH_1):PAGE131',
 PHYS_PAGE='162',
 XY='(2250,-200)',
 ROT='0',
 VER='1',
 PACK_TYPE='C0402',
 CDS_LIB='pure_quanta',
 CDS_PART_NAME='Q_CAP_C0402-0.01UF,50V,10%,EMPA',
 TOLERANCE='10%',
 MATERIAL='EMPTY',
 VOLTAGE='50V',
 VALUE='0.01UF',
 PRIM_FILE='./archive_libs/logical/q_cap/chips/chips.prt';

PART_NAME
 C2175 'Q_CAP_0402-100PF,50V,5%,EMPTY,A':
 ROOM='ADC1_BOM1';

SECTION_NUMBER 1
 '@S9S_MB_2U_LIB.S9S_MB_2U(SCH_1):PAGE239_I309@PURE_QUANTA.Q_CAP(CHIPS)':
 C_PATH='@s9s_mb_2u_lib.s9s_mb_2u(sch_1):page239_i309@pure_quanta.q_cap(chips)',
 P_PATH='@s9s_mb_2u_lib.s9s_mb_2u(sch_1):page250_i309@pure_quanta.q_cap(chips)',
 PATH='I309',
 DRAWING='@S9S_MB_2U_LIB.S9S_MB_2U(SCH_1):PAGE239',
 PHYS_PAGE='250',
 XY='(2950,4075)',
 ROT='0',
 VER='1',
 PACK_TYPE='0402',
 CDS_LIB='pure_quanta',
 CDS_PART_NAME='Q_CAP_0402-100PF,50V,5%,EMPTY,A',
 TOLERANCE='5%',
 MATERIAL='EMPTY',
 VOLTAGE='50V',
 ROOM='ADC1_BOM1',
 VALUE='100PF',
 PRIM_FILE='./archive_libs/logical/q_cap/chips/chips.prt';

PART_NAME
 C2176 'Q_CAP_0402-100PF,50V,5%,EMPTY,A':
 ROOM='ADC1_BOM1';

SECTION_NUMBER 1
 '@S9S_MB_2U_LIB.S9S_MB_2U(SCH_1):PAGE239_I304@PURE_QUANTA.Q_CAP(CHIPS)':
 C_PATH='@s9s_mb_2u_lib.s9s_mb_2u(sch_1):page239_i304@pure_quanta.q_cap(chips)',
 P_PATH='@s9s_mb_2u_lib.s9s_mb_2u(sch_1):page250_i304@pure_quanta.q_cap(chips)',
 PATH='I304',
 DRAWING='@S9S_MB_2U_LIB.S9S_MB_2U(SCH_1):PAGE239',
 PHYS_PAGE='250',
 XY='(2975,5050)',
 ROT='0',
 VER='1',
 PACK_TYPE='0402',
 CDS_LIB='pure_quanta',
 CDS_PART_NAME='Q_CAP_0402-100PF,50V,5%,EMPTY,A',
 TOLERANCE='5%',
 MATERIAL='EMPTY',
 VOLTAGE='50V',
 ROOM='ADC1_BOM1',
 VALUE='100PF',
 PRIM_FILE='./archive_libs/logical/q_cap/chips/chips.prt';

PART_NAME
 C2177 'Q_CAP_0402-0.1UF,25V,10%,X7R,CA':
 ROOM='ADC1_BOM2';

SECTION_NUMBER 1
 '@S9S_MB_2U_LIB.S9S_MB_2U(SCH_1):PAGE239_I311@PURE_QUANTA.Q_CAP(CHIPS)':
 C_PATH='@s9s_mb_2u_lib.s9s_mb_2u(sch_1):page239_i311@pure_quanta.q_cap(chips)',
 P_PATH='@s9s_mb_2u_lib.s9s_mb_2u(sch_1):page250_i311@pure_quanta.q_cap(chips)',
 PATH='I311',
 DRAWING='@S9S_MB_2U_LIB.S9S_MB_2U(SCH_1):PAGE239',
 PHYS_PAGE='250',
 XY='(2925,3550)',
 ROT='2',
 VER='1',
 PACK_TYPE='0402',
 CDS_LIB='pure_quanta',
 CDS_PART_NAME='Q_CAP_0402-0.1UF,25V,10%,X7R,CA',
 TOLERANCE='10%',
 MATERIAL='X7R',
 VOLTAGE='25V',
 ROOM='ADC1_BOM2',
 VALUE='0.1UF',
 PRIM_FILE='./archive_libs/logical/q_cap/chips/chips.prt';

PART_NAME
 C2178 'Q_CAP_0402-0.1UF,25V,10%,X7R,CA':
 ROOM='ADC1_BOM2';

SECTION_NUMBER 1
 '@S9S_MB_2U_LIB.S9S_MB_2U(SCH_1):PAGE239_I305@PURE_QUANTA.Q_CAP(CHIPS)':
 C_PATH='@s9s_mb_2u_lib.s9s_mb_2u(sch_1):page239_i305@pure_quanta.q_cap(chips)',
 P_PATH='@s9s_mb_2u_lib.s9s_mb_2u(sch_1):page250_i305@pure_quanta.q_cap(chips)',
 PATH='I305',
 DRAWING='@S9S_MB_2U_LIB.S9S_MB_2U(SCH_1):PAGE239',
 PHYS_PAGE='250',
 XY='(2950,4525)',
 ROT='2',
 VER='1',
 PACK_TYPE='0402',
 CDS_LIB='pure_quanta',
 CDS_PART_NAME='Q_CAP_0402-0.1UF,25V,10%,X7R,CA',
 TOLERANCE='10%',
 MATERIAL='X7R',
 VOLTAGE='25V',
 ROOM='ADC1_BOM2',
 VALUE='0.1UF',
 PRIM_FILE='./archive_libs/logical/q_cap/chips/chips.prt';

PART_NAME
 C2179 'Q_CAP_C0402-100NF,50V,10%,X7R,A':;

SECTION_NUMBER 1
 '@S9S_MB_2U_LIB.S9S_MB_2U(SCH_1):PAGE303_I29@PURE_QUANTA.Q_CAP(CHIPS)':
 C_PATH='@s9s_mb_2u_lib.s9s_mb_2u(sch_1):page303_i29@pure_quanta.q_cap(chips)',
 P_PATH='@s9s_mb_2u_lib.s9s_mb_2u(sch_1):page301_i29@pure_quanta.q_cap(chips)',
 PATH='I29',
 DRAWING='@S9S_MB_2U_LIB.S9S_MB_2U(SCH_1):PAGE303',
 PHYS_PAGE='301',
 XY='(-14475,850)',
 ROT='0',
 VER='1',
 PACK_TYPE='C0402',
 LOCATION='C2179',
 CDS_LIB='pure_quanta',
 CDS_PART_NAME='Q_CAP_C0402-100NF,50V,10%,X7R,A',
 TOLERANCE='10%',
 MATERIAL='X7R',
 VOLTAGE='50V',
 VALUE='100NF',
 PRIM_FILE='./archive_libs/logical/q_cap/chips/chips.prt';

PART_NAME
 C2194 'Q_CAP_0402-0.1UF,25V,10%,X7R,CA':
 ROOM='ADC1_BOM2';

SECTION_NUMBER 1
 '@S9S_MB_2U_LIB.S9S_MB_2U(SCH_1):PAGE239_I336@PURE_QUANTA.Q_CAP(CHIPS)':
 C_PATH='@s9s_mb_2u_lib.s9s_mb_2u(sch_1):page239_i336@pure_quanta.q_cap(chips)',
 P_PATH='@s9s_mb_2u_lib.s9s_mb_2u(sch_1):page250_i336@pure_quanta.q_cap(chips)',
 PATH='I336',
 DRAWING='@S9S_MB_2U_LIB.S9S_MB_2U(SCH_1):PAGE239',
 PHYS_PAGE='250',
 XY='(2900,2550)',
 ROT='2',
 VER='1',
 PACK_TYPE='0402',
 CDS_LIB='pure_quanta',
 CDS_PART_NAME='Q_CAP_0402-0.1UF,25V,10%,X7R,CA',
 TOLERANCE='10%',
 MATERIAL='X7R',
 VOLTAGE='25V',
 ROOM='ADC1_BOM2',
 VALUE='0.1UF',
 PRIM_FILE='./archive_libs/logical/q_cap/chips/chips.prt';

PART_NAME
 C2195 'Q_CAP_0402-100PF,50V,5%,EMPTY,A':
 ROOM='ADC1_BOM1';

SECTION_NUMBER 1
 '@S9S_MB_2U_LIB.S9S_MB_2U(SCH_1):PAGE239_I333@PURE_QUANTA.Q_CAP(CHIPS)':
 C_PATH='@s9s_mb_2u_lib.s9s_mb_2u(sch_1):page239_i333@pure_quanta.q_cap(chips)',
 P_PATH='@s9s_mb_2u_lib.s9s_mb_2u(sch_1):page250_i333@pure_quanta.q_cap(chips)',
 PATH='I333',
 DRAWING='@S9S_MB_2U_LIB.S9S_MB_2U(SCH_1):PAGE239',
 PHYS_PAGE='250',
 XY='(2925,3075)',
 ROT='0',
 VER='1',
 PACK_TYPE='0402',
 CDS_LIB='pure_quanta',
 CDS_PART_NAME='Q_CAP_0402-100PF,50V,5%,EMPTY,A',
 TOLERANCE='5%',
 MATERIAL='EMPTY',
 VOLTAGE='50V',
 ROOM='ADC1_BOM1',
 VALUE='100PF',
 PRIM_FILE='./archive_libs/logical/q_cap/chips/chips.prt';

PART_NAME
 C2243 'Q_CAP_C0402-1UF,25V,10%,X6S,CHA':;

SECTION_NUMBER 1
 '@S9S_MB_2U_LIB.S9S_MB_2U(SCH_1):PAGE321_I85@PURE_QUANTA.Q_CAP(CHIPS)':
 C_PATH='@s9s_mb_2u_lib.s9s_mb_2u(sch_1):page321_i85@pure_quanta.q_cap(chips)',
 P_PATH='@s9s_mb_2u_lib.s9s_mb_2u(sch_1):page226_i85@pure_quanta.q_cap(chips)',
 PATH='I85',
 DRAWING='@S9S_MB_2U_LIB.S9S_MB_2U(SCH_1):PAGE321',
 PHYS_PAGE='226',
 XY='(-75,1975)',
 ROT='0',
 VER='1',
 PACK_TYPE='C0402',
 CDS_LIB='pure_quanta',
 CDS_PART_NAME='Q_CAP_C0402-1UF,25V,10%,X6S,CHA',
 TOLERANCE='10%',
 MATERIAL='X6S',
 VOLTAGE='25V',
 VALUE='1UF',
 PRIM_FILE='./archive_libs/logical/q_cap/chips/chips.prt';

PART_NAME
 C2246 'Q_CAP_C0402-1UF,25V,10%,X6S,CHA':;

SECTION_NUMBER 1
 '@S9S_MB_2U_LIB.S9S_MB_2U(SCH_1):PAGE322_I9@PURE_QUANTA.Q_CAP(CHIPS)':
 C_PATH='@s9s_mb_2u_lib.s9s_mb_2u(sch_1):page322_i9@pure_quanta.q_cap(chips)',
 P_PATH='@s9s_mb_2u_lib.s9s_mb_2u(sch_1):page225_i9@pure_quanta.q_cap(chips)',
 PATH='I9',
 DRAWING='@S9S_MB_2U_LIB.S9S_MB_2U(SCH_1):PAGE322',
 PHYS_PAGE='225',
 XY='(-8825,2300)',
 ROT='0',
 VER='1',
 PACK_TYPE='C0402',
 CDS_LIB='pure_quanta',
 CDS_PART_NAME='Q_CAP_C0402-1UF,25V,10%,X6S,CHA',
 TOLERANCE='10%',
 MATERIAL='X6S',
 VOLTAGE='25V',
 VALUE='1UF',
 PRIM_FILE='./archive_libs/logical/q_cap/chips/chips.prt';

PART_NAME
 C2247 'Q_CAP_C0402-1UF,25V,10%,X6S,CHA':;

SECTION_NUMBER 1
 '@S9S_MB_2U_LIB.S9S_MB_2U(SCH_1):PAGE322_I59@PURE_QUANTA.Q_CAP(CHIPS)':
 C_PATH='@s9s_mb_2u_lib.s9s_mb_2u(sch_1):page322_i59@pure_quanta.q_cap(chips)',
 P_PATH='@s9s_mb_2u_lib.s9s_mb_2u(sch_1):page225_i59@pure_quanta.q_cap(chips)',
 PATH='I59',
 DRAWING='@S9S_MB_2U_LIB.S9S_MB_2U(SCH_1):PAGE322',
 PHYS_PAGE='225',
 XY='(-8825,225)',
 ROT='0',
 VER='1',
 PACK_TYPE='C0402',
 CDS_LIB='pure_quanta',
 CDS_PART_NAME='Q_CAP_C0402-1UF,25V,10%,X6S,CHA',
 TOLERANCE='10%',
 MATERIAL='X6S',
 VOLTAGE='25V',
 VALUE='1UF',
 PRIM_FILE='./archive_libs/logical/q_cap/chips/chips.prt';

PART_NAME
 C2248 'Q_CAP_C0402-1UF,25V,10%,X6S,CHA':;

SECTION_NUMBER 1
 '@S9S_MB_2U_LIB.S9S_MB_2U(SCH_1):PAGE322_I83@PURE_QUANTA.Q_CAP(CHIPS)':
 C_PATH='@s9s_mb_2u_lib.s9s_mb_2u(sch_1):page322_i83@pure_quanta.q_cap(chips)',
 P_PATH='@s9s_mb_2u_lib.s9s_mb_2u(sch_1):page225_i83@pure_quanta.q_cap(chips)',
 PATH='I83',
 DRAWING='@S9S_MB_2U_LIB.S9S_MB_2U(SCH_1):PAGE322',
 PHYS_PAGE='225',
 XY='(-8825,-1675)',
 ROT='0',
 VER='1',
 PACK_TYPE='C0402',
 CDS_LIB='pure_quanta',
 CDS_PART_NAME='Q_CAP_C0402-1UF,25V,10%,X6S,CHA',
 TOLERANCE='10%',
 MATERIAL='X6S',
 VOLTAGE='25V',
 VALUE='1UF',
 PRIM_FILE='./archive_libs/logical/q_cap/chips/chips.prt';

PART_NAME
 C2249 'Q_CAP_0402-0.1UF,25V,10%,X7R,CA':;

SECTION_NUMBER 1
 '@S9S_MB_2U_LIB.S9S_MB_2U(SCH_1):PAGE321_I83@PURE_QUANTA.Q_CAP(CHIPS)':
 C_PATH='@s9s_mb_2u_lib.s9s_mb_2u(sch_1):page321_i83@pure_quanta.q_cap(chips)',
 P_PATH='@s9s_mb_2u_lib.s9s_mb_2u(sch_1):page226_i83@pure_quanta.q_cap(chips)',
 PATH='I83',
 DRAWING='@S9S_MB_2U_LIB.S9S_MB_2U(SCH_1):PAGE321',
 PHYS_PAGE='226',
 XY='(525,1850)',
 ROT='2',
 VER='1',
 PACK_TYPE='0402',
 CDS_LIB='pure_quanta',
 CDS_PART_NAME='Q_CAP_0402-0.1UF,25V,10%,X7R,CA',
 TOLERANCE='10%',
 MATERIAL='X7R',
 VOLTAGE='25V',
 VALUE='0.1UF',
 PRIM_FILE='./archive_libs/logical/q_cap/chips/chips.prt';

PART_NAME
 C2252 'Q_CAP_0402-0.1UF,25V,10%,X7R,CA':;

SECTION_NUMBER 1
 '@S9S_MB_2U_LIB.S9S_MB_2U(SCH_1):PAGE322_I101@PURE_QUANTA.Q_CAP(CHIPS)':
 C_PATH='@s9s_mb_2u_lib.s9s_mb_2u(sch_1):page322_i101@pure_quanta.q_cap(chips)',
 P_PATH='@s9s_mb_2u_lib.s9s_mb_2u(sch_1):page225_i101@pure_quanta.q_cap(chips)',
 PATH='I101',
 DRAWING='@S9S_MB_2U_LIB.S9S_MB_2U(SCH_1):PAGE322',
 PHYS_PAGE='225',
 XY='(-8225,2175)',
 ROT='2',
 VER='1',
 PACK_TYPE='0402',
 CDS_LIB='pure_quanta',
 CDS_PART_NAME='Q_CAP_0402-0.1UF,25V,10%,X7R,CA',
 TOLERANCE='10%',
 MATERIAL='X7R',
 VOLTAGE='25V',
 VALUE='0.1UF',
 PRIM_FILE='./archive_libs/logical/q_cap/chips/chips.prt';

PART_NAME
 C2253 'Q_CAP_0402-0.1UF,25V,10%,X7R,CA':;

SECTION_NUMBER 1
 '@S9S_MB_2U_LIB.S9S_MB_2U(SCH_1):PAGE322_I106@PURE_QUANTA.Q_CAP(CHIPS)':
 C_PATH='@s9s_mb_2u_lib.s9s_mb_2u(sch_1):page322_i106@pure_quanta.q_cap(chips)',
 P_PATH='@s9s_mb_2u_lib.s9s_mb_2u(sch_1):page225_i106@pure_quanta.q_cap(chips)',
 PATH='I106',
 DRAWING='@S9S_MB_2U_LIB.S9S_MB_2U(SCH_1):PAGE322',
 PHYS_PAGE='225',
 XY='(-8225,100)',
 ROT='2',
 VER='1',
 PACK_TYPE='0402',
 CDS_LIB='pure_quanta',
 CDS_PART_NAME='Q_CAP_0402-0.1UF,25V,10%,X7R,CA',
 TOLERANCE='10%',
 MATERIAL='X7R',
 VOLTAGE='25V',
 VALUE='0.1UF',
 PRIM_FILE='./archive_libs/logical/q_cap/chips/chips.prt';

PART_NAME
 C2254 'Q_CAP_0402-0.1UF,25V,10%,X7R,CA':;

SECTION_NUMBER 1
 '@S9S_MB_2U_LIB.S9S_MB_2U(SCH_1):PAGE322_I111@PURE_QUANTA.Q_CAP(CHIPS)':
 C_PATH='@s9s_mb_2u_lib.s9s_mb_2u(sch_1):page322_i111@pure_quanta.q_cap(chips)',
 P_PATH='@s9s_mb_2u_lib.s9s_mb_2u(sch_1):page225_i111@pure_quanta.q_cap(chips)',
 PATH='I111',
 DRAWING='@S9S_MB_2U_LIB.S9S_MB_2U(SCH_1):PAGE322',
 PHYS_PAGE='225',
 XY='(-8225,-1800)',
 ROT='2',
 VER='1',
 PACK_TYPE='0402',
 CDS_LIB='pure_quanta',
 CDS_PART_NAME='Q_CAP_0402-0.1UF,25V,10%,X7R,CA',
 TOLERANCE='10%',
 MATERIAL='X7R',
 VOLTAGE='25V',
 VALUE='0.1UF',
 PRIM_FILE='./archive_libs/logical/q_cap/chips/chips.prt';

PART_NAME
 C2255 'Q_CAP_C0402-8.2PF,50V,0.1P,NP0A':;

SECTION_NUMBER 1
 '@S9S_MB_2U_LIB.S9S_MB_2U(SCH_1):PAGE201_I165@PURE_QUANTA.Q_CAP(CHIPS)':
 C_PATH='@s9s_mb_2u_lib.s9s_mb_2u(sch_1):page201_i165@pure_quanta.q_cap(chips)',
 P_PATH='@s9s_mb_2u_lib.s9s_mb_2u(sch_1):page212_i165@pure_quanta.q_cap(chips)',
 PATH='I165',
 DRAWING='@S9S_MB_2U_LIB.S9S_MB_2U(SCH_1):PAGE201',
 PHYS_PAGE='212',
 XY='(-4350,3700)',
 ROT='0',
 VER='1',
 PACK_TYPE='C0402',
 LOCATION='C2255',
 CDS_LIB='pure_quanta',
 CDS_PART_NAME='Q_CAP_C0402-8.2PF,50V,0.1P,NP0A',
 TOLERANCE='0.1P',
 MATERIAL='NP0',
 VOLTAGE='50V',
 VALUE='8.2PF',
 PRIM_FILE='./archive_libs/logical/q_cap/chips/chips.prt';

PART_NAME
 C2256 'Q_CAP_C0402-8.2PF,50V,0.1P,NP0A':;

SECTION_NUMBER 1
 '@S9S_MB_2U_LIB.S9S_MB_2U(SCH_1):PAGE201_I166@PURE_QUANTA.Q_CAP(CHIPS)':
 C_PATH='@s9s_mb_2u_lib.s9s_mb_2u(sch_1):page201_i166@pure_quanta.q_cap(chips)',
 P_PATH='@s9s_mb_2u_lib.s9s_mb_2u(sch_1):page212_i166@pure_quanta.q_cap(chips)',
 PATH='I166',
 DRAWING='@S9S_MB_2U_LIB.S9S_MB_2U(SCH_1):PAGE201',
 PHYS_PAGE='212',
 XY='(-3475,3700)',
 ROT='0',
 VER='1',
 PACK_TYPE='C0402',
 LOCATION='C2256',
 CDS_LIB='pure_quanta',
 CDS_PART_NAME='Q_CAP_C0402-8.2PF,50V,0.1P,NP0A',
 TOLERANCE='0.1P',
 MATERIAL='NP0',
 VOLTAGE='50V',
 VALUE='8.2PF',
 PRIM_FILE='./archive_libs/logical/q_cap/chips/chips.prt';

PART_NAME
 C2257 'Q_CAP_0402-0.1UF,25V,10%,X7R,CA':;

SECTION_NUMBER 1
 '@S9S_MB_2U_LIB.S9S_MB_2U(SCH_1):PAGE201_I104@PURE_QUANTA.Q_CAP(CHIPS)':
 C_PATH='@s9s_mb_2u_lib.s9s_mb_2u(sch_1):page201_i104@pure_quanta.q_cap(chips)',
 P_PATH='@s9s_mb_2u_lib.s9s_mb_2u(sch_1):page212_i104@pure_quanta.q_cap(chips)',
 PATH='I104',
 DRAWING='@S9S_MB_2U_LIB.S9S_MB_2U(SCH_1):PAGE201',
 PHYS_PAGE='212',
 XY='(-2400,5000)',
 ROT='0',
 VER='1',
 PACK_TYPE='0402',
 CDS_LIB='pure_quanta',
 CDS_PART_NAME='Q_CAP_0402-0.1UF,25V,10%,X7R,CA',
 TOLERANCE='10%',
 MATERIAL='X7R',
 VOLTAGE='25V',
 VALUE='0.1UF',
 PRIM_FILE='./archive_libs/logical/q_cap/chips/chips.prt';

PART_NAME
 C2258 'Q_CAP_0402-0.1UF,25V,10%,X7R,CA':;

SECTION_NUMBER 1
 '@S9S_MB_2U_LIB.S9S_MB_2U(SCH_1):PAGE201_I105@PURE_QUANTA.Q_CAP(CHIPS)':
 C_PATH='@s9s_mb_2u_lib.s9s_mb_2u(sch_1):page201_i105@pure_quanta.q_cap(chips)',
 P_PATH='@s9s_mb_2u_lib.s9s_mb_2u(sch_1):page212_i105@pure_quanta.q_cap(chips)',
 PATH='I105',
 DRAWING='@S9S_MB_2U_LIB.S9S_MB_2U(SCH_1):PAGE201',
 PHYS_PAGE='212',
 XY='(-1600,5000)',
 ROT='0',
 VER='1',
 PACK_TYPE='0402',
 CDS_LIB='pure_quanta',
 CDS_PART_NAME='Q_CAP_0402-0.1UF,25V,10%,X7R,CA',
 TOLERANCE='10%',
 MATERIAL='X7R',
 VOLTAGE='25V',
 VALUE='0.1UF',
 PRIM_FILE='./archive_libs/logical/q_cap/chips/chips.prt';

PART_NAME
 C2259 'Q_CAP_0402-0.1UF,25V,10%,X7R,CA':;

SECTION_NUMBER 1
 '@S9S_MB_2U_LIB.S9S_MB_2U(SCH_1):PAGE201_I106@PURE_QUANTA.Q_CAP(CHIPS)':
 C_PATH='@s9s_mb_2u_lib.s9s_mb_2u(sch_1):page201_i106@pure_quanta.q_cap(chips)',
 P_PATH='@s9s_mb_2u_lib.s9s_mb_2u(sch_1):page212_i106@pure_quanta.q_cap(chips)',
 PATH='I106',
 DRAWING='@S9S_MB_2U_LIB.S9S_MB_2U(SCH_1):PAGE201',
 PHYS_PAGE='212',
 XY='(-725,4975)',
 ROT='0',
 VER='1',
 PACK_TYPE='0402',
 CDS_LIB='pure_quanta',
 CDS_PART_NAME='Q_CAP_0402-0.1UF,25V,10%,X7R,CA',
 TOLERANCE='10%',
 MATERIAL='X7R',
 VOLTAGE='25V',
 VALUE='0.1UF',
 PRIM_FILE='./archive_libs/logical/q_cap/chips/chips.prt';

PART_NAME
 C2264 'Q_CAP_0402-1000PF,50V,5%,EMPTYA':;

SECTION_NUMBER 1
 '@S9S_MB_2U_LIB.S9S_MB_2U(SCH_1):PAGE143_I2@PURE_QUANTA.Q_CAP(CHIPS)':
 C_PATH='@s9s_mb_2u_lib.s9s_mb_2u(sch_1):page143_i2@pure_quanta.q_cap(chips)',
 P_PATH='@s9s_mb_2u_lib.s9s_mb_2u(sch_1):page146_i2@pure_quanta.q_cap(chips)',
 PATH='I2',
 DRAWING='@S9S_MB_2U_LIB.S9S_MB_2U(SCH_1):PAGE143',
 PHYS_PAGE='146',
 XY='(800,3750)',
 ROT='0',
 VER='1',
 PACK_TYPE='0402',
 CDS_LIB='pure_quanta',
 CDS_PART_NAME='Q_CAP_0402-1000PF,50V,5%,EMPTYA',
 TOLERANCE='5%',
 MATERIAL='EMPTY',
 VOLTAGE='50V',
 VALUE='1000PF',
 PRIM_FILE='./archive_libs/logical/q_cap/chips/chips.prt';

PART_NAME
 C2265 'Q_CAP_0402-1000PF,50V,5%,EMPTYA':;

SECTION_NUMBER 1
 '@S9S_MB_2U_LIB.S9S_MB_2U(SCH_1):PAGE143_I40@PURE_QUANTA.Q_CAP(CHIPS)':
 C_PATH='@s9s_mb_2u_lib.s9s_mb_2u(sch_1):page143_i40@pure_quanta.q_cap(chips)',
 P_PATH='@s9s_mb_2u_lib.s9s_mb_2u(sch_1):page146_i40@pure_quanta.q_cap(chips)',
 PATH='I40',
 DRAWING='@S9S_MB_2U_LIB.S9S_MB_2U(SCH_1):PAGE143',
 PHYS_PAGE='146',
 XY='(800,925)',
 ROT='0',
 VER='1',
 PACK_TYPE='0402',
 CDS_LIB='pure_quanta',
 CDS_PART_NAME='Q_CAP_0402-1000PF,50V,5%,EMPTYA',
 TOLERANCE='5%',
 MATERIAL='EMPTY',
 VOLTAGE='50V',
 VALUE='1000PF',
 PRIM_FILE='./archive_libs/logical/q_cap/chips/chips.prt';

PART_NAME
 C2266 'Q_CAP_0402-1000PF,50V,5%,EMPTYA':;

SECTION_NUMBER 1
 '@S9S_MB_2U_LIB.S9S_MB_2U(SCH_1):PAGE143_I23@PURE_QUANTA.Q_CAP(CHIPS)':
 C_PATH='@s9s_mb_2u_lib.s9s_mb_2u(sch_1):page143_i23@pure_quanta.q_cap(chips)',
 P_PATH='@s9s_mb_2u_lib.s9s_mb_2u(sch_1):page146_i23@pure_quanta.q_cap(chips)',
 PATH='I23',
 DRAWING='@S9S_MB_2U_LIB.S9S_MB_2U(SCH_1):PAGE143',
 PHYS_PAGE='146',
 XY='(825,2375)',
 ROT='0',
 VER='1',
 PACK_TYPE='0402',
 CDS_LIB='pure_quanta',
 CDS_PART_NAME='Q_CAP_0402-1000PF,50V,5%,EMPTYA',
 TOLERANCE='5%',
 MATERIAL='EMPTY',
 VOLTAGE='50V',
 VALUE='1000PF',
 PRIM_FILE='./archive_libs/logical/q_cap/chips/chips.prt';

PART_NAME
 C2267 'Q_CAP_0402-1000PF,50V,5%,EMPTYA':;

SECTION_NUMBER 1
 '@S9S_MB_2U_LIB.S9S_MB_2U(SCH_1):PAGE143_I55@PURE_QUANTA.Q_CAP(CHIPS)':
 C_PATH='@s9s_mb_2u_lib.s9s_mb_2u(sch_1):page143_i55@pure_quanta.q_cap(chips)',
 P_PATH='@s9s_mb_2u_lib.s9s_mb_2u(sch_1):page146_i55@pure_quanta.q_cap(chips)',
 PATH='I55',
 DRAWING='@S9S_MB_2U_LIB.S9S_MB_2U(SCH_1):PAGE143',
 PHYS_PAGE='146',
 XY='(5425,4050)',
 ROT='0',
 VER='1',
 PACK_TYPE='0402',
 CDS_LIB='pure_quanta',
 CDS_PART_NAME='Q_CAP_0402-1000PF,50V,5%,EMPTYA',
 TOLERANCE='5%',
 MATERIAL='EMPTY',
 VOLTAGE='50V',
 VALUE='1000PF',
 PRIM_FILE='./archive_libs/logical/q_cap/chips/chips.prt';

PART_NAME
 C2268 'Q_CAP_0402-1000PF,50V,5%,EMPTYA':;

SECTION_NUMBER 1
 '@S9S_MB_2U_LIB.S9S_MB_2U(SCH_1):PAGE143_I66@PURE_QUANTA.Q_CAP(CHIPS)':
 C_PATH='@s9s_mb_2u_lib.s9s_mb_2u(sch_1):page143_i66@pure_quanta.q_cap(chips)',
 P_PATH='@s9s_mb_2u_lib.s9s_mb_2u(sch_1):page146_i66@pure_quanta.q_cap(chips)',
 PATH='I66',
 DRAWING='@S9S_MB_2U_LIB.S9S_MB_2U(SCH_1):PAGE143',
 PHYS_PAGE='146',
 XY='(5425,1225)',
 ROT='0',
 VER='1',
 PACK_TYPE='0402',
 CDS_LIB='pure_quanta',
 CDS_PART_NAME='Q_CAP_0402-1000PF,50V,5%,EMPTYA',
 TOLERANCE='5%',
 MATERIAL='EMPTY',
 VOLTAGE='50V',
 VALUE='1000PF',
 PRIM_FILE='./archive_libs/logical/q_cap/chips/chips.prt';

PART_NAME
 C2269 'Q_CAP_0402-1000PF,50V,5%,EMPTYA':;

SECTION_NUMBER 1
 '@S9S_MB_2U_LIB.S9S_MB_2U(SCH_1):PAGE143_I57@PURE_QUANTA.Q_CAP(CHIPS)':
 C_PATH='@s9s_mb_2u_lib.s9s_mb_2u(sch_1):page143_i57@pure_quanta.q_cap(chips)',
 P_PATH='@s9s_mb_2u_lib.s9s_mb_2u(sch_1):page146_i57@pure_quanta.q_cap(chips)',
 PATH='I57',
 DRAWING='@S9S_MB_2U_LIB.S9S_MB_2U(SCH_1):PAGE143',
 PHYS_PAGE='146',
 XY='(5450,2675)',
 ROT='0',
 VER='1',
 PACK_TYPE='0402',
 CDS_LIB='pure_quanta',
 CDS_PART_NAME='Q_CAP_0402-1000PF,50V,5%,EMPTYA',
 TOLERANCE='5%',
 MATERIAL='EMPTY',
 VOLTAGE='50V',
 VALUE='1000PF',
 PRIM_FILE='./archive_libs/logical/q_cap/chips/chips.prt';

PART_NAME
 C2270 'Q_CAP_0402-1000PF,50V,5%,EMPTYA':;

SECTION_NUMBER 1
 '@S9S_MB_2U_LIB.S9S_MB_2U(SCH_1):PAGE143_I105@PURE_QUANTA.Q_CAP(CHIPS)':
 C_PATH='@s9s_mb_2u_lib.s9s_mb_2u(sch_1):page143_i105@pure_quanta.q_cap(chips)',
 P_PATH='@s9s_mb_2u_lib.s9s_mb_2u(sch_1):page146_i105@pure_quanta.q_cap(chips)',
 PATH='I105',
 DRAWING='@S9S_MB_2U_LIB.S9S_MB_2U(SCH_1):PAGE143',
 PHYS_PAGE='146',
 XY='(875,-625)',
 ROT='0',
 VER='1',
 PACK_TYPE='0402',
 CDS_LIB='pure_quanta',
 CDS_PART_NAME='Q_CAP_0402-1000PF,50V,5%,EMPTYA',
 TOLERANCE='5%',
 MATERIAL='EMPTY',
 VOLTAGE='50V',
 VALUE='1000PF',
 PRIM_FILE='./archive_libs/logical/q_cap/chips/chips.prt';

PART_NAME
 C2271 'Q_CAP_0402-1000PF,50V,5%,EMPTYA':;

SECTION_NUMBER 1
 '@S9S_MB_2U_LIB.S9S_MB_2U(SCH_1):PAGE139_I44@PURE_QUANTA.Q_CAP(CHIPS)':
 C_PATH='@s9s_mb_2u_lib.s9s_mb_2u(sch_1):page139_i44@pure_quanta.q_cap(chips)',
 P_PATH='@s9s_mb_2u_lib.s9s_mb_2u(sch_1):page145_i44@pure_quanta.q_cap(chips)',
 PATH='I44',
 DRAWING='@S9S_MB_2U_LIB.S9S_MB_2U(SCH_1):PAGE139',
 PHYS_PAGE='145',
 XY='(1100,5225)',
 ROT='0',
 VER='1',
 PACK_TYPE='0402',
 CDS_LIB='pure_quanta',
 CDS_PART_NAME='Q_CAP_0402-1000PF,50V,5%,EMPTYA',
 TOLERANCE='5%',
 MATERIAL='EMPTY',
 VOLTAGE='50V',
 VALUE='1000PF',
 PRIM_FILE='./archive_libs/logical/q_cap/chips/chips.prt';

PART_NAME
 C2272 'Q_CAP_0402-1000PF,50V,5%,EMPTYA':;

SECTION_NUMBER 1
 '@S9S_MB_2U_LIB.S9S_MB_2U(SCH_1):PAGE139_I33@PURE_QUANTA.Q_CAP(CHIPS)':
 C_PATH='@s9s_mb_2u_lib.s9s_mb_2u(sch_1):page139_i33@pure_quanta.q_cap(chips)',
 P_PATH='@s9s_mb_2u_lib.s9s_mb_2u(sch_1):page145_i33@pure_quanta.q_cap(chips)',
 PATH='I33',
 DRAWING='@S9S_MB_2U_LIB.S9S_MB_2U(SCH_1):PAGE139',
 PHYS_PAGE='145',
 XY='(1100,2400)',
 ROT='0',
 VER='1',
 PACK_TYPE='0402',
 CDS_LIB='pure_quanta',
 CDS_PART_NAME='Q_CAP_0402-1000PF,50V,5%,EMPTYA',
 TOLERANCE='5%',
 MATERIAL='EMPTY',
 VOLTAGE='50V',
 VALUE='1000PF',
 PRIM_FILE='./archive_libs/logical/q_cap/chips/chips.prt';

PART_NAME
 C2273 'Q_CAP_0402-1000PF,50V,5%,EMPTYA':;

SECTION_NUMBER 1
 '@S9S_MB_2U_LIB.S9S_MB_2U(SCH_1):PAGE139_I42@PURE_QUANTA.Q_CAP(CHIPS)':
 C_PATH='@s9s_mb_2u_lib.s9s_mb_2u(sch_1):page139_i42@pure_quanta.q_cap(chips)',
 P_PATH='@s9s_mb_2u_lib.s9s_mb_2u(sch_1):page145_i42@pure_quanta.q_cap(chips)',
 PATH='I42',
 DRAWING='@S9S_MB_2U_LIB.S9S_MB_2U(SCH_1):PAGE139',
 PHYS_PAGE='145',
 XY='(1125,3850)',
 ROT='0',
 VER='1',
 PACK_TYPE='0402',
 CDS_LIB='pure_quanta',
 CDS_PART_NAME='Q_CAP_0402-1000PF,50V,5%,EMPTYA',
 TOLERANCE='5%',
 MATERIAL='EMPTY',
 VOLTAGE='50V',
 VALUE='1000PF',
 PRIM_FILE='./archive_libs/logical/q_cap/chips/chips.prt';

PART_NAME
 C2274 'Q_CAP_0402-0.1UF,25V,10%,X7R,CA':;

SECTION_NUMBER 1
 '@S9S_MB_2U_LIB.S9S_MB_2U(SCH_1):PAGE161_I139@PURE_QUANTA.Q_CAP(CHIPS)':
 C_PATH='@s9s_mb_2u_lib.s9s_mb_2u(sch_1):page161_i139@pure_quanta.q_cap(chips)',
 P_PATH='@s9s_mb_2u_lib.s9s_mb_2u(sch_1):page170_i139@pure_quanta.q_cap(chips)',
 PATH='I139',
 DRAWING='@S9S_MB_2U_LIB.S9S_MB_2U(SCH_1):PAGE161',
 PHYS_PAGE='170',
 XY='(2475,-2475)',
 ROT='2',
 VER='1',
 PACK_TYPE='0402',
 CDS_LIB='pure_quanta',
 CDS_PART_NAME='Q_CAP_0402-0.1UF,25V,10%,X7R,CA',
 TOLERANCE='10%',
 MATERIAL='X7R',
 VOLTAGE='25V',
 VALUE='0.1UF',
 PRIM_FILE='./archive_libs/logical/q_cap/chips/chips.prt';

PART_NAME
 C2275 'Q_CAP_0402-0.1UF,25V,10%,X7R,CA':;

SECTION_NUMBER 1
 '@S9S_MB_2U_LIB.S9S_MB_2U(SCH_1):PAGE161_I119@PURE_QUANTA.Q_CAP(CHIPS)':
 C_PATH='@s9s_mb_2u_lib.s9s_mb_2u(sch_1):page161_i119@pure_quanta.q_cap(chips)',
 P_PATH='@s9s_mb_2u_lib.s9s_mb_2u(sch_1):page170_i119@pure_quanta.q_cap(chips)',
 PATH='I119',
 DRAWING='@S9S_MB_2U_LIB.S9S_MB_2U(SCH_1):PAGE161',
 PHYS_PAGE='170',
 XY='(2525,-1000)',
 ROT='2',
 VER='1',
 PACK_TYPE='0402',
 CDS_LIB='pure_quanta',
 CDS_PART_NAME='Q_CAP_0402-0.1UF,25V,10%,X7R,CA',
 TOLERANCE='10%',
 MATERIAL='X7R',
 VOLTAGE='25V',
 VALUE='0.1UF',
 PRIM_FILE='./archive_libs/logical/q_cap/chips/chips.prt';

PART_NAME
 C2276 'Q_CAP_0402-0.1UF,25V,10%,X7R,CA':;

SECTION_NUMBER 1
 '@S9S_MB_2U_LIB.S9S_MB_2U(SCH_1):PAGE161_I104@PURE_QUANTA.Q_CAP(CHIPS)':
 C_PATH='@s9s_mb_2u_lib.s9s_mb_2u(sch_1):page161_i104@pure_quanta.q_cap(chips)',
 P_PATH='@s9s_mb_2u_lib.s9s_mb_2u(sch_1):page170_i104@pure_quanta.q_cap(chips)',
 PATH='I104',
 DRAWING='@S9S_MB_2U_LIB.S9S_MB_2U(SCH_1):PAGE161',
 PHYS_PAGE='170',
 XY='(2550,475)',
 ROT='2',
 VER='1',
 PACK_TYPE='0402',
 CDS_LIB='pure_quanta',
 CDS_PART_NAME='Q_CAP_0402-0.1UF,25V,10%,X7R,CA',
 TOLERANCE='10%',
 MATERIAL='X7R',
 VOLTAGE='25V',
 VALUE='0.1UF',
 PRIM_FILE='./archive_libs/logical/q_cap/chips/chips.prt';

PART_NAME
 C2283 'Q_CAP_0402-0.1UF,25V,10%,X7R,CA':;

SECTION_NUMBER 1
 '@S9S_MB_2U_LIB.S9S_MB_2U(SCH_1):PAGE230_I40@PURE_QUANTA.Q_CAP(CHIPS)':
 C_PATH='@s9s_mb_2u_lib.s9s_mb_2u(sch_1):page230_i40@pure_quanta.q_cap(chips)',
 P_PATH='@s9s_mb_2u_lib.s9s_mb_2u(sch_1):page246_i40@pure_quanta.q_cap(chips)',
 PATH='I40',
 DRAWING='@S9S_MB_2U_LIB.S9S_MB_2U(SCH_1):PAGE230',
 PHYS_PAGE='246',
 XY='(1250,-350)',
 ROT='0',
 VER='1',
 PACK_TYPE='0402',
 CDS_LIB='pure_quanta',
 CDS_PART_NAME='Q_CAP_0402-0.1UF,25V,10%,X7R,CA',
 TOLERANCE='10%',
 MATERIAL='X7R',
 VOLTAGE='25V',
 VALUE='0.1UF',
 PRIM_FILE='./archive_libs/logical/q_cap/chips/chips.prt';

PART_NAME
 C2284 'Q_CAP_C0805-22UF,16V,20%,X6S,CB':;

SECTION_NUMBER 1
 '@S9S_MB_2U_LIB.S9S_MB_2U(SCH_1):PAGE162_I37@PURE_QUANTA.Q_CAP(CHIPS)':
 C_PATH='@s9s_mb_2u_lib.s9s_mb_2u(sch_1):page162_i37@pure_quanta.q_cap(chips)',
 P_PATH='@s9s_mb_2u_lib.s9s_mb_2u(sch_1):page169_i37@pure_quanta.q_cap(chips)',
 PATH='I37',
 DRAWING='@S9S_MB_2U_LIB.S9S_MB_2U(SCH_1):PAGE162',
 PHYS_PAGE='169',
 XY='(-3025,4375)',
 ROT='0',
 VER='1',
 PACK_TYPE='C0805',
 LOCATION='C2284',
 CDS_LIB='pure_quanta',
 CDS_PART_NAME='Q_CAP_C0805-22UF,16V,20%,X6S,CB',
 TOLERANCE='20%',
 MATERIAL='X6S',
 VOLTAGE='16V',
 VALUE='22UF',
 PRIM_FILE='./archive_libs/logical/q_cap/chips/chips.prt';

PART_NAME
 C2285 'Q_CAP_0402-0.1UF,25V,10%,X7R,CA':;

SECTION_NUMBER 1
 '@S9S_MB_2U_LIB.S9S_MB_2U(SCH_1):PAGE162_I44@PURE_QUANTA.Q_CAP(CHIPS)':
 C_PATH='@s9s_mb_2u_lib.s9s_mb_2u(sch_1):page162_i44@pure_quanta.q_cap(chips)',
 P_PATH='@s9s_mb_2u_lib.s9s_mb_2u(sch_1):page169_i44@pure_quanta.q_cap(chips)',
 PATH='I44',
 DRAWING='@S9S_MB_2U_LIB.S9S_MB_2U(SCH_1):PAGE162',
 PHYS_PAGE='169',
 XY='(-2650,4375)',
 ROT='0',
 VER='1',
 PACK_TYPE='0402',
 CDS_LIB='pure_quanta',
 CDS_PART_NAME='Q_CAP_0402-0.1UF,25V,10%,X7R,CA',
 TOLERANCE='10%',
 MATERIAL='X7R',
 VOLTAGE='25V',
 VALUE='0.1UF',
 PRIM_FILE='./archive_libs/logical/q_cap/chips/chips.prt';

PART_NAME
 C2286 'Q_CAP_0402-0.1UF,25V,10%,X7R,CA':;

SECTION_NUMBER 1
 '@S9S_MB_2U_LIB.S9S_MB_2U(SCH_1):PAGE162_I45@PURE_QUANTA.Q_CAP(CHIPS)':
 C_PATH='@s9s_mb_2u_lib.s9s_mb_2u(sch_1):page162_i45@pure_quanta.q_cap(chips)',
 P_PATH='@s9s_mb_2u_lib.s9s_mb_2u(sch_1):page169_i45@pure_quanta.q_cap(chips)',
 PATH='I45',
 DRAWING='@S9S_MB_2U_LIB.S9S_MB_2U(SCH_1):PAGE162',
 PHYS_PAGE='169',
 XY='(-2375,4375)',
 ROT='0',
 VER='1',
 PACK_TYPE='0402',
 CDS_LIB='pure_quanta',
 CDS_PART_NAME='Q_CAP_0402-0.1UF,25V,10%,X7R,CA',
 TOLERANCE='10%',
 MATERIAL='X7R',
 VOLTAGE='25V',
 VALUE='0.1UF',
 PRIM_FILE='./archive_libs/logical/q_cap/chips/chips.prt';

PART_NAME
 C2287 'Q_CAP_C0402-0.01UF,50V,10%,X7RA':;

SECTION_NUMBER 1
 '@S9S_MB_2U_LIB.S9S_MB_2U(SCH_1):PAGE249_I36@PURE_QUANTA.Q_CAP(CHIPS)':
 C_PATH='@s9s_mb_2u_lib.s9s_mb_2u(sch_1):page249_i36@pure_quanta.q_cap(chips)',
 P_PATH='@s9s_mb_2u_lib.s9s_mb_2u(sch_1):page263_i36@pure_quanta.q_cap(chips)',
 PATH='I36',
 DRAWING='@S9S_MB_2U_LIB.S9S_MB_2U(SCH_1):PAGE249',
 PHYS_PAGE='263',
 XY='(-775,6575)',
 ROT='0',
 VER='1',
 PACK_TYPE='C0402',
 LOCATION='C2287',
 CDS_LIB='pure_quanta',
 CDS_PART_NAME='Q_CAP_C0402-0.01UF,50V,10%,X7RA',
 TOLERANCE='10%',
 MATERIAL='X7R',
 VOLTAGE='50V',
 VALUE='0.01UF',
 PRIM_FILE='./archive_libs/logical/q_cap/chips/chips.prt';

PART_NAME
 C2289 'Q_CAP_C0201-0.1UF,6.3V,10%,X6SA':;

SECTION_NUMBER 1
 '@S9S_MB_2U_LIB.S9S_MB_2U(SCH_1):PAGE162_I57@PURE_QUANTA.Q_CAP(CHIPS)':
 C_PATH='@s9s_mb_2u_lib.s9s_mb_2u(sch_1):page162_i57@pure_quanta.q_cap(chips)',
 P_PATH='@s9s_mb_2u_lib.s9s_mb_2u(sch_1):page169_i57@pure_quanta.q_cap(chips)',
 PATH='I57',
 DRAWING='@S9S_MB_2U_LIB.S9S_MB_2U(SCH_1):PAGE162',
 PHYS_PAGE='169',
 XY='(0,4075)',
 ROT='0',
 VER='2',
 PACK_TYPE='C0201',
 CDS_LIB='pure_quanta',
 CDS_PART_NAME='Q_CAP_C0201-0.1UF,6.3V,10%,X6SA',
 TOLERANCE='10%',
 MATERIAL='X6S',
 VOLTAGE='6.3V',
 VALUE='0.1UF',
 PRIM_FILE='./archive_libs/logical/q_cap/chips/chips.prt';

PART_NAME
 C2290 'Q_CAP_C0201-0.1UF,6.3V,10%,X6SA':;

SECTION_NUMBER 1
 '@S9S_MB_2U_LIB.S9S_MB_2U(SCH_1):PAGE162_I56@PURE_QUANTA.Q_CAP(CHIPS)':
 C_PATH='@s9s_mb_2u_lib.s9s_mb_2u(sch_1):page162_i56@pure_quanta.q_cap(chips)',
 P_PATH='@s9s_mb_2u_lib.s9s_mb_2u(sch_1):page169_i56@pure_quanta.q_cap(chips)',
 PATH='I56',
 DRAWING='@S9S_MB_2U_LIB.S9S_MB_2U(SCH_1):PAGE162',
 PHYS_PAGE='169',
 XY='(0,4025)',
 ROT='0',
 VER='2',
 PACK_TYPE='C0201',
 CDS_LIB='pure_quanta',
 CDS_PART_NAME='Q_CAP_C0201-0.1UF,6.3V,10%,X6SA',
 TOLERANCE='10%',
 MATERIAL='X6S',
 VOLTAGE='6.3V',
 VALUE='0.1UF',
 PRIM_FILE='./archive_libs/logical/q_cap/chips/chips.prt';

PART_NAME
 C2291 'Q_CAP_C0201-0.1UF,6.3V,10%,X6SA':;

SECTION_NUMBER 1
 '@S9S_MB_2U_LIB.S9S_MB_2U(SCH_1):PAGE162_I55@PURE_QUANTA.Q_CAP(CHIPS)':
 C_PATH='@s9s_mb_2u_lib.s9s_mb_2u(sch_1):page162_i55@pure_quanta.q_cap(chips)',
 P_PATH='@s9s_mb_2u_lib.s9s_mb_2u(sch_1):page169_i55@pure_quanta.q_cap(chips)',
 PATH='I55',
 DRAWING='@S9S_MB_2U_LIB.S9S_MB_2U(SCH_1):PAGE162',
 PHYS_PAGE='169',
 XY='(0,3875)',
 ROT='0',
 VER='2',
 PACK_TYPE='C0201',
 CDS_LIB='pure_quanta',
 CDS_PART_NAME='Q_CAP_C0201-0.1UF,6.3V,10%,X6SA',
 TOLERANCE='10%',
 MATERIAL='X6S',
 VOLTAGE='6.3V',
 VALUE='0.1UF',
 PRIM_FILE='./archive_libs/logical/q_cap/chips/chips.prt';

PART_NAME
 C2292 'Q_CAP_C0201-0.1UF,6.3V,10%,X6SA':;

SECTION_NUMBER 1
 '@S9S_MB_2U_LIB.S9S_MB_2U(SCH_1):PAGE162_I54@PURE_QUANTA.Q_CAP(CHIPS)':
 C_PATH='@s9s_mb_2u_lib.s9s_mb_2u(sch_1):page162_i54@pure_quanta.q_cap(chips)',
 P_PATH='@s9s_mb_2u_lib.s9s_mb_2u(sch_1):page169_i54@pure_quanta.q_cap(chips)',
 PATH='I54',
 DRAWING='@S9S_MB_2U_LIB.S9S_MB_2U(SCH_1):PAGE162',
 PHYS_PAGE='169',
 XY='(0,3825)',
 ROT='0',
 VER='2',
 PACK_TYPE='C0201',
 CDS_LIB='pure_quanta',
 CDS_PART_NAME='Q_CAP_C0201-0.1UF,6.3V,10%,X6SA',
 TOLERANCE='10%',
 MATERIAL='X6S',
 VOLTAGE='6.3V',
 VALUE='0.1UF',
 PRIM_FILE='./archive_libs/logical/q_cap/chips/chips.prt';

PART_NAME
 C2293 'Q_CAP_0402-0.1UF,25V,10%,EMPTYA':;

SECTION_NUMBER 1
 '@S9S_MB_2U_LIB.S9S_MB_2U(SCH_1):PAGE233_I57@PURE_QUANTA.Q_CAP(CHIPS)':
 C_PATH='@s9s_mb_2u_lib.s9s_mb_2u(sch_1):page233_i57@pure_quanta.q_cap(chips)',
 P_PATH='@s9s_mb_2u_lib.s9s_mb_2u(sch_1):page245_i57@pure_quanta.q_cap(chips)',
 PATH='I57',
 DRAWING='@S9S_MB_2U_LIB.S9S_MB_2U(SCH_1):PAGE233',
 PHYS_PAGE='245',
 XY='(750,1325)',
 ROT='0',
 VER='2',
 PACK_TYPE='0402',
 CDS_LIB='pure_quanta',
 CDS_PART_NAME='Q_CAP_0402-0.1UF,25V,10%,EMPTYA',
 TOLERANCE='10%',
 MATERIAL='EMPTY',
 VOLTAGE='25V',
 VALUE='0.1UF',
 PRIM_FILE='./archive_libs/logical/q_cap/chips/chips.prt';

PART_NAME
 C2294 'Q_CAP_0402-0.1UF,25V,10%,EMPTYA':;

SECTION_NUMBER 1
 '@S9S_MB_2U_LIB.S9S_MB_2U(SCH_1):PAGE233_I55@PURE_QUANTA.Q_CAP(CHIPS)':
 C_PATH='@s9s_mb_2u_lib.s9s_mb_2u(sch_1):page233_i55@pure_quanta.q_cap(chips)',
 P_PATH='@s9s_mb_2u_lib.s9s_mb_2u(sch_1):page245_i55@pure_quanta.q_cap(chips)',
 PATH='I55',
 DRAWING='@S9S_MB_2U_LIB.S9S_MB_2U(SCH_1):PAGE233',
 PHYS_PAGE='245',
 XY='(750,1175)',
 ROT='0',
 VER='2',
 PACK_TYPE='0402',
 CDS_LIB='pure_quanta',
 CDS_PART_NAME='Q_CAP_0402-0.1UF,25V,10%,EMPTYA',
 TOLERANCE='10%',
 MATERIAL='EMPTY',
 VOLTAGE='25V',
 VALUE='0.1UF',
 PRIM_FILE='./archive_libs/logical/q_cap/chips/chips.prt';

PART_NAME
 C2295 'Q_CAP_0402-0.1UF,25V,10%,EMPTYA':;

SECTION_NUMBER 1
 '@S9S_MB_2U_LIB.S9S_MB_2U(SCH_1):PAGE233_I54@PURE_QUANTA.Q_CAP(CHIPS)':
 C_PATH='@s9s_mb_2u_lib.s9s_mb_2u(sch_1):page233_i54@pure_quanta.q_cap(chips)',
 P_PATH='@s9s_mb_2u_lib.s9s_mb_2u(sch_1):page245_i54@pure_quanta.q_cap(chips)',
 PATH='I54',
 DRAWING='@S9S_MB_2U_LIB.S9S_MB_2U(SCH_1):PAGE233',
 PHYS_PAGE='245',
 XY='(750,1025)',
 ROT='0',
 VER='2',
 PACK_TYPE='0402',
 CDS_LIB='pure_quanta',
 CDS_PART_NAME='Q_CAP_0402-0.1UF,25V,10%,EMPTYA',
 TOLERANCE='10%',
 MATERIAL='EMPTY',
 VOLTAGE='25V',
 VALUE='0.1UF',
 PRIM_FILE='./archive_libs/logical/q_cap/chips/chips.prt';

PART_NAME
 C2296 'Q_CAP_0402-0.1UF,25V,10%,EMPTYA':;

SECTION_NUMBER 1
 '@S9S_MB_2U_LIB.S9S_MB_2U(SCH_1):PAGE233_I53@PURE_QUANTA.Q_CAP(CHIPS)':
 C_PATH='@s9s_mb_2u_lib.s9s_mb_2u(sch_1):page233_i53@pure_quanta.q_cap(chips)',
 P_PATH='@s9s_mb_2u_lib.s9s_mb_2u(sch_1):page245_i53@pure_quanta.q_cap(chips)',
 PATH='I53',
 DRAWING='@S9S_MB_2U_LIB.S9S_MB_2U(SCH_1):PAGE233',
 PHYS_PAGE='245',
 XY='(750,875)',
 ROT='0',
 VER='2',
 PACK_TYPE='0402',
 CDS_LIB='pure_quanta',
 CDS_PART_NAME='Q_CAP_0402-0.1UF,25V,10%,EMPTYA',
 TOLERANCE='10%',
 MATERIAL='EMPTY',
 VOLTAGE='25V',
 VALUE='0.1UF',
 PRIM_FILE='./archive_libs/logical/q_cap/chips/chips.prt';

PART_NAME
 C2297 'Q_CAP_0402-0.1UF,25V,10%,EMPTYA':;

SECTION_NUMBER 1
 '@S9S_MB_2U_LIB.S9S_MB_2U(SCH_1):PAGE233_I52@PURE_QUANTA.Q_CAP(CHIPS)':
 C_PATH='@s9s_mb_2u_lib.s9s_mb_2u(sch_1):page233_i52@pure_quanta.q_cap(chips)',
 P_PATH='@s9s_mb_2u_lib.s9s_mb_2u(sch_1):page245_i52@pure_quanta.q_cap(chips)',
 PATH='I52',
 DRAWING='@S9S_MB_2U_LIB.S9S_MB_2U(SCH_1):PAGE233',
 PHYS_PAGE='245',
 XY='(750,725)',
 ROT='0',
 VER='2',
 PACK_TYPE='0402',
 CDS_LIB='pure_quanta',
 CDS_PART_NAME='Q_CAP_0402-0.1UF,25V,10%,EMPTYA',
 TOLERANCE='10%',
 MATERIAL='EMPTY',
 VOLTAGE='25V',
 VALUE='0.1UF',
 PRIM_FILE='./archive_libs/logical/q_cap/chips/chips.prt';

PART_NAME
 C2313 'Q_CAP_C0402-10UF,6.3V,20%,EMPTA':;

SECTION_NUMBER 1
 '@S9S_MB_2U_LIB.S9S_MB_2U(SCH_1):PAGE194_I43@PURE_QUANTA.Q_CAP(CHIPS)':
 C_PATH='@s9s_mb_2u_lib.s9s_mb_2u(sch_1):page194_i43@pure_quanta.q_cap(chips)',
 P_PATH='@s9s_mb_2u_lib.s9s_mb_2u(sch_1):page196_i43@pure_quanta.q_cap(chips)',
 PATH='I43',
 DRAWING='@S9S_MB_2U_LIB.S9S_MB_2U(SCH_1):PAGE194',
 PHYS_PAGE='196',
 XY='(-2800,2050)',
 ROT='0',
 VER='1',
 PACK_TYPE='C0402',
 CDS_LIB='pure_quanta',
 CDS_PART_NAME='Q_CAP_C0402-10UF,6.3V,20%,EMPTA',
 TOLERANCE='20%',
 MATERIAL='EMPTY',
 VOLTAGE='6.3V',
 VALUE='10UF',
 PRIM_FILE='./archive_libs/logical/q_cap/chips/chips.prt';

PART_NAME
 C2314 'Q_CAP_0402-0.1UF,25V,10%,EMPTYA':;

SECTION_NUMBER 1
 '@S9S_MB_2U_LIB.S9S_MB_2U(SCH_1):PAGE194_I45@PURE_QUANTA.Q_CAP(CHIPS)':
 C_PATH='@s9s_mb_2u_lib.s9s_mb_2u(sch_1):page194_i45@pure_quanta.q_cap(chips)',
 P_PATH='@s9s_mb_2u_lib.s9s_mb_2u(sch_1):page196_i45@pure_quanta.q_cap(chips)',
 PATH='I45',
 DRAWING='@S9S_MB_2U_LIB.S9S_MB_2U(SCH_1):PAGE194',
 PHYS_PAGE='196',
 XY='(-2425,2050)',
 ROT='2',
 VER='1',
 PACK_TYPE='0402',
 CDS_LIB='pure_quanta',
 CDS_PART_NAME='Q_CAP_0402-0.1UF,25V,10%,EMPTYA',
 TOLERANCE='10%',
 MATERIAL='EMPTY',
 VOLTAGE='25V',
 VALUE='0.1UF',
 PRIM_FILE='./archive_libs/logical/q_cap/chips/chips.prt';

PART_NAME
 C2315 'Q_CAP_0402-0.1UF,25V,10%,EMPTYA':;

SECTION_NUMBER 1
 '@S9S_MB_2U_LIB.S9S_MB_2U(SCH_1):PAGE194_I46@PURE_QUANTA.Q_CAP(CHIPS)':
 C_PATH='@s9s_mb_2u_lib.s9s_mb_2u(sch_1):page194_i46@pure_quanta.q_cap(chips)',
 P_PATH='@s9s_mb_2u_lib.s9s_mb_2u(sch_1):page196_i46@pure_quanta.q_cap(chips)',
 PATH='I46',
 DRAWING='@S9S_MB_2U_LIB.S9S_MB_2U(SCH_1):PAGE194',
 PHYS_PAGE='196',
 XY='(-2025,2050)',
 ROT='2',
 VER='1',
 PACK_TYPE='0402',
 CDS_LIB='pure_quanta',
 CDS_PART_NAME='Q_CAP_0402-0.1UF,25V,10%,EMPTYA',
 TOLERANCE='10%',
 MATERIAL='EMPTY',
 VOLTAGE='25V',
 VALUE='0.1UF',
 PRIM_FILE='./archive_libs/logical/q_cap/chips/chips.prt';

PART_NAME
 C2316 'Q_CAP_C0402-1UF,25V,10%,EMPTY,A':;

SECTION_NUMBER 1
 '@S9S_MB_2U_LIB.S9S_MB_2U(SCH_1):PAGE194_I47@PURE_QUANTA.Q_CAP(CHIPS)':
 C_PATH='@s9s_mb_2u_lib.s9s_mb_2u(sch_1):page194_i47@pure_quanta.q_cap(chips)',
 P_PATH='@s9s_mb_2u_lib.s9s_mb_2u(sch_1):page196_i47@pure_quanta.q_cap(chips)',
 PATH='I47',
 DRAWING='@S9S_MB_2U_LIB.S9S_MB_2U(SCH_1):PAGE194',
 PHYS_PAGE='196',
 XY='(-1650,2050)',
 ROT='0',
 VER='1',
 PACK_TYPE='C0402',
 CDS_LIB='pure_quanta',
 CDS_PART_NAME='Q_CAP_C0402-1UF,25V,10%,EMPTY,A',
 TOLERANCE='10%',
 MATERIAL='EMPTY',
 VOLTAGE='25V',
 VALUE='1UF',
 PRIM_FILE='./archive_libs/logical/q_cap/chips/chips.prt';

PART_NAME
 C2317 'Q_CAP_C0402-1UF,25V,10%,EMPTY,A':;

SECTION_NUMBER 1
 '@S9S_MB_2U_LIB.S9S_MB_2U(SCH_1):PAGE194_I15@PURE_QUANTA.Q_CAP(CHIPS)':
 C_PATH='@s9s_mb_2u_lib.s9s_mb_2u(sch_1):page194_i15@pure_quanta.q_cap(chips)',
 P_PATH='@s9s_mb_2u_lib.s9s_mb_2u(sch_1):page196_i15@pure_quanta.q_cap(chips)',
 PATH='I15',
 DRAWING='@S9S_MB_2U_LIB.S9S_MB_2U(SCH_1):PAGE194',
 PHYS_PAGE='196',
 XY='(-1625,700)',
 ROT='0',
 VER='1',
 PACK_TYPE='C0402',
 CDS_LIB='pure_quanta',
 CDS_PART_NAME='Q_CAP_C0402-1UF,25V,10%,EMPTY,A',
 TOLERANCE='10%',
 MATERIAL='EMPTY',
 VOLTAGE='25V',
 VALUE='1UF',
 PRIM_FILE='./archive_libs/logical/q_cap/chips/chips.prt';

PART_NAME
 C2318 'Q_CAP_0402-0.1UF,25V,10%,EMPTYA':;

SECTION_NUMBER 1
 '@S9S_MB_2U_LIB.S9S_MB_2U(SCH_1):PAGE194_I49@PURE_QUANTA.Q_CAP(CHIPS)':
 C_PATH='@s9s_mb_2u_lib.s9s_mb_2u(sch_1):page194_i49@pure_quanta.q_cap(chips)',
 P_PATH='@s9s_mb_2u_lib.s9s_mb_2u(sch_1):page196_i49@pure_quanta.q_cap(chips)',
 PATH='I49',
 DRAWING='@S9S_MB_2U_LIB.S9S_MB_2U(SCH_1):PAGE194',
 PHYS_PAGE='196',
 XY='(-1275,2050)',
 ROT='2',
 VER='1',
 PACK_TYPE='0402',
 CDS_LIB='pure_quanta',
 CDS_PART_NAME='Q_CAP_0402-0.1UF,25V,10%,EMPTYA',
 TOLERANCE='10%',
 MATERIAL='EMPTY',
 VOLTAGE='25V',
 VALUE='0.1UF',
 PRIM_FILE='./archive_libs/logical/q_cap/chips/chips.prt';

PART_NAME
 C2319 'Q_CAP_0402-0.1UF,25V,10%,EMPTYA':;

SECTION_NUMBER 1
 '@S9S_MB_2U_LIB.S9S_MB_2U(SCH_1):PAGE194_I51@PURE_QUANTA.Q_CAP(CHIPS)':
 C_PATH='@s9s_mb_2u_lib.s9s_mb_2u(sch_1):page194_i51@pure_quanta.q_cap(chips)',
 P_PATH='@s9s_mb_2u_lib.s9s_mb_2u(sch_1):page196_i51@pure_quanta.q_cap(chips)',
 PATH='I51',
 DRAWING='@S9S_MB_2U_LIB.S9S_MB_2U(SCH_1):PAGE194',
 PHYS_PAGE='196',
 XY='(-900,2050)',
 ROT='2',
 VER='1',
 PACK_TYPE='0402',
 CDS_LIB='pure_quanta',
 CDS_PART_NAME='Q_CAP_0402-0.1UF,25V,10%,EMPTYA',
 TOLERANCE='10%',
 MATERIAL='EMPTY',
 VOLTAGE='25V',
 VALUE='0.1UF',
 PRIM_FILE='./archive_libs/logical/q_cap/chips/chips.prt';

PART_NAME
 C2320 'Q_CAP_0402-0.1UF,25V,10%,EMPTYA':;

SECTION_NUMBER 1
 '@S9S_MB_2U_LIB.S9S_MB_2U(SCH_1):PAGE194_I52@PURE_QUANTA.Q_CAP(CHIPS)':
 C_PATH='@s9s_mb_2u_lib.s9s_mb_2u(sch_1):page194_i52@pure_quanta.q_cap(chips)',
 P_PATH='@s9s_mb_2u_lib.s9s_mb_2u(sch_1):page196_i52@pure_quanta.q_cap(chips)',
 PATH='I52',
 DRAWING='@S9S_MB_2U_LIB.S9S_MB_2U(SCH_1):PAGE194',
 PHYS_PAGE='196',
 XY='(-525,2050)',
 ROT='2',
 VER='1',
 PACK_TYPE='0402',
 CDS_LIB='pure_quanta',
 CDS_PART_NAME='Q_CAP_0402-0.1UF,25V,10%,EMPTYA',
 TOLERANCE='10%',
 MATERIAL='EMPTY',
 VOLTAGE='25V',
 VALUE='0.1UF',
 PRIM_FILE='./archive_libs/logical/q_cap/chips/chips.prt';

PART_NAME
 C2321 'Q_CAP_0402-0.1UF,25V,10%,EMPTYA':;

SECTION_NUMBER 1
 '@S9S_MB_2U_LIB.S9S_MB_2U(SCH_1):PAGE194_I2@PURE_QUANTA.Q_CAP(CHIPS)':
 C_PATH='@s9s_mb_2u_lib.s9s_mb_2u(sch_1):page194_i2@pure_quanta.q_cap(chips)',
 P_PATH='@s9s_mb_2u_lib.s9s_mb_2u(sch_1):page196_i2@pure_quanta.q_cap(chips)',
 PATH='I2',
 DRAWING='@S9S_MB_2U_LIB.S9S_MB_2U(SCH_1):PAGE194',
 PHYS_PAGE='196',
 XY='(-500,-2675)',
 ROT='0',
 VER='1',
 PACK_TYPE='0402',
 CDS_LIB='pure_quanta',
 CDS_PART_NAME='Q_CAP_0402-0.1UF,25V,10%,EMPTYA',
 TOLERANCE='10%',
 MATERIAL='EMPTY',
 VOLTAGE='25V',
 VALUE='0.1UF',
 PRIM_FILE='./archive_libs/logical/q_cap/chips/chips.prt';

PART_NAME
 C2322 'Q_CAP_C0402-1UF,25V,10%,EMPTY,A':;

SECTION_NUMBER 1
 '@S9S_MB_2U_LIB.S9S_MB_2U(SCH_1):PAGE194_I53@PURE_QUANTA.Q_CAP(CHIPS)':
 C_PATH='@s9s_mb_2u_lib.s9s_mb_2u(sch_1):page194_i53@pure_quanta.q_cap(chips)',
 P_PATH='@s9s_mb_2u_lib.s9s_mb_2u(sch_1):page196_i53@pure_quanta.q_cap(chips)',
 PATH='I53',
 DRAWING='@S9S_MB_2U_LIB.S9S_MB_2U(SCH_1):PAGE194',
 PHYS_PAGE='196',
 XY='(-175,2050)',
 ROT='0',
 VER='1',
 PACK_TYPE='C0402',
 CDS_LIB='pure_quanta',
 CDS_PART_NAME='Q_CAP_C0402-1UF,25V,10%,EMPTY,A',
 TOLERANCE='10%',
 MATERIAL='EMPTY',
 VOLTAGE='25V',
 VALUE='1UF',
 PRIM_FILE='./archive_libs/logical/q_cap/chips/chips.prt';

PART_NAME
 C2323 'Q_CAP_C0402-1UF,25V,10%,EMPTY,A':;

SECTION_NUMBER 1
 '@S9S_MB_2U_LIB.S9S_MB_2U(SCH_1):PAGE194_I56@PURE_QUANTA.Q_CAP(CHIPS)':
 C_PATH='@s9s_mb_2u_lib.s9s_mb_2u(sch_1):page194_i56@pure_quanta.q_cap(chips)',
 P_PATH='@s9s_mb_2u_lib.s9s_mb_2u(sch_1):page196_i56@pure_quanta.q_cap(chips)',
 PATH='I56',
 DRAWING='@S9S_MB_2U_LIB.S9S_MB_2U(SCH_1):PAGE194',
 PHYS_PAGE='196',
 XY='(925,-1725)',
 ROT='0',
 VER='1',
 PACK_TYPE='C0402',
 CDS_LIB='pure_quanta',
 CDS_PART_NAME='Q_CAP_C0402-1UF,25V,10%,EMPTY,A',
 TOLERANCE='10%',
 MATERIAL='EMPTY',
 VOLTAGE='25V',
 VALUE='1UF',
 PRIM_FILE='./archive_libs/logical/q_cap/chips/chips.prt';

PART_NAME
 C2324 'Q_CAP_0402-0.1UF,25V,10%,EMPTYA':;

SECTION_NUMBER 1
 '@S9S_MB_2U_LIB.S9S_MB_2U(SCH_1):PAGE194_I58@PURE_QUANTA.Q_CAP(CHIPS)':
 C_PATH='@s9s_mb_2u_lib.s9s_mb_2u(sch_1):page194_i58@pure_quanta.q_cap(chips)',
 P_PATH='@s9s_mb_2u_lib.s9s_mb_2u(sch_1):page196_i58@pure_quanta.q_cap(chips)',
 PATH='I58',
 DRAWING='@S9S_MB_2U_LIB.S9S_MB_2U(SCH_1):PAGE194',
 PHYS_PAGE='196',
 XY='(1375,-1725)',
 ROT='0',
 VER='1',
 PACK_TYPE='0402',
 CDS_LIB='pure_quanta',
 CDS_PART_NAME='Q_CAP_0402-0.1UF,25V,10%,EMPTYA',
 TOLERANCE='10%',
 MATERIAL='EMPTY',
 VOLTAGE='25V',
 VALUE='0.1UF',
 PRIM_FILE='./archive_libs/logical/q_cap/chips/chips.prt';

PART_NAME
 C2325 'Q_CAP_0402-0.1UF,25V,10%,EMPTYA':;

SECTION_NUMBER 1
 '@S9S_MB_2U_LIB.S9S_MB_2U(SCH_1):PAGE194_I55@PURE_QUANTA.Q_CAP(CHIPS)':
 C_PATH='@s9s_mb_2u_lib.s9s_mb_2u(sch_1):page194_i55@pure_quanta.q_cap(chips)',
 P_PATH='@s9s_mb_2u_lib.s9s_mb_2u(sch_1):page196_i55@pure_quanta.q_cap(chips)',
 PATH='I55',
 DRAWING='@S9S_MB_2U_LIB.S9S_MB_2U(SCH_1):PAGE194',
 PHYS_PAGE='196',
 XY='(2125,-2650)',
 ROT='0',
 VER='1',
 PACK_TYPE='0402',
 CDS_LIB='pure_quanta',
 CDS_PART_NAME='Q_CAP_0402-0.1UF,25V,10%,EMPTYA',
 TOLERANCE='10%',
 MATERIAL='EMPTY',
 VOLTAGE='25V',
 VALUE='0.1UF',
 PRIM_FILE='./archive_libs/logical/q_cap/chips/chips.prt';

PART_NAME
 C2326 'Q_CAP_C0402-12PF,50V,5%,EMPTY,A':;

SECTION_NUMBER 1
 '@S9S_MB_2U_LIB.S9S_MB_2U(SCH_1):PAGE194_I81@PURE_QUANTA.Q_CAP(CHIPS)':
 C_PATH='@s9s_mb_2u_lib.s9s_mb_2u(sch_1):page194_i81@pure_quanta.q_cap(chips)',
 P_PATH='@s9s_mb_2u_lib.s9s_mb_2u(sch_1):page196_i81@pure_quanta.q_cap(chips)',
 PATH='I81',
 DRAWING='@S9S_MB_2U_LIB.S9S_MB_2U(SCH_1):PAGE194',
 PHYS_PAGE='196',
 XY='(4125,1925)',
 ROT='0',
 VER='1',
 PACK_TYPE='C0402',
 CDS_LIB='pure_quanta',
 CDS_PART_NAME='Q_CAP_C0402-12PF,50V,5%,EMPTY,A',
 TOLERANCE='5%',
 MATERIAL='EMPTY',
 VOLTAGE='50V',
 VALUE='12PF',
 PRIM_FILE='./archive_libs/logical/q_cap/chips/chips.prt';

PART_NAME
 C2327 'Q_CAP_C0402-12PF,50V,5%,EMPTY,A':;

SECTION_NUMBER 1
 '@S9S_MB_2U_LIB.S9S_MB_2U(SCH_1):PAGE194_I85@PURE_QUANTA.Q_CAP(CHIPS)':
 C_PATH='@s9s_mb_2u_lib.s9s_mb_2u(sch_1):page194_i85@pure_quanta.q_cap(chips)',
 P_PATH='@s9s_mb_2u_lib.s9s_mb_2u(sch_1):page196_i85@pure_quanta.q_cap(chips)',
 PATH='I85',
 DRAWING='@S9S_MB_2U_LIB.S9S_MB_2U(SCH_1):PAGE194',
 PHYS_PAGE='196',
 XY='(5125,1925)',
 ROT='0',
 VER='1',
 PACK_TYPE='C0402',
 CDS_LIB='pure_quanta',
 CDS_PART_NAME='Q_CAP_C0402-12PF,50V,5%,EMPTY,A',
 TOLERANCE='5%',
 MATERIAL='EMPTY',
 VOLTAGE='50V',
 VALUE='12PF',
 PRIM_FILE='./archive_libs/logical/q_cap/chips/chips.prt';

PART_NAME
 C2328 'Q_CAP_C0603-10UF,6.3V,20%,X6S,A':;

SECTION_NUMBER 1
 '@S9S_MB_2U_LIB.S9S_MB_2U(SCH_1):PAGE200_I17@PURE_QUANTA.Q_CAP(CHIPS)':
 C_PATH='@s9s_mb_2u_lib.s9s_mb_2u(sch_1):page200_i17@pure_quanta.q_cap(chips)',
 P_PATH='@s9s_mb_2u_lib.s9s_mb_2u(sch_1):page211_i17@pure_quanta.q_cap(chips)',
 PATH='I17',
 DRAWING='@S9S_MB_2U_LIB.S9S_MB_2U(SCH_1):PAGE200',
 PHYS_PAGE='211',
 XY='(8600,7825)',
 ROT='0',
 VER='1',
 PACK_TYPE='C0603',
 CDS_LIB='pure_quanta',
 CDS_PART_NAME='Q_CAP_C0603-10UF,6.3V,20%,X6S,A',
 TOLERANCE='20%',
 MATERIAL='X6S',
 VOLTAGE='6.3V',
 VALUE='10UF',
 PRIM_FILE='./archive_libs/logical/q_cap/chips/chips.prt';

PART_NAME
 C2329 'Q_CAP_0402-0.1UF,25V,10%,X7R,CA':;

SECTION_NUMBER 1
 '@S9S_MB_2U_LIB.S9S_MB_2U(SCH_1):PAGE200_I54@PURE_QUANTA.Q_CAP(CHIPS)':
 C_PATH='@s9s_mb_2u_lib.s9s_mb_2u(sch_1):page200_i54@pure_quanta.q_cap(chips)',
 P_PATH='@s9s_mb_2u_lib.s9s_mb_2u(sch_1):page211_i54@pure_quanta.q_cap(chips)',
 PATH='I54',
 DRAWING='@S9S_MB_2U_LIB.S9S_MB_2U(SCH_1):PAGE200',
 PHYS_PAGE='211',
 XY='(8950,7825)',
 ROT='0',
 VER='1',
 PACK_TYPE='0402',
 CDS_LIB='pure_quanta',
 CDS_PART_NAME='Q_CAP_0402-0.1UF,25V,10%,X7R,CA',
 TOLERANCE='10%',
 MATERIAL='X7R',
 VOLTAGE='25V',
 VALUE='0.1UF',
 PRIM_FILE='./archive_libs/logical/q_cap/chips/chips.prt';

PART_NAME
 C2330 'Q_CAP_0402-0.1UF,25V,10%,X7R,CA':;

SECTION_NUMBER 1
 '@S9S_MB_2U_LIB.S9S_MB_2U(SCH_1):PAGE200_I55@PURE_QUANTA.Q_CAP(CHIPS)':
 C_PATH='@s9s_mb_2u_lib.s9s_mb_2u(sch_1):page200_i55@pure_quanta.q_cap(chips)',
 P_PATH='@s9s_mb_2u_lib.s9s_mb_2u(sch_1):page211_i55@pure_quanta.q_cap(chips)',
 PATH='I55',
 DRAWING='@S9S_MB_2U_LIB.S9S_MB_2U(SCH_1):PAGE200',
 PHYS_PAGE='211',
 XY='(9200,7825)',
 ROT='0',
 VER='1',
 PACK_TYPE='0402',
 CDS_LIB='pure_quanta',
 CDS_PART_NAME='Q_CAP_0402-0.1UF,25V,10%,X7R,CA',
 TOLERANCE='10%',
 MATERIAL='X7R',
 VOLTAGE='25V',
 VALUE='0.1UF',
 PRIM_FILE='./archive_libs/logical/q_cap/chips/chips.prt';

PART_NAME
 C2331 'Q_CAP_C0603-10UF,6.3V,20%,X6S,A':;

SECTION_NUMBER 1
 '@S9S_MB_2U_LIB.S9S_MB_2U(SCH_1):PAGE200_I5@PURE_QUANTA.Q_CAP(CHIPS)':
 C_PATH='@s9s_mb_2u_lib.s9s_mb_2u(sch_1):page200_i5@pure_quanta.q_cap(chips)',
 P_PATH='@s9s_mb_2u_lib.s9s_mb_2u(sch_1):page211_i5@pure_quanta.q_cap(chips)',
 PATH='I5',
 DRAWING='@S9S_MB_2U_LIB.S9S_MB_2U(SCH_1):PAGE200',
 PHYS_PAGE='211',
 XY='(6025,8175)',
 ROT='0',
 VER='1',
 PACK_TYPE='C0603',
 CDS_LIB='pure_quanta',
 CDS_PART_NAME='Q_CAP_C0603-10UF,6.3V,20%,X6S,A',
 TOLERANCE='20%',
 MATERIAL='X6S',
 VOLTAGE='6.3V',
 VALUE='10UF',
 PRIM_FILE='./archive_libs/logical/q_cap/chips/chips.prt';

PART_NAME
 C2332 'Q_CAP_C0603-10UF,6.3V,20%,X6S,A':;

SECTION_NUMBER 1
 '@S9S_MB_2U_LIB.S9S_MB_2U(SCH_1):PAGE200_I10@PURE_QUANTA.Q_CAP(CHIPS)':
 C_PATH='@s9s_mb_2u_lib.s9s_mb_2u(sch_1):page200_i10@pure_quanta.q_cap(chips)',
 P_PATH='@s9s_mb_2u_lib.s9s_mb_2u(sch_1):page211_i10@pure_quanta.q_cap(chips)',
 PATH='I10',
 DRAWING='@S9S_MB_2U_LIB.S9S_MB_2U(SCH_1):PAGE200',
 PHYS_PAGE='211',
 XY='(6050,7375)',
 ROT='0',
 VER='1',
 PACK_TYPE='C0603',
 CDS_LIB='pure_quanta',
 CDS_PART_NAME='Q_CAP_C0603-10UF,6.3V,20%,X6S,A',
 TOLERANCE='20%',
 MATERIAL='X6S',
 VOLTAGE='6.3V',
 VALUE='10UF',
 PRIM_FILE='./archive_libs/logical/q_cap/chips/chips.prt';

PART_NAME
 C2333 'Q_CAP_0402-0.1UF,25V,10%,X7R,CA':;

SECTION_NUMBER 1
 '@S9S_MB_2U_LIB.S9S_MB_2U(SCH_1):PAGE200_I56@PURE_QUANTA.Q_CAP(CHIPS)':
 C_PATH='@s9s_mb_2u_lib.s9s_mb_2u(sch_1):page200_i56@pure_quanta.q_cap(chips)',
 P_PATH='@s9s_mb_2u_lib.s9s_mb_2u(sch_1):page211_i56@pure_quanta.q_cap(chips)',
 PATH='I56',
 DRAWING='@S9S_MB_2U_LIB.S9S_MB_2U(SCH_1):PAGE200',
 PHYS_PAGE='211',
 XY='(9450,7825)',
 ROT='0',
 VER='1',
 PACK_TYPE='0402',
 CDS_LIB='pure_quanta',
 CDS_PART_NAME='Q_CAP_0402-0.1UF,25V,10%,X7R,CA',
 TOLERANCE='10%',
 MATERIAL='X7R',
 VOLTAGE='25V',
 VALUE='0.1UF',
 PRIM_FILE='./archive_libs/logical/q_cap/chips/chips.prt';

PART_NAME
 C2334 'Q_CAP_0402-0.1UF,25V,10%,X7R,CA':;

SECTION_NUMBER 1
 '@S9S_MB_2U_LIB.S9S_MB_2U(SCH_1):PAGE200_I58@PURE_QUANTA.Q_CAP(CHIPS)':
 C_PATH='@s9s_mb_2u_lib.s9s_mb_2u(sch_1):page200_i58@pure_quanta.q_cap(chips)',
 P_PATH='@s9s_mb_2u_lib.s9s_mb_2u(sch_1):page211_i58@pure_quanta.q_cap(chips)',
 PATH='I58',
 DRAWING='@S9S_MB_2U_LIB.S9S_MB_2U(SCH_1):PAGE200',
 PHYS_PAGE='211',
 XY='(6375,8175)',
 ROT='0',
 VER='1',
 PACK_TYPE='0402',
 CDS_LIB='pure_quanta',
 CDS_PART_NAME='Q_CAP_0402-0.1UF,25V,10%,X7R,CA',
 TOLERANCE='10%',
 MATERIAL='X7R',
 VOLTAGE='25V',
 VALUE='0.1UF',
 PRIM_FILE='./archive_libs/logical/q_cap/chips/chips.prt';

PART_NAME
 C2335 'Q_CAP_0402-0.1UF,25V,10%,X7R,CA':;

SECTION_NUMBER 1
 '@S9S_MB_2U_LIB.S9S_MB_2U(SCH_1):PAGE200_I59@PURE_QUANTA.Q_CAP(CHIPS)':
 C_PATH='@s9s_mb_2u_lib.s9s_mb_2u(sch_1):page200_i59@pure_quanta.q_cap(chips)',
 P_PATH='@s9s_mb_2u_lib.s9s_mb_2u(sch_1):page211_i59@pure_quanta.q_cap(chips)',
 PATH='I59',
 DRAWING='@S9S_MB_2U_LIB.S9S_MB_2U(SCH_1):PAGE200',
 PHYS_PAGE='211',
 XY='(6400,7375)',
 ROT='0',
 VER='1',
 PACK_TYPE='0402',
 CDS_LIB='pure_quanta',
 CDS_PART_NAME='Q_CAP_0402-0.1UF,25V,10%,X7R,CA',
 TOLERANCE='10%',
 MATERIAL='X7R',
 VOLTAGE='25V',
 VALUE='0.1UF',
 PRIM_FILE='./archive_libs/logical/q_cap/chips/chips.prt';

PART_NAME
 C2336 'Q_CAP_0402-0.1UF,25V,10%,X7R,CA':;

SECTION_NUMBER 1
 '@S9S_MB_2U_LIB.S9S_MB_2U(SCH_1):PAGE200_I57@PURE_QUANTA.Q_CAP(CHIPS)':
 C_PATH='@s9s_mb_2u_lib.s9s_mb_2u(sch_1):page200_i57@pure_quanta.q_cap(chips)',
 P_PATH='@s9s_mb_2u_lib.s9s_mb_2u(sch_1):page211_i57@pure_quanta.q_cap(chips)',
 PATH='I57',
 DRAWING='@S9S_MB_2U_LIB.S9S_MB_2U(SCH_1):PAGE200',
 PHYS_PAGE='211',
 XY='(9700,7825)',
 ROT='0',
 VER='1',
 PACK_TYPE='0402',
 CDS_LIB='pure_quanta',
 CDS_PART_NAME='Q_CAP_0402-0.1UF,25V,10%,X7R,CA',
 TOLERANCE='10%',
 MATERIAL='X7R',
 VOLTAGE='25V',
 VALUE='0.1UF',
 PRIM_FILE='./archive_libs/logical/q_cap/chips/chips.prt';

PART_NAME
 C2337 'Q_CAP_0402-0.1UF,25V,10%,X7R,CA':;

SECTION_NUMBER 1
 '@S9S_MB_2U_LIB.S9S_MB_2U(SCH_1):PAGE225_I5@PURE_QUANTA.Q_CAP(CHIPS)':
 C_PATH='@s9s_mb_2u_lib.s9s_mb_2u(sch_1):page225_i5@pure_quanta.q_cap(chips)',
 P_PATH='@s9s_mb_2u_lib.s9s_mb_2u(sch_1):page237_i5@pure_quanta.q_cap(chips)',
 PATH='I5',
 DRAWING='@S9S_MB_2U_LIB.S9S_MB_2U(SCH_1):PAGE225',
 PHYS_PAGE='237',
 XY='(-950,1075)',
 ROT='0',
 VER='1',
 PACK_TYPE='0402',
 CDS_LIB='pure_quanta',
 CDS_PART_NAME='Q_CAP_0402-0.1UF,25V,10%,X7R,CA',
 TOLERANCE='10%',
 MATERIAL='X7R',
 VOLTAGE='25V',
 VALUE='0.1UF',
 PRIM_FILE='./archive_libs/logical/q_cap/chips/chips.prt';

PART_NAME
 C2338 'Q_CAP_0402-0.1UF,25V,10%,X7R,CA':;

SECTION_NUMBER 1
 '@S9S_MB_2U_LIB.S9S_MB_2U(SCH_1):PAGE225_I8@PURE_QUANTA.Q_CAP(CHIPS)':
 C_PATH='@s9s_mb_2u_lib.s9s_mb_2u(sch_1):page225_i8@pure_quanta.q_cap(chips)',
 P_PATH='@s9s_mb_2u_lib.s9s_mb_2u(sch_1):page237_i8@pure_quanta.q_cap(chips)',
 PATH='I8',
 DRAWING='@S9S_MB_2U_LIB.S9S_MB_2U(SCH_1):PAGE225',
 PHYS_PAGE='237',
 XY='(725,1075)',
 ROT='0',
 VER='1',
 PACK_TYPE='0402',
 CDS_LIB='pure_quanta',
 CDS_PART_NAME='Q_CAP_0402-0.1UF,25V,10%,X7R,CA',
 TOLERANCE='10%',
 MATERIAL='X7R',
 VOLTAGE='25V',
 VALUE='0.1UF',
 PRIM_FILE='./archive_libs/logical/q_cap/chips/chips.prt';

PART_NAME
 C2339 'Q_CAP_0402-0.1UF,25V,10%,X7R,CA':;

SECTION_NUMBER 1
 '@S9S_MB_2U_LIB.S9S_MB_2U(SCH_1):PAGE200_I71@PURE_QUANTA.Q_CAP(CHIPS)':
 C_PATH='@s9s_mb_2u_lib.s9s_mb_2u(sch_1):page200_i71@pure_quanta.q_cap(chips)',
 P_PATH='@s9s_mb_2u_lib.s9s_mb_2u(sch_1):page211_i71@pure_quanta.q_cap(chips)',
 PATH='I71',
 DRAWING='@S9S_MB_2U_LIB.S9S_MB_2U(SCH_1):PAGE200',
 PHYS_PAGE='211',
 XY='(9975,7825)',
 ROT='0',
 VER='1',
 PACK_TYPE='0402',
 CDS_LIB='pure_quanta',
 CDS_PART_NAME='Q_CAP_0402-0.1UF,25V,10%,X7R,CA',
 TOLERANCE='10%',
 MATERIAL='X7R',
 VOLTAGE='25V',
 VALUE='0.1UF',
 PRIM_FILE='./archive_libs/logical/q_cap/chips/chips.prt';

PART_NAME
 C2340 'Q_CAP_0402-1000PF,50V,5%,EMPTYA':;

SECTION_NUMBER 1
 '@S9S_MB_2U_LIB.S9S_MB_2U(SCH_1):PAGE139_I52@PURE_QUANTA.Q_CAP(CHIPS)':
 C_PATH='@s9s_mb_2u_lib.s9s_mb_2u(sch_1):page139_i52@pure_quanta.q_cap(chips)',
 P_PATH='@s9s_mb_2u_lib.s9s_mb_2u(sch_1):page145_i52@pure_quanta.q_cap(chips)',
 PATH='I52',
 DRAWING='@S9S_MB_2U_LIB.S9S_MB_2U(SCH_1):PAGE139',
 PHYS_PAGE='145',
 XY='(1100,775)',
 ROT='0',
 VER='1',
 PACK_TYPE='0402',
 CDS_LIB='pure_quanta',
 CDS_PART_NAME='Q_CAP_0402-1000PF,50V,5%,EMPTYA',
 TOLERANCE='5%',
 MATERIAL='EMPTY',
 VOLTAGE='50V',
 VALUE='1000PF',
 PRIM_FILE='./archive_libs/logical/q_cap/chips/chips.prt';

PART_NAME
 C2341 'Q_CAP_0402-0.1UF,25V,10%,X7R,CA':;

SECTION_NUMBER 1
 '@S9S_MB_2U_LIB.S9S_MB_2U(SCH_1):PAGE139_I93@PURE_QUANTA.Q_CAP(CHIPS)':
 C_PATH='@s9s_mb_2u_lib.s9s_mb_2u(sch_1):page139_i93@pure_quanta.q_cap(chips)',
 P_PATH='@s9s_mb_2u_lib.s9s_mb_2u(sch_1):page145_i93@pure_quanta.q_cap(chips)',
 PATH='I93',
 DRAWING='@S9S_MB_2U_LIB.S9S_MB_2U(SCH_1):PAGE139',
 PHYS_PAGE='145',
 XY='(4100,5425)',
 ROT='0',
 VER='1',
 PACK_TYPE='0402',
 CDS_LIB='pure_quanta',
 CDS_PART_NAME='Q_CAP_0402-0.1UF,25V,10%,X7R,CA',
 TOLERANCE='10%',
 MATERIAL='X7R',
 VOLTAGE='25V',
 VALUE='0.1UF',
 PRIM_FILE='./archive_libs/logical/q_cap/chips/chips.prt';

PART_NAME
 C2342 'Q_CAP_0402-1000PF,50V,5%,EMPTYA':;

SECTION_NUMBER 1
 '@S9S_MB_2U_LIB.S9S_MB_2U(SCH_1):PAGE230_I62@PURE_QUANTA.Q_CAP(CHIPS)':
 C_PATH='@s9s_mb_2u_lib.s9s_mb_2u(sch_1):page230_i62@pure_quanta.q_cap(chips)',
 P_PATH='@s9s_mb_2u_lib.s9s_mb_2u(sch_1):page246_i62@pure_quanta.q_cap(chips)',
 PATH='I62',
 DRAWING='@S9S_MB_2U_LIB.S9S_MB_2U(SCH_1):PAGE230',
 PHYS_PAGE='246',
 XY='(1975,-1775)',
 ROT='0',
 VER='1',
 PACK_TYPE='0402',
 CDS_LIB='pure_quanta',
 CDS_PART_NAME='Q_CAP_0402-1000PF,50V,5%,EMPTYA',
 TOLERANCE='5%',
 MATERIAL='EMPTY',
 VOLTAGE='50V',
 VALUE='1000PF',
 PRIM_FILE='./archive_libs/logical/q_cap/chips/chips.prt';

PART_NAME
 C2343 'Q_CAP_0402-1000PF,50V,5%,EMPTYA':;

SECTION_NUMBER 1
 '@S9S_MB_2U_LIB.S9S_MB_2U(SCH_1):PAGE143_I118@PURE_QUANTA.Q_CAP(CHIPS)':
 C_PATH='@s9s_mb_2u_lib.s9s_mb_2u(sch_1):page143_i118@pure_quanta.q_cap(chips)',
 P_PATH='@s9s_mb_2u_lib.s9s_mb_2u(sch_1):page146_i118@pure_quanta.q_cap(chips)',
 PATH='I118',
 DRAWING='@S9S_MB_2U_LIB.S9S_MB_2U(SCH_1):PAGE143',
 PHYS_PAGE='146',
 XY='(5425,-250)',
 ROT='0',
 VER='1',
 PACK_TYPE='0402',
 CDS_LIB='pure_quanta',
 CDS_PART_NAME='Q_CAP_0402-1000PF,50V,5%,EMPTYA',
 TOLERANCE='5%',
 MATERIAL='EMPTY',
 VOLTAGE='50V',
 VALUE='1000PF',
 PRIM_FILE='./archive_libs/logical/q_cap/chips/chips.prt';

PART_NAME
 C2344 'Q_CAP_0402-0.1UF,25V,10%,X7R,CA':;

SECTION_NUMBER 1
 '@S9S_MB_2U_LIB.S9S_MB_2U(SCH_1):PAGE152_I87@PURE_QUANTA.Q_CAP(CHIPS)':
 C_PATH='@s9s_mb_2u_lib.s9s_mb_2u(sch_1):page152_i87@pure_quanta.q_cap(chips)',
 P_PATH='@s9s_mb_2u_lib.s9s_mb_2u(sch_1):page155_i87@pure_quanta.q_cap(chips)',
 PATH='I87',
 DRAWING='@S9S_MB_2U_LIB.S9S_MB_2U(SCH_1):PAGE152',
 PHYS_PAGE='155',
 XY='(-2700,3400)',
 ROT='0',
 VER='1',
 PACK_TYPE='0402',
 CDS_LIB='pure_quanta',
 CDS_PART_NAME='Q_CAP_0402-0.1UF,25V,10%,X7R,CA',
 TOLERANCE='10%',
 MATERIAL='X7R',
 VOLTAGE='25V',
 VALUE='0.1UF',
 PRIM_FILE='./archive_libs/logical/q_cap/chips/chips.prt';

PART_NAME
 C2345 'Q_CAP_0402-0.1UF,25V,10%,X7R,CA':;

SECTION_NUMBER 1
 '@S9S_MB_2U_LIB.S9S_MB_2U(SCH_1):PAGE156_I81@PURE_QUANTA.Q_CAP(CHIPS)':
 C_PATH='@s9s_mb_2u_lib.s9s_mb_2u(sch_1):page156_i81@pure_quanta.q_cap(chips)',
 P_PATH='@s9s_mb_2u_lib.s9s_mb_2u(sch_1):page161_i81@pure_quanta.q_cap(chips)',
 PATH='I81',
 DRAWING='@S9S_MB_2U_LIB.S9S_MB_2U(SCH_1):PAGE156',
 PHYS_PAGE='161',
 XY='(10825,-3200)',
 ROT='0',
 VER='1',
 PACK_TYPE='0402',
 CDS_LIB='pure_quanta',
 CDS_PART_NAME='Q_CAP_0402-0.1UF,25V,10%,X7R,CA',
 TOLERANCE='10%',
 MATERIAL='X7R',
 VOLTAGE='25V',
 VALUE='0.1UF',
 PRIM_FILE='./archive_libs/logical/q_cap/chips/chips.prt';

PART_NAME
 C2346 'Q_CAP_0402-0.1UF,25V,10%,X7R,CA':;

SECTION_NUMBER 1
 '@S9S_MB_2U_LIB.S9S_MB_2U(SCH_1):PAGE154_I223@PURE_QUANTA.Q_CAP(CHIPS)':
 C_PATH='@s9s_mb_2u_lib.s9s_mb_2u(sch_1):page154_i223@pure_quanta.q_cap(chips)',
 P_PATH='@s9s_mb_2u_lib.s9s_mb_2u(sch_1):page158_i223@pure_quanta.q_cap(chips)',
 PATH='I223',
 DRAWING='@S9S_MB_2U_LIB.S9S_MB_2U(SCH_1):PAGE154',
 PHYS_PAGE='158',
 XY='(425,7625)',
 ROT='0',
 VER='1',
 PACK_TYPE='0402',
 CDS_LIB='pure_quanta',
 CDS_PART_NAME='Q_CAP_0402-0.1UF,25V,10%,X7R,CA',
 TOLERANCE='10%',
 MATERIAL='X7R',
 VOLTAGE='25V',
 VALUE='0.1UF',
 PRIM_FILE='./archive_libs/logical/q_cap/chips/chips.prt';

PART_NAME
 C2347 'Q_CAP_0402-0.1UF,25V,10%,X7R,CA':;

SECTION_NUMBER 1
 '@S9S_MB_2U_LIB.S9S_MB_2U(SCH_1):PAGE132_I90@PURE_QUANTA.Q_CAP(CHIPS)':
 C_PATH='@s9s_mb_2u_lib.s9s_mb_2u(sch_1):page132_i90@pure_quanta.q_cap(chips)',
 P_PATH='@s9s_mb_2u_lib.s9s_mb_2u(sch_1):page164_i90@pure_quanta.q_cap(chips)',
 PATH='I90',
 DRAWING='@S9S_MB_2U_LIB.S9S_MB_2U(SCH_1):PAGE132',
 PHYS_PAGE='164',
 XY='(100,1500)',
 ROT='0',
 VER='1',
 PACK_TYPE='0402',
 CDS_LIB='pure_quanta',
 CDS_PART_NAME='Q_CAP_0402-0.1UF,25V,10%,X7R,CA',
 TOLERANCE='10%',
 MATERIAL='X7R',
 VOLTAGE='25V',
 VALUE='0.1UF',
 PRIM_FILE='./archive_libs/logical/q_cap/chips/chips.prt';

PART_NAME
 C2348 'Q_CAP_0402-0.1UF,25V,10%,X7R,CA':;

SECTION_NUMBER 1
 '@S9S_MB_2U_LIB.S9S_MB_2U(SCH_1):PAGE235_I23@PURE_QUANTA.Q_CAP(CHIPS)':
 C_PATH='@s9s_mb_2u_lib.s9s_mb_2u(sch_1):page235_i23@pure_quanta.q_cap(chips)',
 P_PATH='@s9s_mb_2u_lib.s9s_mb_2u(sch_1):page248_i23@pure_quanta.q_cap(chips)',
 PATH='I23',
 DRAWING='@S9S_MB_2U_LIB.S9S_MB_2U(SCH_1):PAGE235',
 PHYS_PAGE='248',
 XY='(2225,7075)',
 ROT='0',
 VER='1',
 PACK_TYPE='0402',
 CDS_LIB='pure_quanta',
 CDS_PART_NAME='Q_CAP_0402-0.1UF,25V,10%,X7R,CA',
 TOLERANCE='10%',
 MATERIAL='X7R',
 VOLTAGE='25V',
 VALUE='0.1UF',
 PRIM_FILE='./archive_libs/logical/q_cap/chips/chips.prt';

PART_NAME
 C2349 'Q_CAP_DIFFBUS_C0402-DIFF BUS_0A':;

SECTION_NUMBER 1
 '@S9S_MB_2U_LIB.S9S_MB_2U(SCH_1):PAGE162_I26@PURE_QUANTA.Q_CAP_DIFFBUS(CHIPS)':
 C_PATH='@s9s_mb_2u_lib.s9s_mb_2u(sch_1):page162_i26@pure_quanta.q_cap_diffbus(c~
hips)',
 P_PATH='@s9s_mb_2u_lib.s9s_mb_2u(sch_1):page169_i26@pure_quanta.q_cap_diffbus(c~
hips)',
 PATH='I26',
 DRAWING='@S9S_MB_2U_LIB.S9S_MB_2U(SCH_1):PAGE162',
 PIN_NAMES_ROTATE='True',
 PHYS_PAGE='169',
 XY='(-3725,3225)',
 ROT='0',
 VER='2',
 PACK_TYPE='C0402',
 LOCATION='C2349',
 CDS_LIB='pure_quanta',
 CDS_PART_NAME='Q_CAP_DIFFBUS_C0402-DIFF BUS_0A',
 TOLERANCE='10%',
 MATERIAL='X6S',
 VOLTAGE='6.3V',
 VALUE='DIFF BUS_0.33UF',
 PRIM_FILE='./archive_libs/logical/q_cap_diffbus/chips/chips.prt';

PART_NAME
 C2350 'Q_CAP_DIFFBUS_C0402-DIFF BUS_0A':;

SECTION_NUMBER 1
 '@S9S_MB_2U_LIB.S9S_MB_2U(SCH_1):PAGE162_I25@PURE_QUANTA.Q_CAP_DIFFBUS(CHIPS)':
 C_PATH='@s9s_mb_2u_lib.s9s_mb_2u(sch_1):page162_i25@pure_quanta.q_cap_diffbus(c~
hips)',
 P_PATH='@s9s_mb_2u_lib.s9s_mb_2u(sch_1):page169_i25@pure_quanta.q_cap_diffbus(c~
hips)',
 PATH='I25',
 DRAWING='@S9S_MB_2U_LIB.S9S_MB_2U(SCH_1):PAGE162',
 PIN_NAMES_ROTATE='True',
 PHYS_PAGE='169',
 XY='(-3725,3175)',
 ROT='0',
 VER='2',
 PACK_TYPE='C0402',
 LOCATION='C2350',
 CDS_LIB='pure_quanta',
 CDS_PART_NAME='Q_CAP_DIFFBUS_C0402-DIFF BUS_0A',
 TOLERANCE='10%',
 MATERIAL='X6S',
 VOLTAGE='6.3V',
 VALUE='DIFF BUS_0.33UF',
 PRIM_FILE='./archive_libs/logical/q_cap_diffbus/chips/chips.prt';

PART_NAME
 C2351 'Q_CAP_0402-0.1UF,25V,10%,EMPTYA':
 ROOM='PCIE REDRIVER1_BOM2';

SECTION_NUMBER 1
 '@S9S_MB_2U_LIB.S9S_MB_2U(SCH_1):PAGE159_I31@PURE_QUANTA.Q_CAP(CHIPS)':
 C_PATH='@s9s_mb_2u_lib.s9s_mb_2u(sch_1):page159_i31@pure_quanta.q_cap(chips)',
 P_PATH='@s9s_mb_2u_lib.s9s_mb_2u(sch_1):page167_i31@pure_quanta.q_cap(chips)',
 PATH='I31',
 DRAWING='@S9S_MB_2U_LIB.S9S_MB_2U(SCH_1):PAGE159',
 PHYS_PAGE='167',
 XY='(-2825,650)',
 ROT='0',
 VER='2',
 PACK_TYPE='0402',
 CDS_LIB='pure_quanta',
 CDS_PART_NAME='Q_CAP_0402-0.1UF,25V,10%,EMPTYA',
 TOLERANCE='10%',
 MATERIAL='EMPTY',
 VOLTAGE='25V',
 ROOM='PCIE REDRIVER1_BOM2',
 VALUE='0.1UF',
 PRIM_FILE='./archive_libs/logical/q_cap/chips/chips.prt';

PART_NAME
 C2352 'Q_CAP_0402-0.1UF,25V,10%,EMPTYA':
 ROOM='PCIE REDRIVER1_BOM2';

SECTION_NUMBER 1
 '@S9S_MB_2U_LIB.S9S_MB_2U(SCH_1):PAGE159_I32@PURE_QUANTA.Q_CAP(CHIPS)':
 C_PATH='@s9s_mb_2u_lib.s9s_mb_2u(sch_1):page159_i32@pure_quanta.q_cap(chips)',
 P_PATH='@s9s_mb_2u_lib.s9s_mb_2u(sch_1):page167_i32@pure_quanta.q_cap(chips)',
 PATH='I32',
 DRAWING='@S9S_MB_2U_LIB.S9S_MB_2U(SCH_1):PAGE159',
 PHYS_PAGE='167',
 XY='(-2825,600)',
 ROT='0',
 VER='2',
 PACK_TYPE='0402',
 CDS_LIB='pure_quanta',
 CDS_PART_NAME='Q_CAP_0402-0.1UF,25V,10%,EMPTYA',
 TOLERANCE='10%',
 MATERIAL='EMPTY',
 VOLTAGE='25V',
 ROOM='PCIE REDRIVER1_BOM2',
 VALUE='0.1UF',
 PRIM_FILE='./archive_libs/logical/q_cap/chips/chips.prt';

PART_NAME
 C2353 'Q_CAP_0402-0.1UF,25V,10%,EMPTYA':
 ROOM='PCIE REDRIVER1_BOM2';

SECTION_NUMBER 1
 '@S9S_MB_2U_LIB.S9S_MB_2U(SCH_1):PAGE159_I27@PURE_QUANTA.Q_CAP(CHIPS)':
 C_PATH='@s9s_mb_2u_lib.s9s_mb_2u(sch_1):page159_i27@pure_quanta.q_cap(chips)',
 P_PATH='@s9s_mb_2u_lib.s9s_mb_2u(sch_1):page167_i27@pure_quanta.q_cap(chips)',
 PATH='I27',
 DRAWING='@S9S_MB_2U_LIB.S9S_MB_2U(SCH_1):PAGE159',
 PHYS_PAGE='167',
 XY='(-2825,25)',
 ROT='0',
 VER='2',
 PACK_TYPE='0402',
 CDS_LIB='pure_quanta',
 CDS_PART_NAME='Q_CAP_0402-0.1UF,25V,10%,EMPTYA',
 TOLERANCE='10%',
 MATERIAL='EMPTY',
 VOLTAGE='25V',
 ROOM='PCIE REDRIVER1_BOM2',
 VALUE='0.1UF',
 PRIM_FILE='./archive_libs/logical/q_cap/chips/chips.prt';

PART_NAME
 C2354 'Q_CAP_0402-0.1UF,25V,10%,EMPTYA':
 ROOM='PCIE REDRIVER1_BOM2';

SECTION_NUMBER 1
 '@S9S_MB_2U_LIB.S9S_MB_2U(SCH_1):PAGE159_I28@PURE_QUANTA.Q_CAP(CHIPS)':
 C_PATH='@s9s_mb_2u_lib.s9s_mb_2u(sch_1):page159_i28@pure_quanta.q_cap(chips)',
 P_PATH='@s9s_mb_2u_lib.s9s_mb_2u(sch_1):page167_i28@pure_quanta.q_cap(chips)',
 PATH='I28',
 DRAWING='@S9S_MB_2U_LIB.S9S_MB_2U(SCH_1):PAGE159',
 PHYS_PAGE='167',
 XY='(-2825,-25)',
 ROT='0',
 VER='2',
 PACK_TYPE='0402',
 CDS_LIB='pure_quanta',
 CDS_PART_NAME='Q_CAP_0402-0.1UF,25V,10%,EMPTYA',
 TOLERANCE='10%',
 MATERIAL='EMPTY',
 VOLTAGE='25V',
 ROOM='PCIE REDRIVER1_BOM2',
 VALUE='0.1UF',
 PRIM_FILE='./archive_libs/logical/q_cap/chips/chips.prt';

PART_NAME
 C2355 'Q_CAP_C0402-1UF,25V,10%,X6S,CHA':
 ROOM='PCIE REDRIVER1_BOM2';

SECTION_NUMBER 1
 '@S9S_MB_2U_LIB.S9S_MB_2U(SCH_1):PAGE159_I96@PURE_QUANTA.Q_CAP(CHIPS)':
 C_PATH='@s9s_mb_2u_lib.s9s_mb_2u(sch_1):page159_i96@pure_quanta.q_cap(chips)',
 P_PATH='@s9s_mb_2u_lib.s9s_mb_2u(sch_1):page167_i96@pure_quanta.q_cap(chips)',
 PATH='I96',
 DRAWING='@S9S_MB_2U_LIB.S9S_MB_2U(SCH_1):PAGE159',
 PHYS_PAGE='167',
 XY='(0,2175)',
 ROT='2',
 VER='1',
 PACK_TYPE='C0402',
 CDS_LIB='pure_quanta',
 CDS_PART_NAME='Q_CAP_C0402-1UF,25V,10%,X6S,CHA',
 TOLERANCE='10%',
 MATERIAL='X6S',
 VOLTAGE='25V',
 ROOM='PCIE REDRIVER1_BOM2',
 VALUE='1UF',
 PRIM_FILE='./archive_libs/logical/q_cap/chips/chips.prt';

PART_NAME
 C2356 'Q_CAP_C0805-10UF,16V,10%,X6S,CA':
 ROOM='PCIE REDRIVER1_BOM2';

SECTION_NUMBER 1
 '@S9S_MB_2U_LIB.S9S_MB_2U(SCH_1):PAGE159_I98@PURE_QUANTA.Q_CAP(CHIPS)':
 C_PATH='@s9s_mb_2u_lib.s9s_mb_2u(sch_1):page159_i98@pure_quanta.q_cap(chips)',
 P_PATH='@s9s_mb_2u_lib.s9s_mb_2u(sch_1):page167_i98@pure_quanta.q_cap(chips)',
 PATH='I98',
 DRAWING='@S9S_MB_2U_LIB.S9S_MB_2U(SCH_1):PAGE159',
 BOM_COST='VR_SYSTEM ',
 PHYS_PAGE='167',
 XY='(325,2175)',
 ROT='2',
 VER='1',
 PACK_TYPE='C0805',
 CDS_LIB='pure_quanta',
 CDS_PART_NAME='Q_CAP_C0805-10UF,16V,10%,X6S,CA',
 TOLERANCE='10%',
 MATERIAL='X6S',
 VOLTAGE='16V',
 ROOM='PCIE REDRIVER1_BOM2',
 VALUE='10UF',
 PRIM_FILE='./archive_libs/logical/q_cap/chips/chips.prt';

PART_NAME
 C2357 'Q_CAP_0402-0.1UF,25V,10%,X7R,CA':
 ROOM='PCIE REDRIVER1_BOM2';

SECTION_NUMBER 1
 '@S9S_MB_2U_LIB.S9S_MB_2U(SCH_1):PAGE159_I99@PURE_QUANTA.Q_CAP(CHIPS)':
 C_PATH='@s9s_mb_2u_lib.s9s_mb_2u(sch_1):page159_i99@pure_quanta.q_cap(chips)',
 P_PATH='@s9s_mb_2u_lib.s9s_mb_2u(sch_1):page167_i99@pure_quanta.q_cap(chips)',
 PATH='I99',
 DRAWING='@S9S_MB_2U_LIB.S9S_MB_2U(SCH_1):PAGE159',
 PHYS_PAGE='167',
 XY='(625,2175)',
 ROT='0',
 VER='1',
 PACK_TYPE='0402',
 CDS_LIB='pure_quanta',
 CDS_PART_NAME='Q_CAP_0402-0.1UF,25V,10%,X7R,CA',
 TOLERANCE='10%',
 MATERIAL='X7R',
 VOLTAGE='25V',
 ROOM='PCIE REDRIVER1_BOM2',
 VALUE='0.1UF',
 PRIM_FILE='./archive_libs/logical/q_cap/chips/chips.prt';

PART_NAME
 C2358 'Q_CAP_0402-0.1UF,25V,10%,X7R,CA':
 ROOM='PCIE REDRIVER1_BOM2';

SECTION_NUMBER 1
 '@S9S_MB_2U_LIB.S9S_MB_2U(SCH_1):PAGE159_I100@PURE_QUANTA.Q_CAP(CHIPS)':
 C_PATH='@s9s_mb_2u_lib.s9s_mb_2u(sch_1):page159_i100@pure_quanta.q_cap(chips)',
 P_PATH='@s9s_mb_2u_lib.s9s_mb_2u(sch_1):page167_i100@pure_quanta.q_cap(chips)',
 PATH='I100',
 DRAWING='@S9S_MB_2U_LIB.S9S_MB_2U(SCH_1):PAGE159',
 PHYS_PAGE='167',
 XY='(850,2175)',
 ROT='0',
 VER='1',
 PACK_TYPE='0402',
 CDS_LIB='pure_quanta',
 CDS_PART_NAME='Q_CAP_0402-0.1UF,25V,10%,X7R,CA',
 TOLERANCE='10%',
 MATERIAL='X7R',
 VOLTAGE='25V',
 ROOM='PCIE REDRIVER1_BOM2',
 VALUE='0.1UF',
 PRIM_FILE='./archive_libs/logical/q_cap/chips/chips.prt';

PART_NAME
 C2359 'Q_CAP_C0402-0.22UF,25V,10%,X7RA':;

SECTION_NUMBER 1
 '@S9S_MB_2U_LIB.S9S_MB_2U(SCH_1):PAGE246_I94@PURE_QUANTA.Q_CAP(CHIPS)':
 C_PATH='@s9s_mb_2u_lib.s9s_mb_2u(sch_1):page246_i94@pure_quanta.q_cap(chips)',
 P_PATH='@s9s_mb_2u_lib.s9s_mb_2u(sch_1):page260_i94@pure_quanta.q_cap(chips)',
 PATH='I94',
 DRAWING='@S9S_MB_2U_LIB.S9S_MB_2U(SCH_1):PAGE246',
 PHYS_PAGE='260',
 XY='(175,4075)',
 ROT='0',
 VER='1',
 PACK_TYPE='C0402',
 CDS_LIB='pure_quanta',
 CDS_PART_NAME='Q_CAP_C0402-0.22UF,25V,10%,X7RA',
 TOLERANCE='10%',
 MATERIAL='X7R',
 VOLTAGE='25V',
 VALUE='0.22UF',
 PRIM_FILE='./archive_libs/logical/q_cap/chips/chips.prt';

PART_NAME
 C2360 'Q_CAP_0402-0.1UF,25V,10%,X7R,CA':;

SECTION_NUMBER 1
 '@S9S_MB_2U_LIB.S9S_MB_2U(SCH_1):PAGE246_I107@PURE_QUANTA.Q_CAP(CHIPS)':
 C_PATH='@s9s_mb_2u_lib.s9s_mb_2u(sch_1):page246_i107@pure_quanta.q_cap(chips)',
 P_PATH='@s9s_mb_2u_lib.s9s_mb_2u(sch_1):page260_i107@pure_quanta.q_cap(chips)',
 PATH='I107',
 DRAWING='@S9S_MB_2U_LIB.S9S_MB_2U(SCH_1):PAGE246',
 PHYS_PAGE='260',
 XY='(-7200,3000)',
 ROT='2',
 VER='1',
 PACK_TYPE='0402',
 CDS_LIB='pure_quanta',
 CDS_PART_NAME='Q_CAP_0402-0.1UF,25V,10%,X7R,CA',
 TOLERANCE='10%',
 MATERIAL='X7R',
 VOLTAGE='25V',
 VALUE='0.1UF',
 PRIM_FILE='./archive_libs/logical/q_cap/chips/chips.prt';

PART_NAME
 C2363 'Q_CAP_0402-0.1UF,25V,10%,EMPTYA':
 ROOM='HSC1_BOM2';

SECTION_NUMBER 1
 '@S9S_MB_2U_LIB.S9S_MB_2U(SCH_1):PAGE240_I15@PURE_QUANTA.Q_CAP(CHIPS)':
 C_PATH='@s9s_mb_2u_lib.s9s_mb_2u(sch_1):page240_i15@pure_quanta.q_cap(chips)',
 P_PATH='@s9s_mb_2u_lib.s9s_mb_2u(sch_1):page251_i15@pure_quanta.q_cap(chips)',
 PATH='I15',
 DRAWING='@S9S_MB_2U_LIB.S9S_MB_2U(SCH_1):PAGE240',
 PHYS_PAGE='251',
 XY='(-1275,-225)',
 ROT='0',
 VER='1',
 PACK_TYPE='0402',
 CDS_LIB='pure_quanta',
 CDS_PART_NAME='Q_CAP_0402-0.1UF,25V,10%,EMPTYA',
 TOLERANCE='10%',
 MATERIAL='EMPTY',
 VOLTAGE='25V',
 ROOM='HSC1_BOM2',
 VALUE='0.1UF',
 PRIM_FILE='./archive_libs/logical/q_cap/chips/chips.prt';

PART_NAME
 C2364 'Q_CAP_0402-0.1UF,25V,10%,EMPTYA':
 ROOM='HSC1_BOM2';

SECTION_NUMBER 1
 '@S9S_MB_2U_LIB.S9S_MB_2U(SCH_1):PAGE240_I33@PURE_QUANTA.Q_CAP(CHIPS)':
 C_PATH='@s9s_mb_2u_lib.s9s_mb_2u(sch_1):page240_i33@pure_quanta.q_cap(chips)',
 P_PATH='@s9s_mb_2u_lib.s9s_mb_2u(sch_1):page251_i33@pure_quanta.q_cap(chips)',
 PATH='I33',
 DRAWING='@S9S_MB_2U_LIB.S9S_MB_2U(SCH_1):PAGE240',
 PHYS_PAGE='251',
 XY='(-700,800)',
 ROT='0',
 VER='1',
 PACK_TYPE='0402',
 CDS_LIB='pure_quanta',
 CDS_PART_NAME='Q_CAP_0402-0.1UF,25V,10%,EMPTYA',
 TOLERANCE='10%',
 MATERIAL='EMPTY',
 VOLTAGE='25V',
 ROOM='HSC1_BOM2',
 VALUE='0.1UF',
 PRIM_FILE='./archive_libs/logical/q_cap/chips/chips.prt';

PART_NAME
 C2369 'Q_CAP_C0402-1UF,25V,10%,EMPTY,A':;

SECTION_NUMBER 1
 '@S9S_MB_2U_LIB.S9S_MB_2U(SCH_1):PAGE213_I42@PURE_QUANTA.Q_CAP(CHIPS)':
 C_PATH='@s9s_mb_2u_lib.s9s_mb_2u(sch_1):page213_i42@pure_quanta.q_cap(chips)',
 P_PATH='@s9s_mb_2u_lib.s9s_mb_2u(sch_1):page224_i42@pure_quanta.q_cap(chips)',
 PATH='I42',
 DRAWING='@S9S_MB_2U_LIB.S9S_MB_2U(SCH_1):PAGE213',
 PHYS_PAGE='224',
 XY='(-8825,850)',
 ROT='2',
 VER='1',
 PACK_TYPE='C0402',
 CDS_LIB='pure_quanta',
 CDS_PART_NAME='Q_CAP_C0402-1UF,25V,10%,EMPTY,A',
 TOLERANCE='10%',
 MATERIAL='EMPTY',
 VOLTAGE='25V',
 VALUE='1UF',
 PRIM_FILE='./archive_libs/logical/q_cap/chips/chips.prt';

PART_NAME
 C2370 'Q_CAP_0402-0.1UF,25V,10%,EMPTYA':;

SECTION_NUMBER 1
 '@S9S_MB_2U_LIB.S9S_MB_2U(SCH_1):PAGE213_I35@PURE_QUANTA.Q_CAP(CHIPS)':
 C_PATH='@s9s_mb_2u_lib.s9s_mb_2u(sch_1):page213_i35@pure_quanta.q_cap(chips)',
 P_PATH='@s9s_mb_2u_lib.s9s_mb_2u(sch_1):page224_i35@pure_quanta.q_cap(chips)',
 PATH='I35',
 DRAWING='@S9S_MB_2U_LIB.S9S_MB_2U(SCH_1):PAGE213',
 PHYS_PAGE='224',
 XY='(-6700,1375)',
 ROT='0',
 VER='1',
 PACK_TYPE='0402',
 CDS_LIB='pure_quanta',
 CDS_PART_NAME='Q_CAP_0402-0.1UF,25V,10%,EMPTYA',
 TOLERANCE='10%',
 MATERIAL='EMPTY',
 VOLTAGE='25V',
 VALUE='0.1UF',
 PRIM_FILE='./archive_libs/logical/q_cap/chips/chips.prt';

PART_NAME
 C2371 'Q_CAP_0402-0.1UF,25V,10%,EMPTYA':;

SECTION_NUMBER 1
 '@S9S_MB_2U_LIB.S9S_MB_2U(SCH_1):PAGE233_I51@PURE_QUANTA.Q_CAP(CHIPS)':
 C_PATH='@s9s_mb_2u_lib.s9s_mb_2u(sch_1):page233_i51@pure_quanta.q_cap(chips)',
 P_PATH='@s9s_mb_2u_lib.s9s_mb_2u(sch_1):page245_i51@pure_quanta.q_cap(chips)',
 PATH='I51',
 DRAWING='@S9S_MB_2U_LIB.S9S_MB_2U(SCH_1):PAGE233',
 PHYS_PAGE='245',
 XY='(750,550)',
 ROT='0',
 VER='2',
 PACK_TYPE='0402',
 CDS_LIB='pure_quanta',
 CDS_PART_NAME='Q_CAP_0402-0.1UF,25V,10%,EMPTYA',
 TOLERANCE='10%',
 MATERIAL='EMPTY',
 VOLTAGE='25V',
 VALUE='0.1UF',
 PRIM_FILE='./archive_libs/logical/q_cap/chips/chips.prt';

PART_NAME
 C2372 'Q_CAP_0402-1000PF,50V,5%,EMPTYA':;

SECTION_NUMBER 1
 '@S9S_MB_2U_LIB.S9S_MB_2U(SCH_1):PAGE147_I15@PURE_QUANTA.Q_CAP(CHIPS)':
 C_PATH='@s9s_mb_2u_lib.s9s_mb_2u(sch_1):page147_i15@pure_quanta.q_cap(chips)',
 P_PATH='@s9s_mb_2u_lib.s9s_mb_2u(sch_1):page144_i15@pure_quanta.q_cap(chips)',
 PATH='I15',
 DRAWING='@S9S_MB_2U_LIB.S9S_MB_2U(SCH_1):PAGE147',
 PHYS_PAGE='144',
 XY='(-3625,8200)',
 ROT='0',
 VER='1',
 PACK_TYPE='0402',
 CDS_LIB='pure_quanta',
 CDS_PART_NAME='Q_CAP_0402-1000PF,50V,5%,EMPTYA',
 TOLERANCE='5%',
 MATERIAL='EMPTY',
 VOLTAGE='50V',
 VALUE='1000PF',
 PRIM_FILE='./archive_libs/logical/q_cap/chips/chips.prt';

PART_NAME
 C2373 'Q_CAP_0402-1000PF,50V,5%,EMPTYA':;

SECTION_NUMBER 1
 '@S9S_MB_2U_LIB.S9S_MB_2U(SCH_1):PAGE147_I22@PURE_QUANTA.Q_CAP(CHIPS)':
 C_PATH='@s9s_mb_2u_lib.s9s_mb_2u(sch_1):page147_i22@pure_quanta.q_cap(chips)',
 P_PATH='@s9s_mb_2u_lib.s9s_mb_2u(sch_1):page144_i22@pure_quanta.q_cap(chips)',
 PATH='I22',
 DRAWING='@S9S_MB_2U_LIB.S9S_MB_2U(SCH_1):PAGE147',
 PHYS_PAGE='144',
 XY='(-3500,6675)',
 ROT='0',
 VER='1',
 PACK_TYPE='0402',
 CDS_LIB='pure_quanta',
 CDS_PART_NAME='Q_CAP_0402-1000PF,50V,5%,EMPTYA',
 TOLERANCE='5%',
 MATERIAL='EMPTY',
 VOLTAGE='50V',
 VALUE='1000PF',
 PRIM_FILE='./archive_libs/logical/q_cap/chips/chips.prt';

PART_NAME
 C2374 'Q_CAP_0402-1000PF,50V,5%,EMPTYA':;

SECTION_NUMBER 1
 '@S9S_MB_2U_LIB.S9S_MB_2U(SCH_1):PAGE147_I47@PURE_QUANTA.Q_CAP(CHIPS)':
 C_PATH='@s9s_mb_2u_lib.s9s_mb_2u(sch_1):page147_i47@pure_quanta.q_cap(chips)',
 P_PATH='@s9s_mb_2u_lib.s9s_mb_2u(sch_1):page144_i47@pure_quanta.q_cap(chips)',
 PATH='I47',
 DRAWING='@S9S_MB_2U_LIB.S9S_MB_2U(SCH_1):PAGE147',
 PHYS_PAGE='144',
 XY='(-3275,5025)',
 ROT='0',
 VER='1',
 PACK_TYPE='0402',
 CDS_LIB='pure_quanta',
 CDS_PART_NAME='Q_CAP_0402-1000PF,50V,5%,EMPTYA',
 TOLERANCE='5%',
 MATERIAL='EMPTY',
 VOLTAGE='50V',
 VALUE='1000PF',
 PRIM_FILE='./archive_libs/logical/q_cap/chips/chips.prt';

PART_NAME
 C2376 'Q_CAP_0402-0.1UF,25V,10%,X7R,CA':;

SECTION_NUMBER 1
 '@S9S_MB_2U_LIB.S9S_MB_2U(SCH_1):PAGE154_I241@PURE_QUANTA.Q_CAP(CHIPS)':
 C_PATH='@s9s_mb_2u_lib.s9s_mb_2u(sch_1):page154_i241@pure_quanta.q_cap(chips)',
 P_PATH='@s9s_mb_2u_lib.s9s_mb_2u(sch_1):page158_i241@pure_quanta.q_cap(chips)',
 PATH='I241',
 DRAWING='@S9S_MB_2U_LIB.S9S_MB_2U(SCH_1):PAGE154',
 PHYS_PAGE='158',
 XY='(1475,6000)',
 ROT='0',
 VER='1',
 PACK_TYPE='0402',
 CDS_LIB='pure_quanta',
 CDS_PART_NAME='Q_CAP_0402-0.1UF,25V,10%,X7R,CA',
 TOLERANCE='10%',
 MATERIAL='X7R',
 VOLTAGE='25V',
 VALUE='0.1UF',
 PRIM_FILE='./archive_libs/logical/q_cap/chips/chips.prt';

PART_NAME
 C2377 'Q_CAP_0402-0.1UF,25V,10%,X7R,CA':;

SECTION_NUMBER 1
 '@S9S_MB_2U_LIB.S9S_MB_2U(SCH_1):PAGE132_I110@PURE_QUANTA.Q_CAP(CHIPS)':
 C_PATH='@s9s_mb_2u_lib.s9s_mb_2u(sch_1):page132_i110@pure_quanta.q_cap(chips)',
 P_PATH='@s9s_mb_2u_lib.s9s_mb_2u(sch_1):page164_i110@pure_quanta.q_cap(chips)',
 PATH='I110',
 DRAWING='@S9S_MB_2U_LIB.S9S_MB_2U(SCH_1):PAGE132',
 PHYS_PAGE='164',
 XY='(1550,-200)',
 ROT='0',
 VER='1',
 PACK_TYPE='0402',
 CDS_LIB='pure_quanta',
 CDS_PART_NAME='Q_CAP_0402-0.1UF,25V,10%,X7R,CA',
 TOLERANCE='10%',
 MATERIAL='X7R',
 VOLTAGE='25V',
 VALUE='0.1UF',
 PRIM_FILE='./archive_libs/logical/q_cap/chips/chips.prt';

PART_NAME
 C2378 'Q_CAP_0402-0.1UF,25V,10%,X7R,CA':;

SECTION_NUMBER 1
 '@S9S_MB_2U_LIB.S9S_MB_2U(SCH_1):PAGE297_I327@PURE_QUANTA.Q_CAP(CHIPS)':
 C_PATH='@s9s_mb_2u_lib.s9s_mb_2u(sch_1):page297_i327@pure_quanta.q_cap(chips)',
 P_PATH='@s9s_mb_2u_lib.s9s_mb_2u(sch_1):page191_i327@pure_quanta.q_cap(chips)',
 PATH='I327',
 DRAWING='@S9S_MB_2U_LIB.S9S_MB_2U(SCH_1):PAGE297',
 PHYS_PAGE='191',
 XY='(-3350,1075)',
 ROT='2',
 VER='1',
 PACK_TYPE='0402',
 CDS_LIB='pure_quanta',
 CDS_PART_NAME='Q_CAP_0402-0.1UF,25V,10%,X7R,CA',
 TOLERANCE='10%',
 MATERIAL='X7R',
 VOLTAGE='25V',
 VALUE='0.1UF',
 PRIM_FILE='./archive_libs/logical/q_cap/chips/chips.prt';

PART_NAME
 C2379 'Q_CAP_C0402-100NF,50V,10%,EMPTA':;

SECTION_NUMBER 1
 '@S9S_MB_2U_LIB.S9S_MB_2U(SCH_1):PAGE329_I1@PURE_QUANTA.Q_CAP(CHIPS)':
 C_PATH='@s9s_mb_2u_lib.s9s_mb_2u(sch_1):page329_i1@pure_quanta.q_cap(chips)',
 P_PATH='@s9s_mb_2u_lib.s9s_mb_2u(sch_1):page307_i1@pure_quanta.q_cap(chips)',
 PATH='I1',
 DRAWING='@S9S_MB_2U_LIB.S9S_MB_2U(SCH_1):PAGE329',
 PHYS_PAGE='307',
 XY='(-700,2825)',
 ROT='2',
 VER='1',
 PACK_TYPE='C0402',
 CDS_LIB='pure_quanta',
 CDS_PART_NAME='Q_CAP_C0402-100NF,50V,10%,EMPTA',
 TOLERANCE='10%',
 MATERIAL='EMPTY',
 VOLTAGE='50V',
 VALUE='100NF',
 PRIM_FILE='./archive_libs/logical/q_cap/chips/chips.prt';

PART_NAME
 C2380 'Q_CAP_C0402-100NF,50V,10%,EMPTA':;

SECTION_NUMBER 1
 '@S9S_MB_2U_LIB.S9S_MB_2U(SCH_1):PAGE329_I35@PURE_QUANTA.Q_CAP(CHIPS)':
 C_PATH='@s9s_mb_2u_lib.s9s_mb_2u(sch_1):page329_i35@pure_quanta.q_cap(chips)',
 P_PATH='@s9s_mb_2u_lib.s9s_mb_2u(sch_1):page307_i35@pure_quanta.q_cap(chips)',
 PATH='I35',
 DRAWING='@S9S_MB_2U_LIB.S9S_MB_2U(SCH_1):PAGE329',
 PHYS_PAGE='307',
 XY='(-675,700)',
 ROT='2',
 VER='1',
 PACK_TYPE='C0402',
 CDS_LIB='pure_quanta',
 CDS_PART_NAME='Q_CAP_C0402-100NF,50V,10%,EMPTA',
 TOLERANCE='10%',
 MATERIAL='EMPTY',
 VOLTAGE='50V',
 VALUE='100NF',
 PRIM_FILE='./archive_libs/logical/q_cap/chips/chips.prt';

PART_NAME
 C2381 'Q_CAP_C0402-100NF,50V,10%,EMPTA':;

SECTION_NUMBER 1
 '@S9S_MB_2U_LIB.S9S_MB_2U(SCH_1):PAGE329_I14@PURE_QUANTA.Q_CAP(CHIPS)':
 C_PATH='@s9s_mb_2u_lib.s9s_mb_2u(sch_1):page329_i14@pure_quanta.q_cap(chips)',
 P_PATH='@s9s_mb_2u_lib.s9s_mb_2u(sch_1):page307_i14@pure_quanta.q_cap(chips)',
 PATH='I14',
 DRAWING='@S9S_MB_2U_LIB.S9S_MB_2U(SCH_1):PAGE329',
 PHYS_PAGE='307',
 XY='(-275,2825)',
 ROT='2',
 VER='1',
 PACK_TYPE='C0402',
 CDS_LIB='pure_quanta',
 CDS_PART_NAME='Q_CAP_C0402-100NF,50V,10%,EMPTA',
 TOLERANCE='10%',
 MATERIAL='EMPTY',
 VOLTAGE='50V',
 VALUE='100NF',
 PRIM_FILE='./archive_libs/logical/q_cap/chips/chips.prt';

PART_NAME
 C2382 'Q_CAP_C0402-100NF,50V,10%,EMPTA':;

SECTION_NUMBER 1
 '@S9S_MB_2U_LIB.S9S_MB_2U(SCH_1):PAGE329_I33@PURE_QUANTA.Q_CAP(CHIPS)':
 C_PATH='@s9s_mb_2u_lib.s9s_mb_2u(sch_1):page329_i33@pure_quanta.q_cap(chips)',
 P_PATH='@s9s_mb_2u_lib.s9s_mb_2u(sch_1):page307_i33@pure_quanta.q_cap(chips)',
 PATH='I33',
 DRAWING='@S9S_MB_2U_LIB.S9S_MB_2U(SCH_1):PAGE329',
 PHYS_PAGE='307',
 XY='(-250,700)',
 ROT='2',
 VER='1',
 PACK_TYPE='C0402',
 CDS_LIB='pure_quanta',
 CDS_PART_NAME='Q_CAP_C0402-100NF,50V,10%,EMPTA',
 TOLERANCE='10%',
 MATERIAL='EMPTY',
 VOLTAGE='50V',
 VALUE='100NF',
 PRIM_FILE='./archive_libs/logical/q_cap/chips/chips.prt';

PART_NAME
 C2383 'Q_CAP_C0402-100NF,50V,10%,EMPTA':;

SECTION_NUMBER 1
 '@S9S_MB_2U_LIB.S9S_MB_2U(SCH_1):PAGE329_I11@PURE_QUANTA.Q_CAP(CHIPS)':
 C_PATH='@s9s_mb_2u_lib.s9s_mb_2u(sch_1):page329_i11@pure_quanta.q_cap(chips)',
 P_PATH='@s9s_mb_2u_lib.s9s_mb_2u(sch_1):page307_i11@pure_quanta.q_cap(chips)',
 PATH='I11',
 DRAWING='@S9S_MB_2U_LIB.S9S_MB_2U(SCH_1):PAGE329',
 PHYS_PAGE='307',
 XY='(325,3850)',
 ROT='2',
 VER='1',
 PACK_TYPE='C0402',
 CDS_LIB='pure_quanta',
 CDS_PART_NAME='Q_CAP_C0402-100NF,50V,10%,EMPTA',
 TOLERANCE='10%',
 MATERIAL='EMPTY',
 VOLTAGE='50V',
 VALUE='100NF',
 PRIM_FILE='./archive_libs/logical/q_cap/chips/chips.prt';

PART_NAME
 C2384 'Q_CAP_C0402-100NF,50V,10%,EMPTA':;

SECTION_NUMBER 1
 '@S9S_MB_2U_LIB.S9S_MB_2U(SCH_1):PAGE329_I29@PURE_QUANTA.Q_CAP(CHIPS)':
 C_PATH='@s9s_mb_2u_lib.s9s_mb_2u(sch_1):page329_i29@pure_quanta.q_cap(chips)',
 P_PATH='@s9s_mb_2u_lib.s9s_mb_2u(sch_1):page307_i29@pure_quanta.q_cap(chips)',
 PATH='I29',
 DRAWING='@S9S_MB_2U_LIB.S9S_MB_2U(SCH_1):PAGE329',
 PHYS_PAGE='307',
 XY='(350,1725)',
 ROT='2',
 VER='1',
 PACK_TYPE='C0402',
 CDS_LIB='pure_quanta',
 CDS_PART_NAME='Q_CAP_C0402-100NF,50V,10%,EMPTA',
 TOLERANCE='10%',
 MATERIAL='EMPTY',
 VOLTAGE='50V',
 VALUE='100NF',
 PRIM_FILE='./archive_libs/logical/q_cap/chips/chips.prt';

PART_NAME
 C2385 'Q_CAP_C0402-100NF,50V,10%,EMPTA':;

SECTION_NUMBER 1
 '@S9S_MB_2U_LIB.S9S_MB_2U(SCH_1):PAGE329_I57@PURE_QUANTA.Q_CAP(CHIPS)':
 C_PATH='@s9s_mb_2u_lib.s9s_mb_2u(sch_1):page329_i57@pure_quanta.q_cap(chips)',
 P_PATH='@s9s_mb_2u_lib.s9s_mb_2u(sch_1):page307_i57@pure_quanta.q_cap(chips)',
 PATH='I57',
 DRAWING='@S9S_MB_2U_LIB.S9S_MB_2U(SCH_1):PAGE329',
 PHYS_PAGE='307',
 XY='(-675,-1175)',
 ROT='2',
 VER='1',
 PACK_TYPE='C0402',
 CDS_LIB='pure_quanta',
 CDS_PART_NAME='Q_CAP_C0402-100NF,50V,10%,EMPTA',
 TOLERANCE='10%',
 MATERIAL='EMPTY',
 VOLTAGE='50V',
 VALUE='100NF',
 PRIM_FILE='./archive_libs/logical/q_cap/chips/chips.prt';

PART_NAME
 C2386 'Q_CAP_C0402-100NF,50V,10%,EMPTA':;

SECTION_NUMBER 1
 '@S9S_MB_2U_LIB.S9S_MB_2U(SCH_1):PAGE329_I55@PURE_QUANTA.Q_CAP(CHIPS)':
 C_PATH='@s9s_mb_2u_lib.s9s_mb_2u(sch_1):page329_i55@pure_quanta.q_cap(chips)',
 P_PATH='@s9s_mb_2u_lib.s9s_mb_2u(sch_1):page307_i55@pure_quanta.q_cap(chips)',
 PATH='I55',
 DRAWING='@S9S_MB_2U_LIB.S9S_MB_2U(SCH_1):PAGE329',
 PHYS_PAGE='307',
 XY='(-250,-1175)',
 ROT='2',
 VER='1',
 PACK_TYPE='C0402',
 CDS_LIB='pure_quanta',
 CDS_PART_NAME='Q_CAP_C0402-100NF,50V,10%,EMPTA',
 TOLERANCE='10%',
 MATERIAL='EMPTY',
 VOLTAGE='50V',
 VALUE='100NF',
 PRIM_FILE='./archive_libs/logical/q_cap/chips/chips.prt';

PART_NAME
 C2387 'Q_CAP_C0402-100NF,50V,10%,EMPTA':;

SECTION_NUMBER 1
 '@S9S_MB_2U_LIB.S9S_MB_2U(SCH_1):PAGE329_I51@PURE_QUANTA.Q_CAP(CHIPS)':
 C_PATH='@s9s_mb_2u_lib.s9s_mb_2u(sch_1):page329_i51@pure_quanta.q_cap(chips)',
 P_PATH='@s9s_mb_2u_lib.s9s_mb_2u(sch_1):page307_i51@pure_quanta.q_cap(chips)',
 PATH='I51',
 DRAWING='@S9S_MB_2U_LIB.S9S_MB_2U(SCH_1):PAGE329',
 PHYS_PAGE='307',
 XY='(350,-150)',
 ROT='2',
 VER='1',
 PACK_TYPE='C0402',
 CDS_LIB='pure_quanta',
 CDS_PART_NAME='Q_CAP_C0402-100NF,50V,10%,EMPTA',
 TOLERANCE='10%',
 MATERIAL='EMPTY',
 VOLTAGE='50V',
 VALUE='100NF',
 PRIM_FILE='./archive_libs/logical/q_cap/chips/chips.prt';

PART_NAME
 C2388 'Q_CAP_C0402-100NF,50V,10%,EMPTA':;

SECTION_NUMBER 1
 '@S9S_MB_2U_LIB.S9S_MB_2U(SCH_1):PAGE326_I64@PURE_QUANTA.Q_CAP(CHIPS)':
 C_PATH='@s9s_mb_2u_lib.s9s_mb_2u(sch_1):page326_i64@pure_quanta.q_cap(chips)',
 P_PATH='@s9s_mb_2u_lib.s9s_mb_2u(sch_1):page306_i64@pure_quanta.q_cap(chips)',
 PATH='I64',
 DRAWING='@S9S_MB_2U_LIB.S9S_MB_2U(SCH_1):PAGE326',
 PHYS_PAGE='306',
 XY='(125,1350)',
 ROT='2',
 VER='1',
 PACK_TYPE='C0402',
 CDS_LIB='pure_quanta',
 CDS_PART_NAME='Q_CAP_C0402-100NF,50V,10%,EMPTA',
 TOLERANCE='10%',
 MATERIAL='EMPTY',
 VOLTAGE='50V',
 VALUE='100NF',
 PRIM_FILE='./archive_libs/logical/q_cap/chips/chips.prt';

PART_NAME
 C2389 'Q_CAP_C0402-100NF,50V,10%,EMPTA':;

SECTION_NUMBER 1
 '@S9S_MB_2U_LIB.S9S_MB_2U(SCH_1):PAGE326_I76@PURE_QUANTA.Q_CAP(CHIPS)':
 C_PATH='@s9s_mb_2u_lib.s9s_mb_2u(sch_1):page326_i76@pure_quanta.q_cap(chips)',
 P_PATH='@s9s_mb_2u_lib.s9s_mb_2u(sch_1):page306_i76@pure_quanta.q_cap(chips)',
 PATH='I76',
 DRAWING='@S9S_MB_2U_LIB.S9S_MB_2U(SCH_1):PAGE326',
 PHYS_PAGE='306',
 XY='(550,1350)',
 ROT='2',
 VER='1',
 PACK_TYPE='C0402',
 CDS_LIB='pure_quanta',
 CDS_PART_NAME='Q_CAP_C0402-100NF,50V,10%,EMPTA',
 TOLERANCE='10%',
 MATERIAL='EMPTY',
 VOLTAGE='50V',
 VALUE='100NF',
 PRIM_FILE='./archive_libs/logical/q_cap/chips/chips.prt';

PART_NAME
 C2390 'Q_CAP_C0402-100NF,50V,10%,EMPTA':;

SECTION_NUMBER 1
 '@S9S_MB_2U_LIB.S9S_MB_2U(SCH_1):PAGE326_I71@PURE_QUANTA.Q_CAP(CHIPS)':
 C_PATH='@s9s_mb_2u_lib.s9s_mb_2u(sch_1):page326_i71@pure_quanta.q_cap(chips)',
 P_PATH='@s9s_mb_2u_lib.s9s_mb_2u(sch_1):page306_i71@pure_quanta.q_cap(chips)',
 PATH='I71',
 DRAWING='@S9S_MB_2U_LIB.S9S_MB_2U(SCH_1):PAGE326',
 PHYS_PAGE='306',
 XY='(1150,2375)',
 ROT='2',
 VER='1',
 PACK_TYPE='C0402',
 CDS_LIB='pure_quanta',
 CDS_PART_NAME='Q_CAP_C0402-100NF,50V,10%,EMPTA',
 TOLERANCE='10%',
 MATERIAL='EMPTY',
 VOLTAGE='50V',
 VALUE='100NF',
 PRIM_FILE='./archive_libs/logical/q_cap/chips/chips.prt';

PART_NAME
 C2391 'Q_CAP_0402-1000PF,50V,5%,EMPTYA':;

SECTION_NUMBER 1
 '@S9S_MB_2U_LIB.S9S_MB_2U(SCH_1):PAGE147_I66@PURE_QUANTA.Q_CAP(CHIPS)':
 C_PATH='@s9s_mb_2u_lib.s9s_mb_2u(sch_1):page147_i66@pure_quanta.q_cap(chips)',
 P_PATH='@s9s_mb_2u_lib.s9s_mb_2u(sch_1):page144_i66@pure_quanta.q_cap(chips)',
 PATH='I66',
 DRAWING='@S9S_MB_2U_LIB.S9S_MB_2U(SCH_1):PAGE147',
 PHYS_PAGE='144',
 XY='(-3250,3625)',
 ROT='0',
 VER='1',
 PACK_TYPE='0402',
 CDS_LIB='pure_quanta',
 CDS_PART_NAME='Q_CAP_0402-1000PF,50V,5%,EMPTYA',
 TOLERANCE='5%',
 MATERIAL='EMPTY',
 VOLTAGE='50V',
 VALUE='1000PF',
 PRIM_FILE='./archive_libs/logical/q_cap/chips/chips.prt';

PART_NAME
 C2392 'Q_CAP_0402-0.1UF,25V,10%,EMPTYA':;

SECTION_NUMBER 1
 '@S9S_MB_2U_LIB.S9S_MB_2U(SCH_1):PAGE326_I95@PURE_QUANTA.Q_CAP(CHIPS)':
 C_PATH='@s9s_mb_2u_lib.s9s_mb_2u(sch_1):page326_i95@pure_quanta.q_cap(chips)',
 P_PATH='@s9s_mb_2u_lib.s9s_mb_2u(sch_1):page306_i95@pure_quanta.q_cap(chips)',
 PATH='I95',
 DRAWING='@S9S_MB_2U_LIB.S9S_MB_2U(SCH_1):PAGE326',
 PHYS_PAGE='306',
 XY='(-1625,-1025)',
 ROT='0',
 VER='1',
 PACK_TYPE='0402',
 CDS_LIB='pure_quanta',
 CDS_PART_NAME='Q_CAP_0402-0.1UF,25V,10%,EMPTYA',
 TOLERANCE='10%',
 MATERIAL='EMPTY',
 VOLTAGE='25V',
 VALUE='0.1UF',
 PRIM_FILE='./archive_libs/logical/q_cap/chips/chips.prt';

PART_NAME
 C2393 'Q_CAP_0402-0.1UF,25V,10%,EMPTYA':;

SECTION_NUMBER 1
 '@S9S_MB_2U_LIB.S9S_MB_2U(SCH_1):PAGE326_I92@PURE_QUANTA.Q_CAP(CHIPS)':
 C_PATH='@s9s_mb_2u_lib.s9s_mb_2u(sch_1):page326_i92@pure_quanta.q_cap(chips)',
 P_PATH='@s9s_mb_2u_lib.s9s_mb_2u(sch_1):page306_i92@pure_quanta.q_cap(chips)',
 PATH='I92',
 DRAWING='@S9S_MB_2U_LIB.S9S_MB_2U(SCH_1):PAGE326',
 PHYS_PAGE='306',
 XY='(400,4100)',
 ROT='0',
 VER='1',
 PACK_TYPE='0402',
 CDS_LIB='pure_quanta',
 CDS_PART_NAME='Q_CAP_0402-0.1UF,25V,10%,EMPTYA',
 TOLERANCE='10%',
 MATERIAL='EMPTY',
 VOLTAGE='25V',
 VALUE='0.1UF',
 PRIM_FILE='./archive_libs/logical/q_cap/chips/chips.prt';

PART_NAME
 C2394 'Q_CAP_0402-0.1UF,25V,10%,X7R,CA':;

SECTION_NUMBER 1
 '@S9S_MB_2U_LIB.S9S_MB_2U(SCH_1):PAGE326_I93@PURE_QUANTA.Q_CAP(CHIPS)':
 C_PATH='@s9s_mb_2u_lib.s9s_mb_2u(sch_1):page326_i93@pure_quanta.q_cap(chips)',
 P_PATH='@s9s_mb_2u_lib.s9s_mb_2u(sch_1):page306_i93@pure_quanta.q_cap(chips)',
 PATH='I93',
 DRAWING='@S9S_MB_2U_LIB.S9S_MB_2U(SCH_1):PAGE326',
 PHYS_PAGE='306',
 XY='(950,275)',
 ROT='0',
 VER='1',
 PACK_TYPE='0402',
 CDS_LIB='pure_quanta',
 CDS_PART_NAME='Q_CAP_0402-0.1UF,25V,10%,X7R,CA',
 TOLERANCE='10%',
 MATERIAL='X7R',
 VOLTAGE='25V',
 VALUE='0.1UF',
 PRIM_FILE='./archive_libs/logical/q_cap/chips/chips.prt';

PART_NAME
 C2443 'Q_CAP_C0402-10UF,6.3V,20%,X6S,B':;

SECTION_NUMBER 1
 '@S9S_MB_2U_LIB.S9S_MB_2U(SCH_1):PAGE264_I18@PURE_QUANTA.Q_CAP(CHIPS)':
 C_PATH='@s9s_mb_2u_lib.s9s_mb_2u(sch_1):page264_i18@pure_quanta.q_cap(chips)',
 P_PATH='@s9s_mb_2u_lib.s9s_mb_2u(sch_1):page278_i18@pure_quanta.q_cap(chips)',
 PATH='I18',
 DRAWING='@S9S_MB_2U_LIB.S9S_MB_2U(SCH_1):PAGE264',
 PHYS_PAGE='278',
 XY='(-12100,8675)',
 ROT='0',
 VER='1',
 PACK_TYPE='C0402',
 LOCATION='C2443',
 CDS_LIB='pure_quanta',
 CDS_PART_NAME='Q_CAP_C0402-10UF,6.3V,20%,X6S,B',
 TOLERANCE='20%',
 MATERIAL='X6S',
 VOLTAGE='6.3V',
 VALUE='10UF',
 PRIM_FILE='./archive_libs/logical/q_cap/chips/chips.prt';

PART_NAME
 C2444 'Q_CAP_0402-0.1UF,25V,10%,X7R,CA':;

SECTION_NUMBER 1
 '@S9S_MB_2U_LIB.S9S_MB_2U(SCH_1):PAGE264_I19@PURE_QUANTA.Q_CAP(CHIPS)':
 C_PATH='@s9s_mb_2u_lib.s9s_mb_2u(sch_1):page264_i19@pure_quanta.q_cap(chips)',
 P_PATH='@s9s_mb_2u_lib.s9s_mb_2u(sch_1):page278_i19@pure_quanta.q_cap(chips)',
 PATH='I19',
 DRAWING='@S9S_MB_2U_LIB.S9S_MB_2U(SCH_1):PAGE264',
 PHYS_PAGE='278',
 XY='(-11875,8675)',
 ROT='0',
 VER='1',
 PACK_TYPE='0402',
 LOCATION='C2444',
 CDS_LIB='pure_quanta',
 CDS_PART_NAME='Q_CAP_0402-0.1UF,25V,10%,X7R,CA',
 TOLERANCE='10%',
 MATERIAL='X7R',
 VOLTAGE='25V',
 VALUE='0.1UF',
 PRIM_FILE='./archive_libs/logical/q_cap/chips/chips.prt';

PART_NAME
 C2445 'Q_CAP_0402-1000PF,50V,5%,EMPTYA':;

SECTION_NUMBER 1
 '@S9S_MB_2U_LIB.S9S_MB_2U(SCH_1):PAGE285_I11@PURE_QUANTA.Q_CAP(CHIPS)':
 C_PATH='@s9s_mb_2u_lib.s9s_mb_2u(sch_1):page285_i11@pure_quanta.q_cap(chips)',
 P_PATH='@s9s_mb_2u_lib.s9s_mb_2u(sch_1):page299_i11@pure_quanta.q_cap(chips)',
 PATH='I11',
 DRAWING='@S9S_MB_2U_LIB.S9S_MB_2U(SCH_1):PAGE285',
 PHYS_PAGE='299',
 XY='(-9750,2950)',
 ROT='0',
 VER='1',
 PACK_TYPE='0402',
 LOCATION='C2445',
 SEC='1',
 CDS_LIB='pure_quanta',
 CDS_PART_NAME='Q_CAP_0402-1000PF,50V,5%,EMPTYA',
 SEC_TYPE='0402',
 TOLERANCE='5%',
 MATERIAL='EMPTY',
 VOLTAGE='50V',
 VALUE='1000PF',
 PRIM_FILE='./archive_libs/logical/q_cap/chips/chips.prt';

PART_NAME
 C2446 'Q_CAP_0402-1000PF,50V,5%,X7R,TA':;

SECTION_NUMBER 1
 '@S9S_MB_2U_LIB.S9S_MB_2U(SCH_1):PAGE270_I34@PURE_QUANTA.Q_CAP(CHIPS)':
 C_PATH='@s9s_mb_2u_lib.s9s_mb_2u(sch_1):page270_i34@pure_quanta.q_cap(chips)',
 P_PATH='@s9s_mb_2u_lib.s9s_mb_2u(sch_1):page284_i34@pure_quanta.q_cap(chips)',
 PATH='I34',
 DRAWING='@S9S_MB_2U_LIB.S9S_MB_2U(SCH_1):PAGE270',
 PHYS_PAGE='284',
 XY='(-1200,-1500)',
 ROT='0',
 VER='2',
 PACK_TYPE='0402',
 LOCATION='C2446',
 SEC='1',
 CDS_LIB='pure_quanta',
 CDS_PART_NAME='Q_CAP_0402-1000PF,50V,5%,X7R,TA',
 SEC_TYPE='0402',
 TOLERANCE='5%',
 MATERIAL='X7R',
 VOLTAGE='50V',
 VALUE='1000PF',
 PRIM_FILE='./archive_libs/logical/q_cap/chips/chips.prt';

PART_NAME
 C2447 'Q_CAP_0402-1000PF,50V,5%,EMPTYA':;

SECTION_NUMBER 1
 '@S9S_MB_2U_LIB.S9S_MB_2U(SCH_1):PAGE270_I35@PURE_QUANTA.Q_CAP(CHIPS)':
 C_PATH='@s9s_mb_2u_lib.s9s_mb_2u(sch_1):page270_i35@pure_quanta.q_cap(chips)',
 P_PATH='@s9s_mb_2u_lib.s9s_mb_2u(sch_1):page284_i35@pure_quanta.q_cap(chips)',
 PATH='I35',
 DRAWING='@S9S_MB_2U_LIB.S9S_MB_2U(SCH_1):PAGE270',
 PHYS_PAGE='284',
 XY='(-1200,-1625)',
 ROT='0',
 VER='2',
 PACK_TYPE='0402',
 LOCATION='C2447',
 CDS_LIB='pure_quanta',
 CDS_PART_NAME='Q_CAP_0402-1000PF,50V,5%,EMPTYA',
 TOLERANCE='5%',
 MATERIAL='EMPTY',
 VOLTAGE='50V',
 VALUE='1000PF',
 PRIM_FILE='./archive_libs/logical/q_cap/chips/chips.prt';

PART_NAME
 C2448 'Q_CAP_C0603-10UF,4V,20%,EMPTY,A':;

SECTION_NUMBER 1
 '@S9S_MB_2U_LIB.S9S_MB_2U(SCH_1):PAGE270_I103@PURE_QUANTA.Q_CAP(CHIPS)':
 C_PATH='@s9s_mb_2u_lib.s9s_mb_2u(sch_1):page270_i103@pure_quanta.q_cap(chips)',
 P_PATH='@s9s_mb_2u_lib.s9s_mb_2u(sch_1):page284_i103@pure_quanta.q_cap(chips)',
 PATH='I103',
 DRAWING='@S9S_MB_2U_LIB.S9S_MB_2U(SCH_1):PAGE270',
 PHYS_PAGE='284',
 XY='(3700,-300)',
 ROT='0',
 VER='1',
 PACK_TYPE='C0603',
 LOCATION='C2448',
 CDS_LIB='pure_quanta',
 CDS_PART_NAME='Q_CAP_C0603-10UF,4V,20%,EMPTY,A',
 TOLERANCE='20%',
 MATERIAL='EMPTY',
 VOLTAGE='4V',
 VALUE='10UF',
 PRIM_FILE='./archive_libs/logical/q_cap/chips/chips.prt';

PART_NAME
 C2449 'Q_CAP_C0402-100NF,50V,10%,X7R,A':;

SECTION_NUMBER 1
 '@S9S_MB_2U_LIB.S9S_MB_2U(SCH_1):PAGE270_I104@PURE_QUANTA.Q_CAP(CHIPS)':
 C_PATH='@s9s_mb_2u_lib.s9s_mb_2u(sch_1):page270_i104@pure_quanta.q_cap(chips)',
 P_PATH='@s9s_mb_2u_lib.s9s_mb_2u(sch_1):page284_i104@pure_quanta.q_cap(chips)',
 PATH='I104',
 DRAWING='@S9S_MB_2U_LIB.S9S_MB_2U(SCH_1):PAGE270',
 PHYS_PAGE='284',
 XY='(4025,-325)',
 ROT='0',
 VER='1',
 PACK_TYPE='C0402',
 LOCATION='C2449',
 CDS_LIB='pure_quanta',
 CDS_PART_NAME='Q_CAP_C0402-100NF,50V,10%,X7R,A',
 TOLERANCE='10%',
 MATERIAL='X7R',
 VOLTAGE='50V',
 VALUE='100NF',
 PRIM_FILE='./archive_libs/logical/q_cap/chips/chips.prt';

PART_NAME
 C2450 'Q_CAP_0402-1000PF,50V,5%,EMPTYA':;

SECTION_NUMBER 1
 '@S9S_MB_2U_LIB.S9S_MB_2U(SCH_1):PAGE278_I106@PURE_QUANTA.Q_CAP(CHIPS)':
 C_PATH='@s9s_mb_2u_lib.s9s_mb_2u(sch_1):page278_i106@pure_quanta.q_cap(chips)',
 P_PATH='@s9s_mb_2u_lib.s9s_mb_2u(sch_1):page292_i106@pure_quanta.q_cap(chips)',
 PATH='I106',
 DRAWING='@S9S_MB_2U_LIB.S9S_MB_2U(SCH_1):PAGE278',
 PHYS_PAGE='292',
 XY='(2025,9300)',
 ROT='0',
 VER='2',
 PACK_TYPE='0402',
 LOCATION='C2450',
 CDS_LIB='pure_quanta',
 CDS_PART_NAME='Q_CAP_0402-1000PF,50V,5%,EMPTYA',
 TOLERANCE='5%',
 MATERIAL='EMPTY',
 VOLTAGE='50V',
 VALUE='1000PF',
 PRIM_FILE='./archive_libs/logical/q_cap/chips/chips.prt';

PART_NAME
 C2451 'Q_CAP_0402-1000PF,50V,5%,X7R,TA':;

SECTION_NUMBER 1
 '@S9S_MB_2U_LIB.S9S_MB_2U(SCH_1):PAGE278_I63@PURE_QUANTA.Q_CAP(CHIPS)':
 C_PATH='@s9s_mb_2u_lib.s9s_mb_2u(sch_1):page278_i63@pure_quanta.q_cap(chips)',
 P_PATH='@s9s_mb_2u_lib.s9s_mb_2u(sch_1):page292_i63@pure_quanta.q_cap(chips)',
 PATH='I63',
 DRAWING='@S9S_MB_2U_LIB.S9S_MB_2U(SCH_1):PAGE278',
 PHYS_PAGE='292',
 XY='(2000,8875)',
 ROT='0',
 VER='2',
 PACK_TYPE='0402',
 LOCATION='C2451',
 CDS_LIB='pure_quanta',
 CDS_PART_NAME='Q_CAP_0402-1000PF,50V,5%,X7R,TA',
 TOLERANCE='5%',
 MATERIAL='X7R',
 VOLTAGE='50V',
 VALUE='1000PF',
 PRIM_FILE='./archive_libs/logical/q_cap/chips/chips.prt';

PART_NAME
 C2452 'Q_CAP_0402-1000PF,50V,5%,X7R,TA':;

SECTION_NUMBER 1
 '@S9S_MB_2U_LIB.S9S_MB_2U(SCH_1):PAGE278_I33@PURE_QUANTA.Q_CAP(CHIPS)':
 C_PATH='@s9s_mb_2u_lib.s9s_mb_2u(sch_1):page278_i33@pure_quanta.q_cap(chips)',
 P_PATH='@s9s_mb_2u_lib.s9s_mb_2u(sch_1):page292_i33@pure_quanta.q_cap(chips)',
 PATH='I33',
 DRAWING='@S9S_MB_2U_LIB.S9S_MB_2U(SCH_1):PAGE278',
 PHYS_PAGE='292',
 XY='(2150,4625)',
 ROT='0',
 VER='2',
 PACK_TYPE='0402',
 LOCATION='C2452',
 CDS_LIB='pure_quanta',
 CDS_PART_NAME='Q_CAP_0402-1000PF,50V,5%,X7R,TA',
 TOLERANCE='5%',
 MATERIAL='X7R',
 VOLTAGE='50V',
 VALUE='1000PF',
 PRIM_FILE='./archive_libs/logical/q_cap/chips/chips.prt';

PART_NAME
 C2453 'Q_CAP_0402-1000PF,50V,5%,EMPTYA':;

SECTION_NUMBER 1
 '@S9S_MB_2U_LIB.S9S_MB_2U(SCH_1):PAGE278_I32@PURE_QUANTA.Q_CAP(CHIPS)':
 C_PATH='@s9s_mb_2u_lib.s9s_mb_2u(sch_1):page278_i32@pure_quanta.q_cap(chips)',
 P_PATH='@s9s_mb_2u_lib.s9s_mb_2u(sch_1):page292_i32@pure_quanta.q_cap(chips)',
 PATH='I32',
 DRAWING='@S9S_MB_2U_LIB.S9S_MB_2U(SCH_1):PAGE278',
 PHYS_PAGE='292',
 XY='(2150,4500)',
 ROT='0',
 VER='2',
 PACK_TYPE='0402',
 LOCATION='C2453',
 CDS_LIB='pure_quanta',
 CDS_PART_NAME='Q_CAP_0402-1000PF,50V,5%,EMPTYA',
 TOLERANCE='5%',
 MATERIAL='EMPTY',
 VOLTAGE='50V',
 VALUE='1000PF',
 PRIM_FILE='./archive_libs/logical/q_cap/chips/chips.prt';

PART_NAME
 C2454 'Q_CAP_0402-1000PF,50V,5%,EMPTYA':;

SECTION_NUMBER 1
 '@S9S_MB_2U_LIB.S9S_MB_2U(SCH_1):PAGE282_I45@PURE_QUANTA.Q_CAP(CHIPS)':
 C_PATH='@s9s_mb_2u_lib.s9s_mb_2u(sch_1):page282_i45@pure_quanta.q_cap(chips)',
 P_PATH='@s9s_mb_2u_lib.s9s_mb_2u(sch_1):page296_i45@pure_quanta.q_cap(chips)',
 PATH='I45',
 DRAWING='@S9S_MB_2U_LIB.S9S_MB_2U(SCH_1):PAGE282',
 PHYS_PAGE='296',
 XY='(-4475,5600)',
 ROT='0',
 VER='2',
 PACK_TYPE='0402',
 LOCATION='C2454',
 CDS_LIB='pure_quanta',
 CDS_PART_NAME='Q_CAP_0402-1000PF,50V,5%,EMPTYA',
 TOLERANCE='5%',
 MATERIAL='EMPTY',
 VOLTAGE='50V',
 VALUE='1000PF',
 PRIM_FILE='./archive_libs/logical/q_cap/chips/chips.prt';

PART_NAME
 C2458 'Q_CAP_0402-0.1UF,25V,10%,EMPTYA':
 ROOM='HSC1_BOM2';

SECTION_NUMBER 1
 '@S9S_MB_2U_LIB.S9S_MB_2U(SCH_1):PAGE327_I8@PURE_QUANTA.Q_CAP(CHIPS)':
 C_PATH='@s9s_mb_2u_lib.s9s_mb_2u(sch_1):page327_i8@pure_quanta.q_cap(chips)',
 P_PATH='@s9s_mb_2u_lib.s9s_mb_2u(sch_1):page305_i8@pure_quanta.q_cap(chips)',
 PATH='I8',
 DRAWING='@S9S_MB_2U_LIB.S9S_MB_2U(SCH_1):PAGE327',
 PHYS_PAGE='305',
 XY='(2275,625)',
 ROT='0',
 VER='1',
 PACK_TYPE='0402',
 LOCATION='C2458',
 CDS_LIB='pure_quanta',
 CDS_PART_NAME='Q_CAP_0402-0.1UF,25V,10%,EMPTYA',
 TOLERANCE='10%',
 MATERIAL='EMPTY',
 VOLTAGE='25V',
 ROOM='HSC1_BOM2',
 VALUE='0.1UF',
 PRIM_FILE='./archive_libs/logical/q_cap/chips/chips.prt';

PART_NAME
 C2459 'Q_CAP_0603-1000PF,50V,10%,EMPTA':
 ROOM='HSC1_BOM2';

SECTION_NUMBER 1
 '@S9S_MB_2U_LIB.S9S_MB_2U(SCH_1):PAGE327_I6@PURE_QUANTA.Q_CAP(CHIPS)':
 C_PATH='@s9s_mb_2u_lib.s9s_mb_2u(sch_1):page327_i6@pure_quanta.q_cap(chips)',
 P_PATH='@s9s_mb_2u_lib.s9s_mb_2u(sch_1):page305_i6@pure_quanta.q_cap(chips)',
 PATH='I6',
 DRAWING='@S9S_MB_2U_LIB.S9S_MB_2U(SCH_1):PAGE327',
 PHYS_PAGE='305',
 XY='(2050,150)',
 ROT='2',
 VER='1',
 PACK_TYPE='0603',
 LOCATION='C2459',
 CDS_LIB='pure_quanta',
 CDS_PART_NAME='Q_CAP_0603-1000PF,50V,10%,EMPTA',
 TOLERANCE='10%',
 MATERIAL='EMPTY',
 VOLTAGE='50V',
 ROOM='HSC1_BOM2',
 VALUE='1000PF',
 PRIM_FILE='./archive_libs/logical/q_cap/chips/chips.prt';

PART_NAME
 C2460 'Q_CAP_0402-1000PF,50V,5%,X7R,TA':;

SECTION_NUMBER 1
 '@S9S_MB_2U_LIB.S9S_MB_2U(SCH_1):PAGE285_I36@PURE_QUANTA.Q_CAP(CHIPS)':
 C_PATH='@s9s_mb_2u_lib.s9s_mb_2u(sch_1):page285_i36@pure_quanta.q_cap(chips)',
 P_PATH='@s9s_mb_2u_lib.s9s_mb_2u(sch_1):page299_i36@pure_quanta.q_cap(chips)',
 PATH='I36',
 DRAWING='@S9S_MB_2U_LIB.S9S_MB_2U(SCH_1):PAGE285',
 PHYS_PAGE='299',
 XY='(-6175,3750)',
 ROT='0',
 VER='2',
 PACK_TYPE='0402',
 LOCATION='C2460',
 CDS_LIB='pure_quanta',
 CDS_PART_NAME='Q_CAP_0402-1000PF,50V,5%,X7R,TA',
 TOLERANCE='5%',
 MATERIAL='X7R',
 VOLTAGE='50V',
 VALUE='1000PF',
 PRIM_FILE='./archive_libs/logical/q_cap/chips/chips.prt';

PART_NAME
 C2541 'Q_CAP_C0402-0.22UF,25V,10%,X7RA':;

SECTION_NUMBER 1
 '@S9S_MB_2U_LIB.S9S_MB_2U(SCH_1):PAGE245_I73@PURE_QUANTA.Q_CAP(CHIPS)':
 C_PATH='@s9s_mb_2u_lib.s9s_mb_2u(sch_1):page245_i73@pure_quanta.q_cap(chips)',
 P_PATH='@s9s_mb_2u_lib.s9s_mb_2u(sch_1):page259_i73@pure_quanta.q_cap(chips)',
 PATH='I73',
 DRAWING='@S9S_MB_2U_LIB.S9S_MB_2U(SCH_1):PAGE245',
 PHYS_PAGE='259',
 XY='(-3225,-1600)',
 ROT='0',
 VER='1',
 PACK_TYPE='C0402',
 LOCATION='C2541',
 CDS_LIB='pure_quanta',
 CDS_PART_NAME='Q_CAP_C0402-0.22UF,25V,10%,X7RA',
 TOLERANCE='10%',
 MATERIAL='X7R',
 VOLTAGE='25V',
 VALUE='0.22UF',
 PRIM_FILE='./archive_libs/logical/q_cap/chips/chips.prt';

PART_NAME
 C2859 'Q_CAP_0402-1000PF,50V,5%,EMPTYA':;

SECTION_NUMBER 1
 '@S9S_MB_2U_LIB.S9S_MB_2U(SCH_1):PAGE270_I68@PURE_QUANTA.Q_CAP(CHIPS)':
 C_PATH='@s9s_mb_2u_lib.s9s_mb_2u(sch_1):page270_i68@pure_quanta.q_cap(chips)',
 P_PATH='@s9s_mb_2u_lib.s9s_mb_2u(sch_1):page284_i68@pure_quanta.q_cap(chips)',
 PATH='I68',
 DRAWING='@S9S_MB_2U_LIB.S9S_MB_2U(SCH_1):PAGE270',
 PHYS_PAGE='284',
 XY='(-1325,3175)',
 ROT='0',
 VER='2',
 PACK_TYPE='0402',
 LOCATION='C2859',
 CDS_LIB='pure_quanta',
 CDS_PART_NAME='Q_CAP_0402-1000PF,50V,5%,EMPTYA',
 TOLERANCE='5%',
 MATERIAL='EMPTY',
 VOLTAGE='50V',
 VALUE='1000PF',
 PRIM_FILE='./archive_libs/logical/q_cap/chips/chips.prt';

PART_NAME
 C2860 'Q_CAP_0402-1000PF,50V,5%,X7R,TA':;

SECTION_NUMBER 1
 '@S9S_MB_2U_LIB.S9S_MB_2U(SCH_1):PAGE270_I67@PURE_QUANTA.Q_CAP(CHIPS)':
 C_PATH='@s9s_mb_2u_lib.s9s_mb_2u(sch_1):page270_i67@pure_quanta.q_cap(chips)',
 P_PATH='@s9s_mb_2u_lib.s9s_mb_2u(sch_1):page284_i67@pure_quanta.q_cap(chips)',
 PATH='I67',
 DRAWING='@S9S_MB_2U_LIB.S9S_MB_2U(SCH_1):PAGE270',
 PHYS_PAGE='284',
 XY='(-1350,2750)',
 ROT='0',
 VER='2',
 PACK_TYPE='0402',
 LOCATION='C2860',
 CDS_LIB='pure_quanta',
 CDS_PART_NAME='Q_CAP_0402-1000PF,50V,5%,X7R,TA',
 TOLERANCE='5%',
 MATERIAL='X7R',
 VOLTAGE='50V',
 VALUE='1000PF',
 PRIM_FILE='./archive_libs/logical/q_cap/chips/chips.prt';

PART_NAME
 C3266 'Q_CAP_0402-1000PF,50V,5%,EMPTYA':;

SECTION_NUMBER 1
 '@S9S_MB_2U_LIB.S9S_MB_2U(SCH_1):PAGE252_I84@PURE_QUANTA.Q_CAP(CHIPS)':
 C_PATH='@s9s_mb_2u_lib.s9s_mb_2u(sch_1):page252_i84@pure_quanta.q_cap(chips)',
 P_PATH='@s9s_mb_2u_lib.s9s_mb_2u(sch_1):page266_i84@pure_quanta.q_cap(chips)',
 PATH='I84',
 DRAWING='@S9S_MB_2U_LIB.S9S_MB_2U(SCH_1):PAGE252',
 PHYS_PAGE='266',
 XY='(-4275,6700)',
 ROT='0',
 VER='2',
 PACK_TYPE='0402',
 LOCATION='C3266',
 CDS_LIB='pure_quanta',
 CDS_PART_NAME='Q_CAP_0402-1000PF,50V,5%,EMPTYA',
 TOLERANCE='5%',
 MATERIAL='EMPTY',
 VOLTAGE='50V',
 VALUE='1000PF',
 PRIM_FILE='./archive_libs/logical/q_cap/chips/chips.prt';

PART_NAME
 C3267 'Q_CAP_0402-1000PF,50V,5%,X7R,TA':;

SECTION_NUMBER 1
 '@S9S_MB_2U_LIB.S9S_MB_2U(SCH_1):PAGE252_I82@PURE_QUANTA.Q_CAP(CHIPS)':
 C_PATH='@s9s_mb_2u_lib.s9s_mb_2u(sch_1):page252_i82@pure_quanta.q_cap(chips)',
 P_PATH='@s9s_mb_2u_lib.s9s_mb_2u(sch_1):page266_i82@pure_quanta.q_cap(chips)',
 PATH='I82',
 DRAWING='@S9S_MB_2U_LIB.S9S_MB_2U(SCH_1):PAGE252',
 PHYS_PAGE='266',
 XY='(-4300,6275)',
 ROT='0',
 VER='2',
 PACK_TYPE='0402',
 LOCATION='C3267',
 CDS_LIB='pure_quanta',
 CDS_PART_NAME='Q_CAP_0402-1000PF,50V,5%,X7R,TA',
 TOLERANCE='5%',
 MATERIAL='X7R',
 VOLTAGE='50V',
 VALUE='1000PF',
 PRIM_FILE='./archive_libs/logical/q_cap/chips/chips.prt';

PART_NAME
 C3268 'Q_CAP_0402-1000PF,50V,5%,X7R,TA':;

SECTION_NUMBER 1
 '@S9S_MB_2U_LIB.S9S_MB_2U(SCH_1):PAGE252_I58@PURE_QUANTA.Q_CAP(CHIPS)':
 C_PATH='@s9s_mb_2u_lib.s9s_mb_2u(sch_1):page252_i58@pure_quanta.q_cap(chips)',
 P_PATH='@s9s_mb_2u_lib.s9s_mb_2u(sch_1):page266_i58@pure_quanta.q_cap(chips)',
 PATH='I58',
 DRAWING='@S9S_MB_2U_LIB.S9S_MB_2U(SCH_1):PAGE252',
 PHYS_PAGE='266',
 XY='(-4150,2025)',
 ROT='0',
 VER='2',
 PACK_TYPE='0402',
 LOCATION='C3268',
 CDS_LIB='pure_quanta',
 CDS_PART_NAME='Q_CAP_0402-1000PF,50V,5%,X7R,TA',
 TOLERANCE='5%',
 MATERIAL='X7R',
 VOLTAGE='50V',
 VALUE='1000PF',
 PRIM_FILE='./archive_libs/logical/q_cap/chips/chips.prt';

PART_NAME
 C3269 'Q_CAP_0402-1000PF,50V,5%,EMPTYA':;

SECTION_NUMBER 1
 '@S9S_MB_2U_LIB.S9S_MB_2U(SCH_1):PAGE252_I57@PURE_QUANTA.Q_CAP(CHIPS)':
 C_PATH='@s9s_mb_2u_lib.s9s_mb_2u(sch_1):page252_i57@pure_quanta.q_cap(chips)',
 P_PATH='@s9s_mb_2u_lib.s9s_mb_2u(sch_1):page266_i57@pure_quanta.q_cap(chips)',
 PATH='I57',
 DRAWING='@S9S_MB_2U_LIB.S9S_MB_2U(SCH_1):PAGE252',
 PHYS_PAGE='266',
 XY='(-4150,1900)',
 ROT='0',
 VER='2',
 PACK_TYPE='0402',
 LOCATION='C3269',
 CDS_LIB='pure_quanta',
 CDS_PART_NAME='Q_CAP_0402-1000PF,50V,5%,EMPTYA',
 TOLERANCE='5%',
 MATERIAL='EMPTY',
 VOLTAGE='50V',
 VALUE='1000PF',
 PRIM_FILE='./archive_libs/logical/q_cap/chips/chips.prt';

PART_NAME
 C3270 'Q_CAP_C0603-10UF,4V,20%,EMPTY,A':;

SECTION_NUMBER 1
 '@S9S_MB_2U_LIB.S9S_MB_2U(SCH_1):PAGE252_I127@PURE_QUANTA.Q_CAP(CHIPS)':
 C_PATH='@s9s_mb_2u_lib.s9s_mb_2u(sch_1):page252_i127@pure_quanta.q_cap(chips)',
 P_PATH='@s9s_mb_2u_lib.s9s_mb_2u(sch_1):page266_i127@pure_quanta.q_cap(chips)',
 PATH='I127',
 DRAWING='@S9S_MB_2U_LIB.S9S_MB_2U(SCH_1):PAGE252',
 PHYS_PAGE='266',
 XY='(750,2675)',
 ROT='0',
 VER='1',
 PACK_TYPE='C0603',
 LOCATION='C3270',
 CDS_LIB='pure_quanta',
 CDS_PART_NAME='Q_CAP_C0603-10UF,4V,20%,EMPTY,A',
 TOLERANCE='20%',
 MATERIAL='EMPTY',
 VOLTAGE='4V',
 VALUE='10UF',
 PRIM_FILE='./archive_libs/logical/q_cap/chips/chips.prt';

PART_NAME
 C3271 'Q_CAP_C0402-100NF,50V,10%,X7R,A':;

SECTION_NUMBER 1
 '@S9S_MB_2U_LIB.S9S_MB_2U(SCH_1):PAGE252_I128@PURE_QUANTA.Q_CAP(CHIPS)':
 C_PATH='@s9s_mb_2u_lib.s9s_mb_2u(sch_1):page252_i128@pure_quanta.q_cap(chips)',
 P_PATH='@s9s_mb_2u_lib.s9s_mb_2u(sch_1):page266_i128@pure_quanta.q_cap(chips)',
 PATH='I128',
 DRAWING='@S9S_MB_2U_LIB.S9S_MB_2U(SCH_1):PAGE252',
 PHYS_PAGE='266',
 XY='(1075,2650)',
 ROT='0',
 VER='1',
 PACK_TYPE='C0402',
 LOCATION='C3271',
 CDS_LIB='pure_quanta',
 CDS_PART_NAME='Q_CAP_C0402-100NF,50V,10%,X7R,A',
 TOLERANCE='10%',
 MATERIAL='X7R',
 VOLTAGE='50V',
 VALUE='100NF',
 PRIM_FILE='./archive_libs/logical/q_cap/chips/chips.prt';

PART_NAME
 C3273 'Q_CAP_0402-1000PF,50V,5%,EMPTYA':;

SECTION_NUMBER 1
 '@S9S_MB_2U_LIB.S9S_MB_2U(SCH_1):PAGE260_I61@PURE_QUANTA.Q_CAP(CHIPS)':
 C_PATH='@s9s_mb_2u_lib.s9s_mb_2u(sch_1):page260_i61@pure_quanta.q_cap(chips)',
 P_PATH='@s9s_mb_2u_lib.s9s_mb_2u(sch_1):page274_i61@pure_quanta.q_cap(chips)',
 PATH='I61',
 DRAWING='@S9S_MB_2U_LIB.S9S_MB_2U(SCH_1):PAGE260',
 PHYS_PAGE='274',
 XY='(-8350,7725)',
 ROT='0',
 VER='2',
 PACK_TYPE='0402',
 LOCATION='C3273',
 CDS_LIB='pure_quanta',
 CDS_PART_NAME='Q_CAP_0402-1000PF,50V,5%,EMPTYA',
 TOLERANCE='5%',
 MATERIAL='EMPTY',
 VOLTAGE='50V',
 VALUE='1000PF',
 PRIM_FILE='./archive_libs/logical/q_cap/chips/chips.prt';

PART_NAME
 C3274 'Q_CAP_0402-1000PF,50V,5%,X7R,TA':;

SECTION_NUMBER 1
 '@S9S_MB_2U_LIB.S9S_MB_2U(SCH_1):PAGE260_I60@PURE_QUANTA.Q_CAP(CHIPS)':
 C_PATH='@s9s_mb_2u_lib.s9s_mb_2u(sch_1):page260_i60@pure_quanta.q_cap(chips)',
 P_PATH='@s9s_mb_2u_lib.s9s_mb_2u(sch_1):page274_i60@pure_quanta.q_cap(chips)',
 PATH='I60',
 DRAWING='@S9S_MB_2U_LIB.S9S_MB_2U(SCH_1):PAGE260',
 PHYS_PAGE='274',
 XY='(-8375,7300)',
 ROT='0',
 VER='2',
 PACK_TYPE='0402',
 LOCATION='C3274',
 CDS_LIB='pure_quanta',
 CDS_PART_NAME='Q_CAP_0402-1000PF,50V,5%,X7R,TA',
 TOLERANCE='5%',
 MATERIAL='X7R',
 VOLTAGE='50V',
 VALUE='1000PF',
 PRIM_FILE='./archive_libs/logical/q_cap/chips/chips.prt';

PART_NAME
 C3275 'Q_CAP_0402-1000PF,50V,5%,X7R,TA':;

SECTION_NUMBER 1
 '@S9S_MB_2U_LIB.S9S_MB_2U(SCH_1):PAGE260_I23@PURE_QUANTA.Q_CAP(CHIPS)':
 C_PATH='@s9s_mb_2u_lib.s9s_mb_2u(sch_1):page260_i23@pure_quanta.q_cap(chips)',
 P_PATH='@s9s_mb_2u_lib.s9s_mb_2u(sch_1):page274_i23@pure_quanta.q_cap(chips)',
 PATH='I23',
 DRAWING='@S9S_MB_2U_LIB.S9S_MB_2U(SCH_1):PAGE260',
 PHYS_PAGE='274',
 XY='(-8225,3050)',
 ROT='0',
 VER='2',
 PACK_TYPE='0402',
 LOCATION='C3275',
 CDS_LIB='pure_quanta',
 CDS_PART_NAME='Q_CAP_0402-1000PF,50V,5%,X7R,TA',
 TOLERANCE='5%',
 MATERIAL='X7R',
 VOLTAGE='50V',
 VALUE='1000PF',
 PRIM_FILE='./archive_libs/logical/q_cap/chips/chips.prt';

PART_NAME
 C3276 'Q_CAP_0402-1000PF,50V,5%,EMPTYA':;

SECTION_NUMBER 1
 '@S9S_MB_2U_LIB.S9S_MB_2U(SCH_1):PAGE260_I22@PURE_QUANTA.Q_CAP(CHIPS)':
 C_PATH='@s9s_mb_2u_lib.s9s_mb_2u(sch_1):page260_i22@pure_quanta.q_cap(chips)',
 P_PATH='@s9s_mb_2u_lib.s9s_mb_2u(sch_1):page274_i22@pure_quanta.q_cap(chips)',
 PATH='I22',
 DRAWING='@S9S_MB_2U_LIB.S9S_MB_2U(SCH_1):PAGE260',
 PHYS_PAGE='274',
 XY='(-8225,2925)',
 ROT='0',
 VER='2',
 PACK_TYPE='0402',
 LOCATION='C3276',
 CDS_LIB='pure_quanta',
 CDS_PART_NAME='Q_CAP_0402-1000PF,50V,5%,EMPTYA',
 TOLERANCE='5%',
 MATERIAL='EMPTY',
 VOLTAGE='50V',
 VALUE='1000PF',
 PRIM_FILE='./archive_libs/logical/q_cap/chips/chips.prt';

PART_NAME
 C4562 'Q_CAP_C0402-1UF,25V,10%,EMPTY,A':;

SECTION_NUMBER 1
 '@S9S_MB_2U_LIB.S9S_MB_2U(SCH_1):PAGE326_I91@PURE_QUANTA.Q_CAP(CHIPS)':
 C_PATH='@s9s_mb_2u_lib.s9s_mb_2u(sch_1):page326_i91@pure_quanta.q_cap(chips)',
 P_PATH='@s9s_mb_2u_lib.s9s_mb_2u(sch_1):page306_i91@pure_quanta.q_cap(chips)',
 PATH='I91',
 DRAWING='@S9S_MB_2U_LIB.S9S_MB_2U(SCH_1):PAGE326',
 PHYS_PAGE='306',
 XY='(0,4100)',
 ROT='0',
 VER='1',
 PACK_TYPE='C0402',
 LOCATION='C4562',
 CDS_LIB='pure_quanta',
 CDS_PART_NAME='Q_CAP_C0402-1UF,25V,10%,EMPTY,A',
 TOLERANCE='10%',
 MATERIAL='EMPTY',
 VOLTAGE='25V',
 VALUE='1UF',
 PRIM_FILE='./archive_libs/logical/q_cap/chips/chips.prt';

PART_NAME
 C5229 'Q_CAP_C0402-1UF,25V,10%,EMPTY,A':
 ROOM='USB1_BOM2';

SECTION_NUMBER 1
 '@S9S_MB_2U_LIB.S9S_MB_2U(SCH_1):PAGE155_I88@PURE_QUANTA.Q_CAP(CHIPS)':
 C_PATH='@s9s_mb_2u_lib.s9s_mb_2u(sch_1):page155_i88@pure_quanta.q_cap(chips)',
 P_PATH='@s9s_mb_2u_lib.s9s_mb_2u(sch_1):page152_i88@pure_quanta.q_cap(chips)',
 PATH='I88',
 DRAWING='@S9S_MB_2U_LIB.S9S_MB_2U(SCH_1):PAGE155',
 PHYS_PAGE='152',
 XY='(75,750)',
 ROT='0',
 VER='1',
 PACK_TYPE='C0402',
 CDS_LIB='pure_quanta',
 CDS_PART_NAME='Q_CAP_C0402-1UF,25V,10%,EMPTY,A',
 TOLERANCE='10%',
 MATERIAL='EMPTY',
 VOLTAGE='25V',
 ROOM='USB1_BOM2',
 VALUE='1UF',
 PRIM_FILE='./archive_libs/logical/q_cap/chips/chips.prt';

PART_NAME
 C5232 'Q_CAP_0402-0.1UF,25V,10%,EMPTYA':
 ROOM='USB1_BOM2';

SECTION_NUMBER 1
 '@S9S_MB_2U_LIB.S9S_MB_2U(SCH_1):PAGE155_I81@PURE_QUANTA.Q_CAP(CHIPS)':
 C_PATH='@s9s_mb_2u_lib.s9s_mb_2u(sch_1):page155_i81@pure_quanta.q_cap(chips)',
 P_PATH='@s9s_mb_2u_lib.s9s_mb_2u(sch_1):page152_i81@pure_quanta.q_cap(chips)',
 PATH='I81',
 DRAWING='@S9S_MB_2U_LIB.S9S_MB_2U(SCH_1):PAGE155',
 PHYS_PAGE='152',
 XY='(-1150,-225)',
 ROT='0',
 VER='1',
 PACK_TYPE='0402',
 CDS_LIB='pure_quanta',
 CDS_PART_NAME='Q_CAP_0402-0.1UF,25V,10%,EMPTYA',
 TOLERANCE='10%',
 MATERIAL='EMPTY',
 VOLTAGE='25V',
 ROOM='USB1_BOM2',
 VALUE='0.1UF',
 PRIM_FILE='./archive_libs/logical/q_cap/chips/chips.prt';

PART_NAME
 C5234 'Q_CAP_0402-0.1UF,25V,10%,EMPTYA':
 ROOM='USB1_BOM2';

SECTION_NUMBER 1
 '@S9S_MB_2U_LIB.S9S_MB_2U(SCH_1):PAGE155_I92@PURE_QUANTA.Q_CAP(CHIPS)':
 C_PATH='@s9s_mb_2u_lib.s9s_mb_2u(sch_1):page155_i92@pure_quanta.q_cap(chips)',
 P_PATH='@s9s_mb_2u_lib.s9s_mb_2u(sch_1):page152_i92@pure_quanta.q_cap(chips)',
 PATH='I92',
 DRAWING='@S9S_MB_2U_LIB.S9S_MB_2U(SCH_1):PAGE155',
 PHYS_PAGE='152',
 XY='(575,725)',
 ROT='0',
 VER='1',
 PACK_TYPE='0402',
 CDS_LIB='pure_quanta',
 CDS_PART_NAME='Q_CAP_0402-0.1UF,25V,10%,EMPTYA',
 TOLERANCE='10%',
 MATERIAL='EMPTY',
 VOLTAGE='25V',
 ROOM='USB1_BOM2',
 VALUE='0.1UF',
 PRIM_FILE='./archive_libs/logical/q_cap/chips/chips.prt';

PART_NAME
 C5236 'Q_CAP_0402-0.1UF,25V,10%,EMPTYA':
 ROOM='USB1_BOM2';

SECTION_NUMBER 1
 '@S9S_MB_2U_LIB.S9S_MB_2U(SCH_1):PAGE155_I87@PURE_QUANTA.Q_CAP(CHIPS)':
 C_PATH='@s9s_mb_2u_lib.s9s_mb_2u(sch_1):page155_i87@pure_quanta.q_cap(chips)',
 P_PATH='@s9s_mb_2u_lib.s9s_mb_2u(sch_1):page152_i87@pure_quanta.q_cap(chips)',
 PATH='I87',
 DRAWING='@S9S_MB_2U_LIB.S9S_MB_2U(SCH_1):PAGE155',
 PHYS_PAGE='152',
 XY='(1475,-200)',
 ROT='0',
 VER='1',
 PACK_TYPE='0402',
 CDS_LIB='pure_quanta',
 CDS_PART_NAME='Q_CAP_0402-0.1UF,25V,10%,EMPTYA',
 TOLERANCE='10%',
 MATERIAL='EMPTY',
 VOLTAGE='25V',
 ROOM='USB1_BOM2',
 VALUE='0.1UF',
 PRIM_FILE='./archive_libs/logical/q_cap/chips/chips.prt';

PART_NAME
 D0 'Q_LED_SMLF-LED_BLUE,LTST-C281TA':;

SECTION_NUMBER 1
 '@S9S_MB_2U_LIB.S9S_MB_2U(SCH_1):PAGE207_I277@PURE_QUANTA.Q_LED(CHIPS)':
 C_PATH='@s9s_mb_2u_lib.s9s_mb_2u(sch_1):page207_i277@pure_quanta.q_led(chips)',
 P_PATH='@s9s_mb_2u_lib.s9s_mb_2u(sch_1):page218_i277@pure_quanta.q_led(chips)',
 PATH='I277',
 DRAWING='@S9S_MB_2U_LIB.S9S_MB_2U(SCH_1):PAGE207',
 COLOR='LED_BLUE',
 PHYS_PAGE='218',
 XY='(-3050,4700)',
 ROT='0',
 VER='1',
 PACK_TYPE='SMLF',
 LOCATION='D0',
 CDS_LIB='pure_quanta',
 CDS_PART_NAME='Q_LED_SMLF-LED_BLUE,LTST-C281TA',
 MANUF_PN='LTST-C281TBKT-5A',
 MATERIAL='IC',
 PRIM_FILE='./archive_libs/logical/q_led/chips/chips.prt';

PART_NAME
 D6 'Q_LED_SMLF-LED_YELLOW,LTST-C19A':;

SECTION_NUMBER 1
 '@S9S_MB_2U_LIB.S9S_MB_2U(SCH_1):PAGE207_I279@PURE_QUANTA.Q_LED(CHIPS)':
 C_PATH='@s9s_mb_2u_lib.s9s_mb_2u(sch_1):page207_i279@pure_quanta.q_led(chips)',
 P_PATH='@s9s_mb_2u_lib.s9s_mb_2u(sch_1):page218_i279@pure_quanta.q_led(chips)',
 PATH='I279',
 DRAWING='@S9S_MB_2U_LIB.S9S_MB_2U(SCH_1):PAGE207',
 COLOR='LED_YELLOW',
 PHYS_PAGE='218',
 XY='(650,1775)',
 ROT='0',
 VER='1',
 PACK_TYPE='SMLF',
 LOCATION='D6',
 CDS_LIB='pure_quanta',
 CDS_PART_NAME='Q_LED_SMLF-LED_YELLOW,LTST-C19A',
 MANUF_PN='LTST-C190KSKT-P',
 MATERIAL='IC',
 PRIM_FILE='./archive_libs/logical/q_led/chips/chips.prt';

PART_NAME
 D7 'BAT547F-BAT547F,SMLF,IC,BC0BATA':;

SECTION_NUMBER 1
 '@S9S_MB_2U_LIB.S9S_MB_2U(SCH_1):PAGE246_I32@PURE_QUANTA.BAT547F(CHIPS)':
 C_PATH='@s9s_mb_2u_lib.s9s_mb_2u(sch_1):page246_i32@pure_quanta.bat547f(chips)',
 P_PATH='@s9s_mb_2u_lib.s9s_mb_2u(sch_1):page260_i32@pure_quanta.bat547f(chips)',
 PATH='I32',
 DRAWING='@S9S_MB_2U_LIB.S9S_MB_2U(SCH_1):PAGE246',
 BOM_COST='VR_SYSTEM ',
 PIN_NAMES_ROTATE='TRUE',
 PHYS_PAGE='260',
 XY='(-6175,1975)',
 ROT='0',
 VER='1',
 CDS_LIB='pure_quanta',
 CDS_PART_NAME='BAT547F-BAT547F,SMLF,IC,BC0BATA',
 PART_TYPE='SMLF',
 MATERIAL='IC',
 VALUE='BAT547F',
 PRIM_FILE='./archive_libs/logical/bat547f/chips/chips.prt';

PART_NAME
 D42 'SCHOTTKY_12-B0530WS7F,SMLF,IC,A':;

SECTION_NUMBER 1
 '@S9S_MB_2U_LIB.S9S_MB_2U(SCH_1):PAGE115_I59@PURE_QUANTA.SCHOTTKY_12(CHIPS)':
 C_PATH='@s9s_mb_2u_lib.s9s_mb_2u(sch_1):page115_i59@pure_quanta.schottky_12(chi~
ps)',
 P_PATH='@s9s_mb_2u_lib.s9s_mb_2u(sch_1):page115_i59@pure_quanta.schottky_12(chi~
ps)',
 PATH='I59',
 DRAWING='@S9S_MB_2U_LIB.S9S_MB_2U(SCH_1):PAGE115',
 PHYS_PAGE='115',
 XY='(4100,2225)',
 ROT='0',
 VER='1',
 CDS_LIB='pure_quanta',
 CDS_PART_NAME='SCHOTTKY_12-B0530WS7F,SMLF,IC,A',
 PART_TYPE='SMLF',
 MATERIAL='IC',
 VALUE='B0530WS7F',
 PRIM_FILE='./archive_libs/logical/schottky_12/chips/chips.prt';

PART_NAME
 D43 'SCHOTTKY_12-B0530WS7F,SMLF,IC,A':;

SECTION_NUMBER 1
 '@S9S_MB_2U_LIB.S9S_MB_2U(SCH_1):PAGE115_I54@PURE_QUANTA.SCHOTTKY_12(CHIPS)':
 C_PATH='@s9s_mb_2u_lib.s9s_mb_2u(sch_1):page115_i54@pure_quanta.schottky_12(chi~
ps)',
 P_PATH='@s9s_mb_2u_lib.s9s_mb_2u(sch_1):page115_i54@pure_quanta.schottky_12(chi~
ps)',
 PATH='I54',
 DRAWING='@S9S_MB_2U_LIB.S9S_MB_2U(SCH_1):PAGE115',
 PHYS_PAGE='115',
 XY='(4100,1600)',
 ROT='0',
 VER='1',
 CDS_LIB='pure_quanta',
 CDS_PART_NAME='SCHOTTKY_12-B0530WS7F,SMLF,IC,A',
 PART_TYPE='SMLF',
 MATERIAL='IC',
 VALUE='B0530WS7F',
 PRIM_FILE='./archive_libs/logical/schottky_12/chips/chips.prt';

PART_NAME
 D44 'SCHOTTKY_12-B0530WS7F,SMLF,IC,A':;

SECTION_NUMBER 1
 '@S9S_MB_2U_LIB.S9S_MB_2U(SCH_1):PAGE115_I52@PURE_QUANTA.SCHOTTKY_12(CHIPS)':
 C_PATH='@s9s_mb_2u_lib.s9s_mb_2u(sch_1):page115_i52@pure_quanta.schottky_12(chi~
ps)',
 P_PATH='@s9s_mb_2u_lib.s9s_mb_2u(sch_1):page115_i52@pure_quanta.schottky_12(chi~
ps)',
 PATH='I52',
 DRAWING='@S9S_MB_2U_LIB.S9S_MB_2U(SCH_1):PAGE115',
 PHYS_PAGE='115',
 XY='(4100,975)',
 ROT='0',
 VER='1',
 CDS_LIB='pure_quanta',
 CDS_PART_NAME='SCHOTTKY_12-B0530WS7F,SMLF,IC,A',
 PART_TYPE='SMLF',
 MATERIAL='IC',
 VALUE='B0530WS7F',
 PRIM_FILE='./archive_libs/logical/schottky_12/chips/chips.prt';

PART_NAME
 D45 'SCHOTTKY_12-B0530WS7F,SMLF,IC,A':;

SECTION_NUMBER 1
 '@S9S_MB_2U_LIB.S9S_MB_2U(SCH_1):PAGE115_I50@PURE_QUANTA.SCHOTTKY_12(CHIPS)':
 C_PATH='@s9s_mb_2u_lib.s9s_mb_2u(sch_1):page115_i50@pure_quanta.schottky_12(chi~
ps)',
 P_PATH='@s9s_mb_2u_lib.s9s_mb_2u(sch_1):page115_i50@pure_quanta.schottky_12(chi~
ps)',
 PATH='I50',
 DRAWING='@S9S_MB_2U_LIB.S9S_MB_2U(SCH_1):PAGE115',
 PHYS_PAGE='115',
 XY='(4100,350)',
 ROT='0',
 VER='1',
 CDS_LIB='pure_quanta',
 CDS_PART_NAME='SCHOTTKY_12-B0530WS7F,SMLF,IC,A',
 PART_TYPE='SMLF',
 MATERIAL='IC',
 VALUE='B0530WS7F',
 PRIM_FILE='./archive_libs/logical/schottky_12/chips/chips.prt';

PART_NAME
 D46 'SCHOTTKY_12-B0530WS7F,SMLF,IC,A':;

SECTION_NUMBER 1
 '@S9S_MB_2U_LIB.S9S_MB_2U(SCH_1):PAGE115_I29@PURE_QUANTA.SCHOTTKY_12(CHIPS)':
 C_PATH='@s9s_mb_2u_lib.s9s_mb_2u(sch_1):page115_i29@pure_quanta.schottky_12(chi~
ps)',
 P_PATH='@s9s_mb_2u_lib.s9s_mb_2u(sch_1):page115_i29@pure_quanta.schottky_12(chi~
ps)',
 PATH='I29',
 DRAWING='@S9S_MB_2U_LIB.S9S_MB_2U(SCH_1):PAGE115',
 PHYS_PAGE='115',
 XY='(4100,-625)',
 ROT='0',
 VER='1',
 CDS_LIB='pure_quanta',
 CDS_PART_NAME='SCHOTTKY_12-B0530WS7F,SMLF,IC,A',
 PART_TYPE='SMLF',
 MATERIAL='IC',
 VALUE='B0530WS7F',
 PRIM_FILE='./archive_libs/logical/schottky_12/chips/chips.prt';

PART_NAME
 D47 'SCHOTTKY_12-B0530WS7F,SMLF,IC,A':;

SECTION_NUMBER 1
 '@S9S_MB_2U_LIB.S9S_MB_2U(SCH_1):PAGE115_I27@PURE_QUANTA.SCHOTTKY_12(CHIPS)':
 C_PATH='@s9s_mb_2u_lib.s9s_mb_2u(sch_1):page115_i27@pure_quanta.schottky_12(chi~
ps)',
 P_PATH='@s9s_mb_2u_lib.s9s_mb_2u(sch_1):page115_i27@pure_quanta.schottky_12(chi~
ps)',
 PATH='I27',
 DRAWING='@S9S_MB_2U_LIB.S9S_MB_2U(SCH_1):PAGE115',
 PHYS_PAGE='115',
 XY='(4100,-1250)',
 ROT='0',
 VER='1',
 CDS_LIB='pure_quanta',
 CDS_PART_NAME='SCHOTTKY_12-B0530WS7F,SMLF,IC,A',
 PART_TYPE='SMLF',
 MATERIAL='IC',
 VALUE='B0530WS7F',
 PRIM_FILE='./archive_libs/logical/schottky_12/chips/chips.prt';

PART_NAME
 D48 'SCHOTTKY_12-B0530WS7F,SMLF,IC,A':;

SECTION_NUMBER 1
 '@S9S_MB_2U_LIB.S9S_MB_2U(SCH_1):PAGE115_I25@PURE_QUANTA.SCHOTTKY_12(CHIPS)':
 C_PATH='@s9s_mb_2u_lib.s9s_mb_2u(sch_1):page115_i25@pure_quanta.schottky_12(chi~
ps)',
 P_PATH='@s9s_mb_2u_lib.s9s_mb_2u(sch_1):page115_i25@pure_quanta.schottky_12(chi~
ps)',
 PATH='I25',
 DRAWING='@S9S_MB_2U_LIB.S9S_MB_2U(SCH_1):PAGE115',
 PHYS_PAGE='115',
 XY='(4100,-1875)',
 ROT='0',
 VER='1',
 CDS_LIB='pure_quanta',
 CDS_PART_NAME='SCHOTTKY_12-B0530WS7F,SMLF,IC,A',
 PART_TYPE='SMLF',
 MATERIAL='IC',
 VALUE='B0530WS7F',
 PRIM_FILE='./archive_libs/logical/schottky_12/chips/chips.prt';

PART_NAME
 D49 'SCHOTTKY_12-B0530WS7F,SMLF,IC,A':;

SECTION_NUMBER 1
 '@S9S_MB_2U_LIB.S9S_MB_2U(SCH_1):PAGE115_I22@PURE_QUANTA.SCHOTTKY_12(CHIPS)':
 C_PATH='@s9s_mb_2u_lib.s9s_mb_2u(sch_1):page115_i22@pure_quanta.schottky_12(chi~
ps)',
 P_PATH='@s9s_mb_2u_lib.s9s_mb_2u(sch_1):page115_i22@pure_quanta.schottky_12(chi~
ps)',
 PATH='I22',
 DRAWING='@S9S_MB_2U_LIB.S9S_MB_2U(SCH_1):PAGE115',
 PHYS_PAGE='115',
 XY='(4100,-2500)',
 ROT='0',
 VER='1',
 CDS_LIB='pure_quanta',
 CDS_PART_NAME='SCHOTTKY_12-B0530WS7F,SMLF,IC,A',
 PART_TYPE='SMLF',
 MATERIAL='IC',
 VALUE='B0530WS7F',
 PRIM_FILE='./archive_libs/logical/schottky_12/chips/chips.prt';

PART_NAME
 D65 'Q_LED_SMLF-LED_BLUE,LTST-C281TA':;

SECTION_NUMBER 1
 '@S9S_MB_2U_LIB.S9S_MB_2U(SCH_1):PAGE304_I21@PURE_QUANTA.Q_LED(CHIPS)':
 C_PATH='@s9s_mb_2u_lib.s9s_mb_2u(sch_1):page304_i21@pure_quanta.q_led(chips)',
 P_PATH='@s9s_mb_2u_lib.s9s_mb_2u(sch_1):page256_i21@pure_quanta.q_led(chips)',
 PATH='I21',
 DRAWING='@S9S_MB_2U_LIB.S9S_MB_2U(SCH_1):PAGE304',
 COLOR='LED_BLUE',
 PHYS_PAGE='256',
 XY='(-1775,4450)',
 ROT='2',
 VER='1',
 PACK_TYPE='SMLF',
 LOCATION='D65',
 CDS_LIB='pure_quanta',
 CDS_PART_NAME='Q_LED_SMLF-LED_BLUE,LTST-C281TA',
 MANUF_PN='LTST-C281TBKT-5A',
 MATERIAL='IC',
 PRIM_FILE='./archive_libs/logical/q_led/chips/chips.prt';

PART_NAME
 D66 'Q_LED_SMLF-LED_BLUE,LTST-C281TA':;

SECTION_NUMBER 1
 '@S9S_MB_2U_LIB.S9S_MB_2U(SCH_1):PAGE304_I20@PURE_QUANTA.Q_LED(CHIPS)':
 C_PATH='@s9s_mb_2u_lib.s9s_mb_2u(sch_1):page304_i20@pure_quanta.q_led(chips)',
 P_PATH='@s9s_mb_2u_lib.s9s_mb_2u(sch_1):page256_i20@pure_quanta.q_led(chips)',
 PATH='I20',
 DRAWING='@S9S_MB_2U_LIB.S9S_MB_2U(SCH_1):PAGE304',
 COLOR='LED_BLUE',
 PHYS_PAGE='256',
 XY='(-1775,2850)',
 ROT='2',
 VER='1',
 PACK_TYPE='SMLF',
 LOCATION='D66',
 CDS_LIB='pure_quanta',
 CDS_PART_NAME='Q_LED_SMLF-LED_BLUE,LTST-C281TA',
 MANUF_PN='LTST-C281TBKT-5A',
 MATERIAL='IC',
 PRIM_FILE='./archive_libs/logical/q_led/chips/chips.prt';

PART_NAME
 D67 'Q_LED_SMLF-LED_BLUE,LTST-C281TA':;

SECTION_NUMBER 1
 '@S9S_MB_2U_LIB.S9S_MB_2U(SCH_1):PAGE304_I12@PURE_QUANTA.Q_LED(CHIPS)':
 C_PATH='@s9s_mb_2u_lib.s9s_mb_2u(sch_1):page304_i12@pure_quanta.q_led(chips)',
 P_PATH='@s9s_mb_2u_lib.s9s_mb_2u(sch_1):page256_i12@pure_quanta.q_led(chips)',
 PATH='I12',
 DRAWING='@S9S_MB_2U_LIB.S9S_MB_2U(SCH_1):PAGE304',
 COLOR='LED_BLUE',
 PHYS_PAGE='256',
 XY='(-1800,1175)',
 ROT='2',
 VER='1',
 PACK_TYPE='SMLF',
 LOCATION='D67',
 CDS_LIB='pure_quanta',
 CDS_PART_NAME='Q_LED_SMLF-LED_BLUE,LTST-C281TA',
 MANUF_PN='LTST-C281TBKT-5A',
 MATERIAL='IC',
 PRIM_FILE='./archive_libs/logical/q_led/chips/chips.prt';

PART_NAME
 D68 'Q_LED_SMLF-LED_BLUE,LTST-C281TA':;

SECTION_NUMBER 1
 '@S9S_MB_2U_LIB.S9S_MB_2U(SCH_1):PAGE304_I9@PURE_QUANTA.Q_LED(CHIPS)':
 C_PATH='@s9s_mb_2u_lib.s9s_mb_2u(sch_1):page304_i9@pure_quanta.q_led(chips)',
 P_PATH='@s9s_mb_2u_lib.s9s_mb_2u(sch_1):page256_i9@pure_quanta.q_led(chips)',
 PATH='I9',
 DRAWING='@S9S_MB_2U_LIB.S9S_MB_2U(SCH_1):PAGE304',
 COLOR='LED_BLUE',
 PHYS_PAGE='256',
 XY='(-1650,-175)',
 ROT='2',
 VER='1',
 PACK_TYPE='SMLF',
 LOCATION='D68',
 CDS_LIB='pure_quanta',
 CDS_PART_NAME='Q_LED_SMLF-LED_BLUE,LTST-C281TA',
 MANUF_PN='LTST-C281TBKT-5A',
 MATERIAL='IC',
 PRIM_FILE='./archive_libs/logical/q_led/chips/chips.prt';

PART_NAME
 D69 'Q_LED_SMLF-LED_BLUE,LTST-C281TA':;

SECTION_NUMBER 1
 '@S9S_MB_2U_LIB.S9S_MB_2U(SCH_1):PAGE304_I32@PURE_QUANTA.Q_LED(CHIPS)':
 C_PATH='@s9s_mb_2u_lib.s9s_mb_2u(sch_1):page304_i32@pure_quanta.q_led(chips)',
 P_PATH='@s9s_mb_2u_lib.s9s_mb_2u(sch_1):page256_i32@pure_quanta.q_led(chips)',
 PATH='I32',
 DRAWING='@S9S_MB_2U_LIB.S9S_MB_2U(SCH_1):PAGE304',
 COLOR='LED_BLUE',
 PHYS_PAGE='256',
 XY='(2700,4425)',
 ROT='2',
 VER='1',
 PACK_TYPE='SMLF',
 LOCATION='D69',
 CDS_LIB='pure_quanta',
 CDS_PART_NAME='Q_LED_SMLF-LED_BLUE,LTST-C281TA',
 MANUF_PN='LTST-C281TBKT-5A',
 MATERIAL='IC',
 PRIM_FILE='./archive_libs/logical/q_led/chips/chips.prt';

PART_NAME
 D70 'Q_LED_SMLF-LED_BLUE,LTST-C281TA':;

SECTION_NUMBER 1
 '@S9S_MB_2U_LIB.S9S_MB_2U(SCH_1):PAGE304_I31@PURE_QUANTA.Q_LED(CHIPS)':
 C_PATH='@s9s_mb_2u_lib.s9s_mb_2u(sch_1):page304_i31@pure_quanta.q_led(chips)',
 P_PATH='@s9s_mb_2u_lib.s9s_mb_2u(sch_1):page256_i31@pure_quanta.q_led(chips)',
 PATH='I31',
 DRAWING='@S9S_MB_2U_LIB.S9S_MB_2U(SCH_1):PAGE304',
 COLOR='LED_BLUE',
 PHYS_PAGE='256',
 XY='(2700,3000)',
 ROT='2',
 VER='1',
 PACK_TYPE='SMLF',
 LOCATION='D70',
 CDS_LIB='pure_quanta',
 CDS_PART_NAME='Q_LED_SMLF-LED_BLUE,LTST-C281TA',
 MANUF_PN='LTST-C281TBKT-5A',
 MATERIAL='IC',
 PRIM_FILE='./archive_libs/logical/q_led/chips/chips.prt';

PART_NAME
 D71 'Q_LED_SMLF-LED_BLUE,LTST-C281TA':;

SECTION_NUMBER 1
 '@S9S_MB_2U_LIB.S9S_MB_2U(SCH_1):PAGE304_I58@PURE_QUANTA.Q_LED(CHIPS)':
 C_PATH='@s9s_mb_2u_lib.s9s_mb_2u(sch_1):page304_i58@pure_quanta.q_led(chips)',
 P_PATH='@s9s_mb_2u_lib.s9s_mb_2u(sch_1):page256_i58@pure_quanta.q_led(chips)',
 PATH='I58',
 DRAWING='@S9S_MB_2U_LIB.S9S_MB_2U(SCH_1):PAGE304',
 COLOR='LED_BLUE',
 PHYS_PAGE='256',
 XY='(2725,1250)',
 ROT='2',
 VER='1',
 PACK_TYPE='SMLF',
 LOCATION='D71',
 CDS_LIB='pure_quanta',
 CDS_PART_NAME='Q_LED_SMLF-LED_BLUE,LTST-C281TA',
 MANUF_PN='LTST-C281TBKT-5A',
 MATERIAL='IC',
 PRIM_FILE='./archive_libs/logical/q_led/chips/chips.prt';

PART_NAME
 D72 'Q_LED_SMLF-LED_BLUE,LTST-C281TA':;

SECTION_NUMBER 1
 '@S9S_MB_2U_LIB.S9S_MB_2U(SCH_1):PAGE304_I63@PURE_QUANTA.Q_LED(CHIPS)':
 C_PATH='@s9s_mb_2u_lib.s9s_mb_2u(sch_1):page304_i63@pure_quanta.q_led(chips)',
 P_PATH='@s9s_mb_2u_lib.s9s_mb_2u(sch_1):page256_i63@pure_quanta.q_led(chips)',
 PATH='I63',
 DRAWING='@S9S_MB_2U_LIB.S9S_MB_2U(SCH_1):PAGE304',
 COLOR='LED_BLUE',
 PHYS_PAGE='256',
 XY='(2875,-100)',
 ROT='2',
 VER='1',
 PACK_TYPE='SMLF',
 LOCATION='D72',
 CDS_LIB='pure_quanta',
 CDS_PART_NAME='Q_LED_SMLF-LED_BLUE,LTST-C281TA',
 MANUF_PN='LTST-C281TBKT-5A',
 MATERIAL='IC',
 PRIM_FILE='./archive_libs/logical/q_led/chips/chips.prt';

PART_NAME
 D73 'Q_LED_SMLF-LED_BLUE,LTST-C281TA':;

SECTION_NUMBER 1
 '@S9S_MB_2U_LIB.S9S_MB_2U(SCH_1):PAGE305_I22@PURE_QUANTA.Q_LED(CHIPS)':
 C_PATH='@s9s_mb_2u_lib.s9s_mb_2u(sch_1):page305_i22@pure_quanta.q_led(chips)',
 P_PATH='@s9s_mb_2u_lib.s9s_mb_2u(sch_1):page253_i22@pure_quanta.q_led(chips)',
 PATH='I22',
 DRAWING='@S9S_MB_2U_LIB.S9S_MB_2U(SCH_1):PAGE305',
 COLOR='LED_BLUE',
 PHYS_PAGE='253',
 XY='(-1575,4700)',
 ROT='2',
 VER='1',
 PACK_TYPE='SMLF',
 LOCATION='D73',
 CDS_LIB='pure_quanta',
 CDS_PART_NAME='Q_LED_SMLF-LED_BLUE,LTST-C281TA',
 MANUF_PN='LTST-C281TBKT-5A',
 MATERIAL='IC',
 PRIM_FILE='./archive_libs/logical/q_led/chips/chips.prt';

PART_NAME
 D74 'Q_LED_SMLF-LED_BLUE,LTST-C281TA':;

SECTION_NUMBER 1
 '@S9S_MB_2U_LIB.S9S_MB_2U(SCH_1):PAGE305_I21@PURE_QUANTA.Q_LED(CHIPS)':
 C_PATH='@s9s_mb_2u_lib.s9s_mb_2u(sch_1):page305_i21@pure_quanta.q_led(chips)',
 P_PATH='@s9s_mb_2u_lib.s9s_mb_2u(sch_1):page253_i21@pure_quanta.q_led(chips)',
 PATH='I21',
 DRAWING='@S9S_MB_2U_LIB.S9S_MB_2U(SCH_1):PAGE305',
 COLOR='LED_BLUE',
 PHYS_PAGE='253',
 XY='(-1575,3375)',
 ROT='2',
 VER='1',
 PACK_TYPE='SMLF',
 LOCATION='D74',
 CDS_LIB='pure_quanta',
 CDS_PART_NAME='Q_LED_SMLF-LED_BLUE,LTST-C281TA',
 MANUF_PN='LTST-C281TBKT-5A',
 MATERIAL='IC',
 PRIM_FILE='./archive_libs/logical/q_led/chips/chips.prt';

PART_NAME
 D75 'Q_LED_SMLF-LED_BLUE,LTST-C281TA':;

SECTION_NUMBER 1
 '@S9S_MB_2U_LIB.S9S_MB_2U(SCH_1):PAGE305_I13@PURE_QUANTA.Q_LED(CHIPS)':
 C_PATH='@s9s_mb_2u_lib.s9s_mb_2u(sch_1):page305_i13@pure_quanta.q_led(chips)',
 P_PATH='@s9s_mb_2u_lib.s9s_mb_2u(sch_1):page253_i13@pure_quanta.q_led(chips)',
 PATH='I13',
 DRAWING='@S9S_MB_2U_LIB.S9S_MB_2U(SCH_1):PAGE305',
 COLOR='LED_BLUE',
 PHYS_PAGE='253',
 XY='(-1575,2150)',
 ROT='2',
 VER='1',
 PACK_TYPE='SMLF',
 LOCATION='D75',
 CDS_LIB='pure_quanta',
 CDS_PART_NAME='Q_LED_SMLF-LED_BLUE,LTST-C281TA',
 MANUF_PN='LTST-C281TBKT-5A',
 MATERIAL='IC',
 PRIM_FILE='./archive_libs/logical/q_led/chips/chips.prt';

PART_NAME
 D76 'Q_LED_SMLF-LED_BLUE,LTST-C281TA':;

SECTION_NUMBER 1
 '@S9S_MB_2U_LIB.S9S_MB_2U(SCH_1):PAGE305_I10@PURE_QUANTA.Q_LED(CHIPS)':
 C_PATH='@s9s_mb_2u_lib.s9s_mb_2u(sch_1):page305_i10@pure_quanta.q_led(chips)',
 P_PATH='@s9s_mb_2u_lib.s9s_mb_2u(sch_1):page253_i10@pure_quanta.q_led(chips)',
 PATH='I10',
 DRAWING='@S9S_MB_2U_LIB.S9S_MB_2U(SCH_1):PAGE305',
 COLOR='LED_BLUE',
 PHYS_PAGE='253',
 XY='(-1575,825)',
 ROT='2',
 VER='1',
 PACK_TYPE='SMLF',
 LOCATION='D76',
 CDS_LIB='pure_quanta',
 CDS_PART_NAME='Q_LED_SMLF-LED_BLUE,LTST-C281TA',
 MANUF_PN='LTST-C281TBKT-5A',
 MATERIAL='IC',
 PRIM_FILE='./archive_libs/logical/q_led/chips/chips.prt';

PART_NAME
 D77 'Q_LED_SMLF-LED_BLUE,LTST-C281TA':;

SECTION_NUMBER 1
 '@S9S_MB_2U_LIB.S9S_MB_2U(SCH_1):PAGE305_I44@PURE_QUANTA.Q_LED(CHIPS)':
 C_PATH='@s9s_mb_2u_lib.s9s_mb_2u(sch_1):page305_i44@pure_quanta.q_led(chips)',
 P_PATH='@s9s_mb_2u_lib.s9s_mb_2u(sch_1):page253_i44@pure_quanta.q_led(chips)',
 PATH='I44',
 DRAWING='@S9S_MB_2U_LIB.S9S_MB_2U(SCH_1):PAGE305',
 COLOR='LED_BLUE',
 PHYS_PAGE='253',
 XY='(3200,4700)',
 ROT='2',
 VER='1',
 PACK_TYPE='SMLF',
 LOCATION='D77',
 CDS_LIB='pure_quanta',
 CDS_PART_NAME='Q_LED_SMLF-LED_BLUE,LTST-C281TA',
 MANUF_PN='LTST-C281TBKT-5A',
 MATERIAL='IC',
 PRIM_FILE='./archive_libs/logical/q_led/chips/chips.prt';

PART_NAME
 D78 'Q_LED_SMLF-LED_BLUE,LTST-C281TA':;

SECTION_NUMBER 1
 '@S9S_MB_2U_LIB.S9S_MB_2U(SCH_1):PAGE305_I43@PURE_QUANTA.Q_LED(CHIPS)':
 C_PATH='@s9s_mb_2u_lib.s9s_mb_2u(sch_1):page305_i43@pure_quanta.q_led(chips)',
 P_PATH='@s9s_mb_2u_lib.s9s_mb_2u(sch_1):page253_i43@pure_quanta.q_led(chips)',
 PATH='I43',
 DRAWING='@S9S_MB_2U_LIB.S9S_MB_2U(SCH_1):PAGE305',
 COLOR='LED_BLUE',
 PHYS_PAGE='253',
 XY='(3200,3375)',
 ROT='2',
 VER='1',
 PACK_TYPE='SMLF',
 LOCATION='D78',
 CDS_LIB='pure_quanta',
 CDS_PART_NAME='Q_LED_SMLF-LED_BLUE,LTST-C281TA',
 MANUF_PN='LTST-C281TBKT-5A',
 MATERIAL='IC',
 PRIM_FILE='./archive_libs/logical/q_led/chips/chips.prt';

PART_NAME
 D79 'Q_LED_SMLF-LED_BLUE,LTST-C281TA':;

SECTION_NUMBER 1
 '@S9S_MB_2U_LIB.S9S_MB_2U(SCH_1):PAGE305_I35@PURE_QUANTA.Q_LED(CHIPS)':
 C_PATH='@s9s_mb_2u_lib.s9s_mb_2u(sch_1):page305_i35@pure_quanta.q_led(chips)',
 P_PATH='@s9s_mb_2u_lib.s9s_mb_2u(sch_1):page253_i35@pure_quanta.q_led(chips)',
 PATH='I35',
 DRAWING='@S9S_MB_2U_LIB.S9S_MB_2U(SCH_1):PAGE305',
 COLOR='LED_BLUE',
 PHYS_PAGE='253',
 XY='(3200,2125)',
 ROT='2',
 VER='1',
 PACK_TYPE='SMLF',
 LOCATION='D79',
 CDS_LIB='pure_quanta',
 CDS_PART_NAME='Q_LED_SMLF-LED_BLUE,LTST-C281TA',
 MANUF_PN='LTST-C281TBKT-5A',
 MATERIAL='IC',
 PRIM_FILE='./archive_libs/logical/q_led/chips/chips.prt';

PART_NAME
 D80 'Q_LED_SMLF-LED_BLUE,LTST-C281TA':;

SECTION_NUMBER 1
 '@S9S_MB_2U_LIB.S9S_MB_2U(SCH_1):PAGE306_I19@PURE_QUANTA.Q_LED(CHIPS)':
 C_PATH='@s9s_mb_2u_lib.s9s_mb_2u(sch_1):page306_i19@pure_quanta.q_led(chips)',
 P_PATH='@s9s_mb_2u_lib.s9s_mb_2u(sch_1):page254_i19@pure_quanta.q_led(chips)',
 PATH='I19',
 DRAWING='@S9S_MB_2U_LIB.S9S_MB_2U(SCH_1):PAGE306',
 COLOR='LED_BLUE',
 PHYS_PAGE='254',
 XY='(-1775,4350)',
 ROT='2',
 VER='1',
 PACK_TYPE='SMLF',
 LOCATION='D80',
 CDS_LIB='pure_quanta',
 CDS_PART_NAME='Q_LED_SMLF-LED_BLUE,LTST-C281TA',
 MANUF_PN='LTST-C281TBKT-5A',
 MATERIAL='IC',
 PRIM_FILE='./archive_libs/logical/q_led/chips/chips.prt';

PART_NAME
 D81 'Q_LED_SMLF-LED_BLUE,LTST-C281TA':;

SECTION_NUMBER 1
 '@S9S_MB_2U_LIB.S9S_MB_2U(SCH_1):PAGE306_I14@PURE_QUANTA.Q_LED(CHIPS)':
 C_PATH='@s9s_mb_2u_lib.s9s_mb_2u(sch_1):page306_i14@pure_quanta.q_led(chips)',
 P_PATH='@s9s_mb_2u_lib.s9s_mb_2u(sch_1):page254_i14@pure_quanta.q_led(chips)',
 PATH='I14',
 DRAWING='@S9S_MB_2U_LIB.S9S_MB_2U(SCH_1):PAGE306',
 COLOR='LED_BLUE',
 PHYS_PAGE='254',
 XY='(-1775,3025)',
 ROT='2',
 VER='1',
 PACK_TYPE='SMLF',
 LOCATION='D81',
 CDS_LIB='pure_quanta',
 CDS_PART_NAME='Q_LED_SMLF-LED_BLUE,LTST-C281TA',
 MANUF_PN='LTST-C281TBKT-5A',
 MATERIAL='IC',
 PRIM_FILE='./archive_libs/logical/q_led/chips/chips.prt';

PART_NAME
 D82 'Q_LED_SMLF-LED_BLUE,LTST-C281TA':;

SECTION_NUMBER 1
 '@S9S_MB_2U_LIB.S9S_MB_2U(SCH_1):PAGE306_I13@PURE_QUANTA.Q_LED(CHIPS)':
 C_PATH='@s9s_mb_2u_lib.s9s_mb_2u(sch_1):page306_i13@pure_quanta.q_led(chips)',
 P_PATH='@s9s_mb_2u_lib.s9s_mb_2u(sch_1):page254_i13@pure_quanta.q_led(chips)',
 PATH='I13',
 DRAWING='@S9S_MB_2U_LIB.S9S_MB_2U(SCH_1):PAGE306',
 COLOR='LED_BLUE',
 PHYS_PAGE='254',
 XY='(-1775,1800)',
 ROT='2',
 VER='1',
 PACK_TYPE='SMLF',
 LOCATION='D82',
 CDS_LIB='pure_quanta',
 CDS_PART_NAME='Q_LED_SMLF-LED_BLUE,LTST-C281TA',
 MANUF_PN='LTST-C281TBKT-5A',
 MATERIAL='IC',
 PRIM_FILE='./archive_libs/logical/q_led/chips/chips.prt';

PART_NAME
 D83 'Q_LED_SMLF-LED_BLUE,LTST-C281TA':;

SECTION_NUMBER 1
 '@S9S_MB_2U_LIB.S9S_MB_2U(SCH_1):PAGE306_I11@PURE_QUANTA.Q_LED(CHIPS)':
 C_PATH='@s9s_mb_2u_lib.s9s_mb_2u(sch_1):page306_i11@pure_quanta.q_led(chips)',
 P_PATH='@s9s_mb_2u_lib.s9s_mb_2u(sch_1):page254_i11@pure_quanta.q_led(chips)',
 PATH='I11',
 DRAWING='@S9S_MB_2U_LIB.S9S_MB_2U(SCH_1):PAGE306',
 COLOR='LED_BLUE',
 PHYS_PAGE='254',
 XY='(-1775,475)',
 ROT='2',
 VER='1',
 PACK_TYPE='SMLF',
 LOCATION='D83',
 CDS_LIB='pure_quanta',
 CDS_PART_NAME='Q_LED_SMLF-LED_BLUE,LTST-C281TA',
 MANUF_PN='LTST-C281TBKT-5A',
 MATERIAL='IC',
 PRIM_FILE='./archive_libs/logical/q_led/chips/chips.prt';

PART_NAME
 D84 'Q_LED_SMLF-LED_BLUE,LTST-C281TA':;

SECTION_NUMBER 1
 '@S9S_MB_2U_LIB.S9S_MB_2U(SCH_1):PAGE306_I36@PURE_QUANTA.Q_LED(CHIPS)':
 C_PATH='@s9s_mb_2u_lib.s9s_mb_2u(sch_1):page306_i36@pure_quanta.q_led(chips)',
 P_PATH='@s9s_mb_2u_lib.s9s_mb_2u(sch_1):page254_i36@pure_quanta.q_led(chips)',
 PATH='I36',
 DRAWING='@S9S_MB_2U_LIB.S9S_MB_2U(SCH_1):PAGE306',
 COLOR='LED_BLUE',
 PHYS_PAGE='254',
 XY='(3000,4350)',
 ROT='2',
 VER='1',
 PACK_TYPE='SMLF',
 LOCATION='D84',
 CDS_LIB='pure_quanta',
 CDS_PART_NAME='Q_LED_SMLF-LED_BLUE,LTST-C281TA',
 MANUF_PN='LTST-C281TBKT-5A',
 MATERIAL='IC',
 PRIM_FILE='./archive_libs/logical/q_led/chips/chips.prt';

PART_NAME
 D85 'Q_LED_SMLF-LED_BLUE,LTST-C281TA':;

SECTION_NUMBER 1
 '@S9S_MB_2U_LIB.S9S_MB_2U(SCH_1):PAGE306_I32@PURE_QUANTA.Q_LED(CHIPS)':
 C_PATH='@s9s_mb_2u_lib.s9s_mb_2u(sch_1):page306_i32@pure_quanta.q_led(chips)',
 P_PATH='@s9s_mb_2u_lib.s9s_mb_2u(sch_1):page254_i32@pure_quanta.q_led(chips)',
 PATH='I32',
 DRAWING='@S9S_MB_2U_LIB.S9S_MB_2U(SCH_1):PAGE306',
 COLOR='LED_BLUE',
 PHYS_PAGE='254',
 XY='(3000,3025)',
 ROT='2',
 VER='1',
 PACK_TYPE='SMLF',
 LOCATION='D85',
 CDS_LIB='pure_quanta',
 CDS_PART_NAME='Q_LED_SMLF-LED_BLUE,LTST-C281TA',
 MANUF_PN='LTST-C281TBKT-5A',
 MATERIAL='IC',
 PRIM_FILE='./archive_libs/logical/q_led/chips/chips.prt';

PART_NAME
 D86 'Q_LED_SMLF-LED_BLUE,LTST-C281TA':;

SECTION_NUMBER 1
 '@S9S_MB_2U_LIB.S9S_MB_2U(SCH_1):PAGE306_I30@PURE_QUANTA.Q_LED(CHIPS)':
 C_PATH='@s9s_mb_2u_lib.s9s_mb_2u(sch_1):page306_i30@pure_quanta.q_led(chips)',
 P_PATH='@s9s_mb_2u_lib.s9s_mb_2u(sch_1):page254_i30@pure_quanta.q_led(chips)',
 PATH='I30',
 DRAWING='@S9S_MB_2U_LIB.S9S_MB_2U(SCH_1):PAGE306',
 COLOR='LED_BLUE',
 PHYS_PAGE='254',
 XY='(3000,1775)',
 ROT='2',
 VER='1',
 PACK_TYPE='SMLF',
 LOCATION='D86',
 CDS_LIB='pure_quanta',
 CDS_PART_NAME='Q_LED_SMLF-LED_BLUE,LTST-C281TA',
 MANUF_PN='LTST-C281TBKT-5A',
 MATERIAL='IC',
 PRIM_FILE='./archive_libs/logical/q_led/chips/chips.prt';

PART_NAME
 D87 'Q_LED_SMLF-LED_BLUE,LTST-C281TA':;

SECTION_NUMBER 1
 '@S9S_MB_2U_LIB.S9S_MB_2U(SCH_1):PAGE241_I20@PURE_QUANTA.Q_LED(CHIPS)':
 C_PATH='@s9s_mb_2u_lib.s9s_mb_2u(sch_1):page241_i20@pure_quanta.q_led(chips)',
 P_PATH='@s9s_mb_2u_lib.s9s_mb_2u(sch_1):page255_i20@pure_quanta.q_led(chips)',
 PATH='I20',
 DRAWING='@S9S_MB_2U_LIB.S9S_MB_2U(SCH_1):PAGE241',
 COLOR='LED_BLUE',
 PHYS_PAGE='255',
 XY='(-12425,3350)',
 ROT='2',
 VER='1',
 PACK_TYPE='SMLF',
 LOCATION='D87',
 CDS_LIB='pure_quanta',
 CDS_PART_NAME='Q_LED_SMLF-LED_BLUE,LTST-C281TA',
 MANUF_PN='LTST-C281TBKT-5A',
 MATERIAL='IC',
 PRIM_FILE='./archive_libs/logical/q_led/chips/chips.prt';

PART_NAME
 D88 'Q_LED_SMLF-LED_BLUE,LTST-C281TA':;

SECTION_NUMBER 1
 '@S9S_MB_2U_LIB.S9S_MB_2U(SCH_1):PAGE241_I19@PURE_QUANTA.Q_LED(CHIPS)':
 C_PATH='@s9s_mb_2u_lib.s9s_mb_2u(sch_1):page241_i19@pure_quanta.q_led(chips)',
 P_PATH='@s9s_mb_2u_lib.s9s_mb_2u(sch_1):page255_i19@pure_quanta.q_led(chips)',
 PATH='I19',
 DRAWING='@S9S_MB_2U_LIB.S9S_MB_2U(SCH_1):PAGE241',
 COLOR='LED_BLUE',
 PHYS_PAGE='255',
 XY='(-12425,2075)',
 ROT='2',
 VER='1',
 PACK_TYPE='SMLF',
 LOCATION='D88',
 CDS_LIB='pure_quanta',
 CDS_PART_NAME='Q_LED_SMLF-LED_BLUE,LTST-C281TA',
 MANUF_PN='LTST-C281TBKT-5A',
 MATERIAL='IC',
 PRIM_FILE='./archive_libs/logical/q_led/chips/chips.prt';

PART_NAME
 D89 'Q_LED_SMLF-LED_BLUE,LTST-C281TA':;

SECTION_NUMBER 1
 '@S9S_MB_2U_LIB.S9S_MB_2U(SCH_1):PAGE241_I11@PURE_QUANTA.Q_LED(CHIPS)':
 C_PATH='@s9s_mb_2u_lib.s9s_mb_2u(sch_1):page241_i11@pure_quanta.q_led(chips)',
 P_PATH='@s9s_mb_2u_lib.s9s_mb_2u(sch_1):page255_i11@pure_quanta.q_led(chips)',
 PATH='I11',
 DRAWING='@S9S_MB_2U_LIB.S9S_MB_2U(SCH_1):PAGE241',
 COLOR='LED_BLUE',
 PHYS_PAGE='255',
 XY='(-12375,700)',
 ROT='2',
 VER='1',
 PACK_TYPE='SMLF',
 LOCATION='D89',
 CDS_LIB='pure_quanta',
 CDS_PART_NAME='Q_LED_SMLF-LED_BLUE,LTST-C281TA',
 MANUF_PN='LTST-C281TBKT-5A',
 MATERIAL='IC',
 PRIM_FILE='./archive_libs/logical/q_led/chips/chips.prt';

PART_NAME
 D90 'Q_LED_SMLF-LED_BLUE,LTST-C281TA':;

SECTION_NUMBER 1
 '@S9S_MB_2U_LIB.S9S_MB_2U(SCH_1):PAGE241_I33@PURE_QUANTA.Q_LED(CHIPS)':
 C_PATH='@s9s_mb_2u_lib.s9s_mb_2u(sch_1):page241_i33@pure_quanta.q_led(chips)',
 P_PATH='@s9s_mb_2u_lib.s9s_mb_2u(sch_1):page255_i33@pure_quanta.q_led(chips)',
 PATH='I33',
 DRAWING='@S9S_MB_2U_LIB.S9S_MB_2U(SCH_1):PAGE241',
 COLOR='LED_BLUE',
 PHYS_PAGE='255',
 XY='(-12350,-750)',
 ROT='2',
 VER='1',
 PACK_TYPE='SMLF',
 LOCATION='D90',
 CDS_LIB='pure_quanta',
 CDS_PART_NAME='Q_LED_SMLF-LED_BLUE,LTST-C281TA',
 MANUF_PN='LTST-C281TBKT-5A',
 MATERIAL='IC',
 PRIM_FILE='./archive_libs/logical/q_led/chips/chips.prt';

PART_NAME
 D91 'Q_LED_SMLF-LED_BLUE,LTST-C281TA':;

SECTION_NUMBER 1
 '@S9S_MB_2U_LIB.S9S_MB_2U(SCH_1):PAGE242_I18@PURE_QUANTA.Q_LED(CHIPS)':
 C_PATH='@s9s_mb_2u_lib.s9s_mb_2u(sch_1):page242_i18@pure_quanta.q_led(chips)',
 P_PATH='@s9s_mb_2u_lib.s9s_mb_2u(sch_1):page252_i18@pure_quanta.q_led(chips)',
 PATH='I18',
 DRAWING='@S9S_MB_2U_LIB.S9S_MB_2U(SCH_1):PAGE242',
 COLOR='LED_BLUE',
 PHYS_PAGE='252',
 XY='(-4750,8450)',
 ROT='2',
 VER='1',
 PACK_TYPE='SMLF',
 LOCATION='D91',
 CDS_LIB='pure_quanta',
 CDS_PART_NAME='Q_LED_SMLF-LED_BLUE,LTST-C281TA',
 MANUF_PN='LTST-C281TBKT-5A',
 MATERIAL='IC',
 PRIM_FILE='./archive_libs/logical/q_led/chips/chips.prt';

PART_NAME
 D92 'Q_LED_SMLF-LED_BLUE,LTST-C281TA':;

SECTION_NUMBER 1
 '@S9S_MB_2U_LIB.S9S_MB_2U(SCH_1):PAGE242_I42@PURE_QUANTA.Q_LED(CHIPS)':
 C_PATH='@s9s_mb_2u_lib.s9s_mb_2u(sch_1):page242_i42@pure_quanta.q_led(chips)',
 P_PATH='@s9s_mb_2u_lib.s9s_mb_2u(sch_1):page252_i42@pure_quanta.q_led(chips)',
 PATH='I42',
 DRAWING='@S9S_MB_2U_LIB.S9S_MB_2U(SCH_1):PAGE242',
 COLOR='LED_BLUE',
 PHYS_PAGE='252',
 XY='(-4750,7125)',
 ROT='2',
 VER='1',
 PACK_TYPE='SMLF',
 LOCATION='D92',
 CDS_LIB='pure_quanta',
 CDS_PART_NAME='Q_LED_SMLF-LED_BLUE,LTST-C281TA',
 MANUF_PN='LTST-C281TBKT-5A',
 MATERIAL='IC',
 PRIM_FILE='./archive_libs/logical/q_led/chips/chips.prt';

PART_NAME
 D93 'Q_LED_SMLF-LED_BLUE,LTST-C281TA':;

SECTION_NUMBER 1
 '@S9S_MB_2U_LIB.S9S_MB_2U(SCH_1):PAGE242_I13@PURE_QUANTA.Q_LED(CHIPS)':
 C_PATH='@s9s_mb_2u_lib.s9s_mb_2u(sch_1):page242_i13@pure_quanta.q_led(chips)',
 P_PATH='@s9s_mb_2u_lib.s9s_mb_2u(sch_1):page252_i13@pure_quanta.q_led(chips)',
 PATH='I13',
 DRAWING='@S9S_MB_2U_LIB.S9S_MB_2U(SCH_1):PAGE242',
 COLOR='LED_BLUE',
 PHYS_PAGE='252',
 XY='(-4750,5900)',
 ROT='2',
 VER='1',
 PACK_TYPE='SMLF',
 LOCATION='D93',
 CDS_LIB='pure_quanta',
 CDS_PART_NAME='Q_LED_SMLF-LED_BLUE,LTST-C281TA',
 MANUF_PN='LTST-C281TBKT-5A',
 MATERIAL='IC',
 PRIM_FILE='./archive_libs/logical/q_led/chips/chips.prt';

PART_NAME
 D94 'Q_LED_SMLF-LED_BLUE,LTST-C281TA':;

SECTION_NUMBER 1
 '@S9S_MB_2U_LIB.S9S_MB_2U(SCH_1):PAGE242_I11@PURE_QUANTA.Q_LED(CHIPS)':
 C_PATH='@s9s_mb_2u_lib.s9s_mb_2u(sch_1):page242_i11@pure_quanta.q_led(chips)',
 P_PATH='@s9s_mb_2u_lib.s9s_mb_2u(sch_1):page252_i11@pure_quanta.q_led(chips)',
 PATH='I11',
 DRAWING='@S9S_MB_2U_LIB.S9S_MB_2U(SCH_1):PAGE242',
 COLOR='LED_BLUE',
 PHYS_PAGE='252',
 XY='(-4725,4575)',
 ROT='2',
 VER='1',
 PACK_TYPE='SMLF',
 LOCATION='D94',
 CDS_LIB='pure_quanta',
 CDS_PART_NAME='Q_LED_SMLF-LED_BLUE,LTST-C281TA',
 MANUF_PN='LTST-C281TBKT-5A',
 MATERIAL='IC',
 PRIM_FILE='./archive_libs/logical/q_led/chips/chips.prt';

PART_NAME
 D95 'Q_LED_SMLF-LED_BLUE,LTST-C281TA':;

SECTION_NUMBER 1
 '@S9S_MB_2U_LIB.S9S_MB_2U(SCH_1):PAGE242_I35@PURE_QUANTA.Q_LED(CHIPS)':
 C_PATH='@s9s_mb_2u_lib.s9s_mb_2u(sch_1):page242_i35@pure_quanta.q_led(chips)',
 P_PATH='@s9s_mb_2u_lib.s9s_mb_2u(sch_1):page252_i35@pure_quanta.q_led(chips)',
 PATH='I35',
 DRAWING='@S9S_MB_2U_LIB.S9S_MB_2U(SCH_1):PAGE242',
 COLOR='LED_BLUE',
 PHYS_PAGE='252',
 XY='(25,8450)',
 ROT='2',
 VER='1',
 PACK_TYPE='SMLF',
 LOCATION='D95',
 CDS_LIB='pure_quanta',
 CDS_PART_NAME='Q_LED_SMLF-LED_BLUE,LTST-C281TA',
 MANUF_PN='LTST-C281TBKT-5A',
 MATERIAL='IC',
 PRIM_FILE='./archive_libs/logical/q_led/chips/chips.prt';

PART_NAME
 D96 'Q_LED_SMLF-LED_BLUE,LTST-C281TA':;

SECTION_NUMBER 1
 '@S9S_MB_2U_LIB.S9S_MB_2U(SCH_1):PAGE242_I31@PURE_QUANTA.Q_LED(CHIPS)':
 C_PATH='@s9s_mb_2u_lib.s9s_mb_2u(sch_1):page242_i31@pure_quanta.q_led(chips)',
 P_PATH='@s9s_mb_2u_lib.s9s_mb_2u(sch_1):page252_i31@pure_quanta.q_led(chips)',
 PATH='I31',
 DRAWING='@S9S_MB_2U_LIB.S9S_MB_2U(SCH_1):PAGE242',
 COLOR='LED_BLUE',
 PHYS_PAGE='252',
 XY='(25,7125)',
 ROT='2',
 VER='1',
 PACK_TYPE='SMLF',
 LOCATION='D96',
 CDS_LIB='pure_quanta',
 CDS_PART_NAME='Q_LED_SMLF-LED_BLUE,LTST-C281TA',
 MANUF_PN='LTST-C281TBKT-5A',
 MATERIAL='IC',
 PRIM_FILE='./archive_libs/logical/q_led/chips/chips.prt';

PART_NAME
 D97 'Q_LED_SMLF-LED_BLUE,LTST-C281TA':;

SECTION_NUMBER 1
 '@S9S_MB_2U_LIB.S9S_MB_2U(SCH_1):PAGE242_I52@PURE_QUANTA.Q_LED(CHIPS)':
 C_PATH='@s9s_mb_2u_lib.s9s_mb_2u(sch_1):page242_i52@pure_quanta.q_led(chips)',
 P_PATH='@s9s_mb_2u_lib.s9s_mb_2u(sch_1):page252_i52@pure_quanta.q_led(chips)',
 PATH='I52',
 DRAWING='@S9S_MB_2U_LIB.S9S_MB_2U(SCH_1):PAGE242',
 COLOR='LED_BLUE',
 PHYS_PAGE='252',
 XY='(-1125,5750)',
 ROT='2',
 VER='1',
 PACK_TYPE='SMLF',
 LOCATION='D97',
 CDS_LIB='pure_quanta',
 CDS_PART_NAME='Q_LED_SMLF-LED_BLUE,LTST-C281TA',
 MANUF_PN='LTST-C281TBKT-5A',
 MATERIAL='IC',
 PRIM_FILE='./archive_libs/logical/q_led/chips/chips.prt';

PART_NAME
 D98 'Q_LED_SMLF-LED_BLUE,LTST-C281TA':;

SECTION_NUMBER 1
 '@S9S_MB_2U_LIB.S9S_MB_2U(SCH_1):PAGE242_I53@PURE_QUANTA.Q_LED(CHIPS)':
 C_PATH='@s9s_mb_2u_lib.s9s_mb_2u(sch_1):page242_i53@pure_quanta.q_led(chips)',
 P_PATH='@s9s_mb_2u_lib.s9s_mb_2u(sch_1):page252_i53@pure_quanta.q_led(chips)',
 PATH='I53',
 DRAWING='@S9S_MB_2U_LIB.S9S_MB_2U(SCH_1):PAGE242',
 COLOR='LED_BLUE',
 PHYS_PAGE='252',
 XY='(-1100,4625)',
 ROT='2',
 VER='1',
 PACK_TYPE='SMLF',
 LOCATION='D98',
 CDS_LIB='pure_quanta',
 CDS_PART_NAME='Q_LED_SMLF-LED_BLUE,LTST-C281TA',
 MANUF_PN='LTST-C281TBKT-5A',
 MATERIAL='IC',
 PRIM_FILE='./archive_libs/logical/q_led/chips/chips.prt';

PART_NAME
 D99 'Q_LED_SMLF-LED_BLUE,LTST-C281TA':;

SECTION_NUMBER 1
 '@S9S_MB_2U_LIB.S9S_MB_2U(SCH_1):PAGE242_I60@PURE_QUANTA.Q_LED(CHIPS)':
 C_PATH='@s9s_mb_2u_lib.s9s_mb_2u(sch_1):page242_i60@pure_quanta.q_led(chips)',
 P_PATH='@s9s_mb_2u_lib.s9s_mb_2u(sch_1):page252_i60@pure_quanta.q_led(chips)',
 PATH='I60',
 DRAWING='@S9S_MB_2U_LIB.S9S_MB_2U(SCH_1):PAGE242',
 COLOR='LED_BLUE',
 PHYS_PAGE='252',
 XY='(-1175,3400)',
 ROT='2',
 VER='1',
 PACK_TYPE='SMLF',
 LOCATION='D99',
 CDS_LIB='pure_quanta',
 CDS_PART_NAME='Q_LED_SMLF-LED_BLUE,LTST-C281TA',
 MANUF_PN='LTST-C281TBKT-5A',
 MATERIAL='IC',
 PRIM_FILE='./archive_libs/logical/q_led/chips/chips.prt';

PART_NAME
 D141 'SCHOTTKY_12-1N5819HW,SMLF,IC,BA':;

SECTION_NUMBER 1
 '@S9S_MB_2U_LIB.S9S_MB_2U(SCH_1):PAGE210_I91@PURE_QUANTA.SCHOTTKY_12(CHIPS)':
 C_PATH='@s9s_mb_2u_lib.s9s_mb_2u(sch_1):page210_i91@pure_quanta.schottky_12(chi~
ps)',
 P_PATH='@s9s_mb_2u_lib.s9s_mb_2u(sch_1):page221_i91@pure_quanta.schottky_12(chi~
ps)',
 PATH='I91',
 DRAWING='@S9S_MB_2U_LIB.S9S_MB_2U(SCH_1):PAGE210',
 PHYS_PAGE='221',
 XY='(-1925,1575)',
 ROT='0',
 VER='1',
 CDS_LIB='pure_quanta',
 CDS_PART_NAME='SCHOTTKY_12-1N5819HW,SMLF,IC,BA',
 PART_TYPE='SMLF',
 MATERIAL='IC',
 VALUE='1N5819HW',
 PRIM_FILE='./archive_libs/logical/schottky_12/chips/chips.prt';

PART_NAME
 D142 'Q_LED_SMLF-LED_BLUE,LTST-C281TA':;

SECTION_NUMBER 1
 '@S9S_MB_2U_LIB.S9S_MB_2U(SCH_1):PAGE241_I58@PURE_QUANTA.Q_LED(CHIPS)':
 C_PATH='@s9s_mb_2u_lib.s9s_mb_2u(sch_1):page241_i58@pure_quanta.q_led(chips)',
 P_PATH='@s9s_mb_2u_lib.s9s_mb_2u(sch_1):page255_i58@pure_quanta.q_led(chips)',
 PATH='I58',
 DRAWING='@S9S_MB_2U_LIB.S9S_MB_2U(SCH_1):PAGE241',
 COLOR='LED_BLUE',
 PHYS_PAGE='255',
 XY='(-9125,3400)',
 ROT='2',
 VER='1',
 PACK_TYPE='SMLF',
 CDS_LIB='pure_quanta',
 CDS_PART_NAME='Q_LED_SMLF-LED_BLUE,LTST-C281TA',
 MANUF_PN='LTST-C281TBKT-5A',
 MATERIAL='IC',
 PRIM_FILE='./archive_libs/logical/q_led/chips/chips.prt';

PART_NAME
 D143 'Q_LED_SMLF-LED_BLUE,LTST-C281TA':;

SECTION_NUMBER 1
 '@S9S_MB_2U_LIB.S9S_MB_2U(SCH_1):PAGE241_I49@PURE_QUANTA.Q_LED(CHIPS)':
 C_PATH='@s9s_mb_2u_lib.s9s_mb_2u(sch_1):page241_i49@pure_quanta.q_led(chips)',
 P_PATH='@s9s_mb_2u_lib.s9s_mb_2u(sch_1):page255_i49@pure_quanta.q_led(chips)',
 PATH='I49',
 DRAWING='@S9S_MB_2U_LIB.S9S_MB_2U(SCH_1):PAGE241',
 COLOR='LED_BLUE',
 PHYS_PAGE='255',
 XY='(-9125,2150)',
 ROT='2',
 VER='1',
 PACK_TYPE='SMLF',
 CDS_LIB='pure_quanta',
 CDS_PART_NAME='Q_LED_SMLF-LED_BLUE,LTST-C281TA',
 MANUF_PN='LTST-C281TBKT-5A',
 MATERIAL='IC',
 PRIM_FILE='./archive_libs/logical/q_led/chips/chips.prt';

PART_NAME
 D144 'Q_LED_SMLF-LED_YELLOW,LTST-C19A':;

SECTION_NUMBER 1
 '@S9S_MB_2U_LIB.S9S_MB_2U(SCH_1):PAGE241_I67@PURE_QUANTA.Q_LED(CHIPS)':
 C_PATH='@s9s_mb_2u_lib.s9s_mb_2u(sch_1):page241_i67@pure_quanta.q_led(chips)',
 P_PATH='@s9s_mb_2u_lib.s9s_mb_2u(sch_1):page255_i67@pure_quanta.q_led(chips)',
 PATH='I67',
 DRAWING='@S9S_MB_2U_LIB.S9S_MB_2U(SCH_1):PAGE241',
 COLOR='LED_YELLOW',
 PHYS_PAGE='255',
 XY='(-7500,425)',
 ROT='2',
 VER='1',
 PACK_TYPE='SMLF',
 CDS_LIB='pure_quanta',
 CDS_PART_NAME='Q_LED_SMLF-LED_YELLOW,LTST-C19A',
 MANUF_PN='LTST-C190KSKT-P',
 MATERIAL='IC',
 PRIM_FILE='./archive_libs/logical/q_led/chips/chips.prt';

PART_NAME
 D145 'Q_DIODE_SMLF-SDMK0340L-7-F,IC,A':;

SECTION_NUMBER 1
 '@S9S_MB_2U_LIB.S9S_MB_2U(SCH_1):PAGE245_I71@PURE_QUANTA.Q_DIODE(CHIPS)':
 C_PATH='@s9s_mb_2u_lib.s9s_mb_2u(sch_1):page245_i71@pure_quanta.q_diode(chips)',
 P_PATH='@s9s_mb_2u_lib.s9s_mb_2u(sch_1):page259_i71@pure_quanta.q_diode(chips)',
 PATH='I71',
 DRAWING='@S9S_MB_2U_LIB.S9S_MB_2U(SCH_1):PAGE245',
 PIN_NAMES_ROTATE='True',
 PHYS_PAGE='259',
 XY='(-3025,-775)',
 ROT='0',
 VER='1',
 PACK_TYPE='SMLF',
 CDS_LIB='pure_quanta',
 CDS_PART_NAME='Q_DIODE_SMLF-SDMK0340L-7-F,IC,A',
 MATERIAL='IC',
 VALUE='SDMK0340L-7-F',
 PRIM_FILE='./archive_libs/logical/q_diode/chips/chips.prt';

PART_NAME
 DB1 'TDR_3P_TH2-EMPTY,N_A':;

SECTION_NUMBER 1
 '@S9S_MB_2U_LIB.S9S_MB_2U(SCH_1):PAGE288_I61@PURE_QUANTA.TDR_3P(CHIPS)':
 C_PATH='@s9s_mb_2u_lib.s9s_mb_2u(sch_1):page288_i61@pure_quanta.tdr_3p(chips)',
 P_PATH='@s9s_mb_2u_lib.s9s_mb_2u(sch_1):page309_i61@pure_quanta.tdr_3p(chips)',
 PATH='I61',
 DRAWING='@S9S_MB_2U_LIB.S9S_MB_2U(SCH_1):PAGE288',
 PHYS_PAGE='309',
 XY='(-2850,4275)',
 ROT='0',
 VER='2',
 PACK_TYPE='TH2',
 CDS_LIB='pure_quanta',
 CDS_PART_NAME='TDR_3P_TH2-EMPTY,N_A',
 MATERIAL='EMPTY',
 PRIM_FILE='./archive_libs/logical/tdr_3p/chips/chips.prt';

PART_NAME
 DB2 'TDR_3P_TH2-EMPTY,N_A':;

SECTION_NUMBER 1
 '@S9S_MB_2U_LIB.S9S_MB_2U(SCH_1):PAGE288_I62@PURE_QUANTA.TDR_3P(CHIPS)':
 C_PATH='@s9s_mb_2u_lib.s9s_mb_2u(sch_1):page288_i62@pure_quanta.tdr_3p(chips)',
 P_PATH='@s9s_mb_2u_lib.s9s_mb_2u(sch_1):page309_i62@pure_quanta.tdr_3p(chips)',
 PATH='I62',
 DRAWING='@S9S_MB_2U_LIB.S9S_MB_2U(SCH_1):PAGE288',
 PHYS_PAGE='309',
 XY='(-2850,3750)',
 ROT='0',
 VER='2',
 PACK_TYPE='TH2',
 CDS_LIB='pure_quanta',
 CDS_PART_NAME='TDR_3P_TH2-EMPTY,N_A',
 MATERIAL='EMPTY',
 PRIM_FILE='./archive_libs/logical/tdr_3p/chips/chips.prt';

PART_NAME
 DB3 'TDR_3P_TH2-EMPTY,N_A':;

SECTION_NUMBER 1
 '@S9S_MB_2U_LIB.S9S_MB_2U(SCH_1):PAGE288_I63@PURE_QUANTA.TDR_3P(CHIPS)':
 C_PATH='@s9s_mb_2u_lib.s9s_mb_2u(sch_1):page288_i63@pure_quanta.tdr_3p(chips)',
 P_PATH='@s9s_mb_2u_lib.s9s_mb_2u(sch_1):page309_i63@pure_quanta.tdr_3p(chips)',
 PATH='I63',
 DRAWING='@S9S_MB_2U_LIB.S9S_MB_2U(SCH_1):PAGE288',
 PHYS_PAGE='309',
 XY='(-2850,3225)',
 ROT='0',
 VER='2',
 PACK_TYPE='TH2',
 CDS_LIB='pure_quanta',
 CDS_PART_NAME='TDR_3P_TH2-EMPTY,N_A',
 MATERIAL='EMPTY',
 PRIM_FILE='./archive_libs/logical/tdr_3p/chips/chips.prt';

PART_NAME
 DB4 'TDR_3P_TH2-EMPTY,N_A':;

SECTION_NUMBER 1
 '@S9S_MB_2U_LIB.S9S_MB_2U(SCH_1):PAGE288_I67@PURE_QUANTA.TDR_3P(CHIPS)':
 C_PATH='@s9s_mb_2u_lib.s9s_mb_2u(sch_1):page288_i67@pure_quanta.tdr_3p(chips)',
 P_PATH='@s9s_mb_2u_lib.s9s_mb_2u(sch_1):page309_i67@pure_quanta.tdr_3p(chips)',
 PATH='I67',
 DRAWING='@S9S_MB_2U_LIB.S9S_MB_2U(SCH_1):PAGE288',
 PHYS_PAGE='309',
 XY='(-2850,2700)',
 ROT='0',
 VER='2',
 PACK_TYPE='TH2',
 CDS_LIB='pure_quanta',
 CDS_PART_NAME='TDR_3P_TH2-EMPTY,N_A',
 MATERIAL='EMPTY',
 PRIM_FILE='./archive_libs/logical/tdr_3p/chips/chips.prt';

PART_NAME
 DB5 'TDR_3P_TH2-EMPTY,N_A':;

SECTION_NUMBER 1
 '@S9S_MB_2U_LIB.S9S_MB_2U(SCH_1):PAGE288_I68@PURE_QUANTA.TDR_3P(CHIPS)':
 C_PATH='@s9s_mb_2u_lib.s9s_mb_2u(sch_1):page288_i68@pure_quanta.tdr_3p(chips)',
 P_PATH='@s9s_mb_2u_lib.s9s_mb_2u(sch_1):page309_i68@pure_quanta.tdr_3p(chips)',
 PATH='I68',
 DRAWING='@S9S_MB_2U_LIB.S9S_MB_2U(SCH_1):PAGE288',
 PHYS_PAGE='309',
 XY='(-2850,2175)',
 ROT='0',
 VER='2',
 PACK_TYPE='TH2',
 CDS_LIB='pure_quanta',
 CDS_PART_NAME='TDR_3P_TH2-EMPTY,N_A',
 MATERIAL='EMPTY',
 PRIM_FILE='./archive_libs/logical/tdr_3p/chips/chips.prt';

PART_NAME
 DB6 'TDR_3P_TH2-EMPTY,N_A':;

SECTION_NUMBER 1
 '@S9S_MB_2U_LIB.S9S_MB_2U(SCH_1):PAGE288_I69@PURE_QUANTA.TDR_3P(CHIPS)':
 C_PATH='@s9s_mb_2u_lib.s9s_mb_2u(sch_1):page288_i69@pure_quanta.tdr_3p(chips)',
 P_PATH='@s9s_mb_2u_lib.s9s_mb_2u(sch_1):page309_i69@pure_quanta.tdr_3p(chips)',
 PATH='I69',
 DRAWING='@S9S_MB_2U_LIB.S9S_MB_2U(SCH_1):PAGE288',
 PHYS_PAGE='309',
 XY='(-2900,575)',
 ROT='0',
 VER='2',
 PACK_TYPE='TH2',
 CDS_LIB='pure_quanta',
 CDS_PART_NAME='TDR_3P_TH2-EMPTY,N_A',
 MATERIAL='EMPTY',
 PRIM_FILE='./archive_libs/logical/tdr_3p/chips/chips.prt';

PART_NAME
 DB7 'TDR_3P_TH2-EMPTY,N_A':;

SECTION_NUMBER 1
 '@S9S_MB_2U_LIB.S9S_MB_2U(SCH_1):PAGE288_I49@PURE_QUANTA.TDR_3P(CHIPS)':
 C_PATH='@s9s_mb_2u_lib.s9s_mb_2u(sch_1):page288_i49@pure_quanta.tdr_3p(chips)',
 P_PATH='@s9s_mb_2u_lib.s9s_mb_2u(sch_1):page309_i49@pure_quanta.tdr_3p(chips)',
 PATH='I49',
 DRAWING='@S9S_MB_2U_LIB.S9S_MB_2U(SCH_1):PAGE288',
 PHYS_PAGE='309',
 XY='(-1150,4275)',
 ROT='0',
 VER='2',
 PACK_TYPE='TH2',
 CDS_LIB='pure_quanta',
 CDS_PART_NAME='TDR_3P_TH2-EMPTY,N_A',
 MATERIAL='EMPTY',
 PRIM_FILE='./archive_libs/logical/tdr_3p/chips/chips.prt';

PART_NAME
 DB8 'TDR_3P_TH2-EMPTY,N_A':;

SECTION_NUMBER 1
 '@S9S_MB_2U_LIB.S9S_MB_2U(SCH_1):PAGE288_I51@PURE_QUANTA.TDR_3P(CHIPS)':
 C_PATH='@s9s_mb_2u_lib.s9s_mb_2u(sch_1):page288_i51@pure_quanta.tdr_3p(chips)',
 P_PATH='@s9s_mb_2u_lib.s9s_mb_2u(sch_1):page309_i51@pure_quanta.tdr_3p(chips)',
 PATH='I51',
 DRAWING='@S9S_MB_2U_LIB.S9S_MB_2U(SCH_1):PAGE288',
 PHYS_PAGE='309',
 XY='(-1150,3750)',
 ROT='0',
 VER='2',
 PACK_TYPE='TH2',
 CDS_LIB='pure_quanta',
 CDS_PART_NAME='TDR_3P_TH2-EMPTY,N_A',
 MATERIAL='EMPTY',
 PRIM_FILE='./archive_libs/logical/tdr_3p/chips/chips.prt';

PART_NAME
 DB9 'TDR_3P_TH2-EMPTY,N_A':;

SECTION_NUMBER 1
 '@S9S_MB_2U_LIB.S9S_MB_2U(SCH_1):PAGE288_I53@PURE_QUANTA.TDR_3P(CHIPS)':
 C_PATH='@s9s_mb_2u_lib.s9s_mb_2u(sch_1):page288_i53@pure_quanta.tdr_3p(chips)',
 P_PATH='@s9s_mb_2u_lib.s9s_mb_2u(sch_1):page309_i53@pure_quanta.tdr_3p(chips)',
 PATH='I53',
 DRAWING='@S9S_MB_2U_LIB.S9S_MB_2U(SCH_1):PAGE288',
 PHYS_PAGE='309',
 XY='(-1150,3225)',
 ROT='0',
 VER='2',
 PACK_TYPE='TH2',
 CDS_LIB='pure_quanta',
 CDS_PART_NAME='TDR_3P_TH2-EMPTY,N_A',
 MATERIAL='EMPTY',
 PRIM_FILE='./archive_libs/logical/tdr_3p/chips/chips.prt';

PART_NAME
 DB10 'TDR_3P_TH2-EMPTY,N_A':;

SECTION_NUMBER 1
 '@S9S_MB_2U_LIB.S9S_MB_2U(SCH_1):PAGE288_I55@PURE_QUANTA.TDR_3P(CHIPS)':
 C_PATH='@s9s_mb_2u_lib.s9s_mb_2u(sch_1):page288_i55@pure_quanta.tdr_3p(chips)',
 P_PATH='@s9s_mb_2u_lib.s9s_mb_2u(sch_1):page309_i55@pure_quanta.tdr_3p(chips)',
 PATH='I55',
 DRAWING='@S9S_MB_2U_LIB.S9S_MB_2U(SCH_1):PAGE288',
 PHYS_PAGE='309',
 XY='(-1150,2700)',
 ROT='0',
 VER='2',
 PACK_TYPE='TH2',
 CDS_LIB='pure_quanta',
 CDS_PART_NAME='TDR_3P_TH2-EMPTY,N_A',
 MATERIAL='EMPTY',
 PRIM_FILE='./archive_libs/logical/tdr_3p/chips/chips.prt';

PART_NAME
 DB11 'TDR_3P_TH2-EMPTY,N_A':;

SECTION_NUMBER 1
 '@S9S_MB_2U_LIB.S9S_MB_2U(SCH_1):PAGE288_I57@PURE_QUANTA.TDR_3P(CHIPS)':
 C_PATH='@s9s_mb_2u_lib.s9s_mb_2u(sch_1):page288_i57@pure_quanta.tdr_3p(chips)',
 P_PATH='@s9s_mb_2u_lib.s9s_mb_2u(sch_1):page309_i57@pure_quanta.tdr_3p(chips)',
 PATH='I57',
 DRAWING='@S9S_MB_2U_LIB.S9S_MB_2U(SCH_1):PAGE288',
 PHYS_PAGE='309',
 XY='(-1150,2175)',
 ROT='0',
 VER='2',
 PACK_TYPE='TH2',
 CDS_LIB='pure_quanta',
 CDS_PART_NAME='TDR_3P_TH2-EMPTY,N_A',
 MATERIAL='EMPTY',
 PRIM_FILE='./archive_libs/logical/tdr_3p/chips/chips.prt';

PART_NAME
 DB12 'TDR_3P_TH2-EMPTY,N_A':;

SECTION_NUMBER 1
 '@S9S_MB_2U_LIB.S9S_MB_2U(SCH_1):PAGE288_I60@PURE_QUANTA.TDR_3P(CHIPS)':
 C_PATH='@s9s_mb_2u_lib.s9s_mb_2u(sch_1):page288_i60@pure_quanta.tdr_3p(chips)',
 P_PATH='@s9s_mb_2u_lib.s9s_mb_2u(sch_1):page309_i60@pure_quanta.tdr_3p(chips)',
 PATH='I60',
 DRAWING='@S9S_MB_2U_LIB.S9S_MB_2U(SCH_1):PAGE288',
 PHYS_PAGE='309',
 XY='(-1200,575)',
 ROT='0',
 VER='2',
 PACK_TYPE='TH2',
 CDS_LIB='pure_quanta',
 CDS_PART_NAME='TDR_3P_TH2-EMPTY,N_A',
 MATERIAL='EMPTY',
 PRIM_FILE='./archive_libs/logical/tdr_3p/chips/chips.prt';

PART_NAME
 DB13 'TDR_3P_TH2-EMPTY,N_A':;

SECTION_NUMBER 1
 '@S9S_MB_2U_LIB.S9S_MB_2U(SCH_1):PAGE288_I101@PURE_QUANTA.TDR_3P(CHIPS)':
 C_PATH='@s9s_mb_2u_lib.s9s_mb_2u(sch_1):page288_i101@pure_quanta.tdr_3p(chips)',
 P_PATH='@s9s_mb_2u_lib.s9s_mb_2u(sch_1):page309_i101@pure_quanta.tdr_3p(chips)',
 PATH='I101',
 DRAWING='@S9S_MB_2U_LIB.S9S_MB_2U(SCH_1):PAGE288',
 PHYS_PAGE='309',
 XY='(-2875,1650)',
 ROT='0',
 VER='2',
 PACK_TYPE='TH2',
 CDS_LIB='pure_quanta',
 CDS_PART_NAME='TDR_3P_TH2-EMPTY,N_A',
 MATERIAL='EMPTY',
 PRIM_FILE='./archive_libs/logical/tdr_3p/chips/chips.prt';

PART_NAME
 DB14 'TDR_3P_TH2-EMPTY,N_A':;

SECTION_NUMBER 1
 '@S9S_MB_2U_LIB.S9S_MB_2U(SCH_1):PAGE288_I96@PURE_QUANTA.TDR_3P(CHIPS)':
 C_PATH='@s9s_mb_2u_lib.s9s_mb_2u(sch_1):page288_i96@pure_quanta.tdr_3p(chips)',
 P_PATH='@s9s_mb_2u_lib.s9s_mb_2u(sch_1):page309_i96@pure_quanta.tdr_3p(chips)',
 PATH='I96',
 DRAWING='@S9S_MB_2U_LIB.S9S_MB_2U(SCH_1):PAGE288',
 PHYS_PAGE='309',
 XY='(-2875,1125)',
 ROT='0',
 VER='2',
 PACK_TYPE='TH2',
 CDS_LIB='pure_quanta',
 CDS_PART_NAME='TDR_3P_TH2-EMPTY,N_A',
 MATERIAL='EMPTY',
 PRIM_FILE='./archive_libs/logical/tdr_3p/chips/chips.prt';

PART_NAME
 DB15 'TDR_3P_TH2-EMPTY,N_A':;

SECTION_NUMBER 1
 '@S9S_MB_2U_LIB.S9S_MB_2U(SCH_1):PAGE288_I97@PURE_QUANTA.TDR_3P(CHIPS)':
 C_PATH='@s9s_mb_2u_lib.s9s_mb_2u(sch_1):page288_i97@pure_quanta.tdr_3p(chips)',
 P_PATH='@s9s_mb_2u_lib.s9s_mb_2u(sch_1):page309_i97@pure_quanta.tdr_3p(chips)',
 PATH='I97',
 DRAWING='@S9S_MB_2U_LIB.S9S_MB_2U(SCH_1):PAGE288',
 PHYS_PAGE='309',
 XY='(-1175,1650)',
 ROT='0',
 VER='2',
 PACK_TYPE='TH2',
 CDS_LIB='pure_quanta',
 CDS_PART_NAME='TDR_3P_TH2-EMPTY,N_A',
 MATERIAL='EMPTY',
 PRIM_FILE='./archive_libs/logical/tdr_3p/chips/chips.prt';

PART_NAME
 DB16 'TDR_3P_TH2-EMPTY,N_A':;

SECTION_NUMBER 1
 '@S9S_MB_2U_LIB.S9S_MB_2U(SCH_1):PAGE288_I99@PURE_QUANTA.TDR_3P(CHIPS)':
 C_PATH='@s9s_mb_2u_lib.s9s_mb_2u(sch_1):page288_i99@pure_quanta.tdr_3p(chips)',
 P_PATH='@s9s_mb_2u_lib.s9s_mb_2u(sch_1):page309_i99@pure_quanta.tdr_3p(chips)',
 PATH='I99',
 DRAWING='@S9S_MB_2U_LIB.S9S_MB_2U(SCH_1):PAGE288',
 PHYS_PAGE='309',
 XY='(-1175,1125)',
 ROT='0',
 VER='2',
 PACK_TYPE='TH2',
 CDS_LIB='pure_quanta',
 CDS_PART_NAME='TDR_3P_TH2-EMPTY,N_A',
 MATERIAL='EMPTY',
 PRIM_FILE='./archive_libs/logical/tdr_3p/chips/chips.prt';

PART_NAME
 DM9 'DUMMY_SYMBOL-MECHANIC_SYMBOL,MA':;

SECTION_NUMBER 1
 '@S9S_MB_2U_LIB.S9S_MB_2U(SCH_1):PAGE290_I23@PURE_QUANTA.DUMMY_SYMBOL(CHIPS)':
 C_PATH='@s9s_mb_2u_lib.s9s_mb_2u(sch_1):page290_i23@pure_quanta.dummy_symbol(ch~
ips)',
 P_PATH='@s9s_mb_2u_lib.s9s_mb_2u(sch_1):page312_i23@pure_quanta.dummy_symbol(ch~
ips)',
 PATH='I23',
 DRAWING='@S9S_MB_2U_LIB.S9S_MB_2U(SCH_1):PAGE290',
 PIN_NAMES_ROTATE='True',
 PHYS_PAGE='312',
 XY='(-132,3078)',
 ROT='0',
 VER='1',
 CDS_LIB='pure_quanta',
 CDS_PART_NAME='DUMMY_SYMBOL-MECHANIC_SYMBOL,MA',
 PART_TYPE='MECH',
 MATERIAL='MECH',
 VALUE='MECHANIC_SYMBOL',
 PRIM_FILE='./archive_libs/logical/dummy_symbol/chips/chips.prt';

PART_NAME
 DM13 'DUMMY_SYMBOL-BATTERY_SYMBOL,MEA':;

SECTION_NUMBER 1
 '@S9S_MB_2U_LIB.S9S_MB_2U(SCH_1):PAGE290_I17@PURE_QUANTA.DUMMY_SYMBOL(CHIPS)':
 C_PATH='@s9s_mb_2u_lib.s9s_mb_2u(sch_1):page290_i17@pure_quanta.dummy_symbol(ch~
ips)',
 P_PATH='@s9s_mb_2u_lib.s9s_mb_2u(sch_1):page312_i17@pure_quanta.dummy_symbol(ch~
ips)',
 PATH='I17',
 DRAWING='@S9S_MB_2U_LIB.S9S_MB_2U(SCH_1):PAGE290',
 L1='AHL03003003',
 PIN_NAMES_ROTATE='True',
 PHYS_PAGE='312',
 XY='(2275,3125)',
 ROT='0',
 VER='1',
 CDS_LIB='pure_quanta',
 CDS_PART_NAME='DUMMY_SYMBOL-BATTERY_SYMBOL,MEA',
 PART_TYPE='MECH',
 MATERIAL='MECH',
 VALUE='BATTERY_SYMBOL',
 PRIM_FILE='./archive_libs/logical/dummy_symbol/chips/chips.prt';

PART_NAME
 FS1 'Q_FUSE_SMLF-20A/125V,IC,DKK00XA':;

SECTION_NUMBER 1
 '@S9S_MB_2U_LIB.S9S_MB_2U(SCH_1):PAGE328_I54@PURE_QUANTA.Q_FUSE(CHIPS)':
 C_PATH='@s9s_mb_2u_lib.s9s_mb_2u(sch_1):page328_i54@pure_quanta.q_fuse(chips)',
 P_PATH='@s9s_mb_2u_lib.s9s_mb_2u(sch_1):page304_i54@pure_quanta.q_fuse(chips)',
 PATH='I54',
 DRAWING='@S9S_MB_2U_LIB.S9S_MB_2U(SCH_1):PAGE328',
 PHYS_PAGE='304',
 XY='(50,4125)',
 ROT='3',
 VER='1',
 PACK_TYPE='SMLF',
 LOCATION='FS1',
 CDS_LIB='pure_quanta',
 CDS_PART_NAME='Q_FUSE_SMLF-20A/125V,IC,DKK00XA',
 MATERIAL='IC',
 VALUE='20A/125V',
 PRIM_FILE='./archive_libs/logical/q_fuse/chips/chips.prt';

PART_NAME
 H15 'HOLE_TH-EMPTY,HOLE1079':;

SECTION_NUMBER 1
 '@S9S_MB_2U_LIB.S9S_MB_2U(SCH_1):PAGE289_I83@PURE_QUANTA.HOLE(CHIPS)':
 C_PATH='@s9s_mb_2u_lib.s9s_mb_2u(sch_1):page289_i83@pure_quanta.hole(chips)',
 P_PATH='@s9s_mb_2u_lib.s9s_mb_2u(sch_1):page311_i83@pure_quanta.hole(chips)',
 PATH='I83',
 DRAWING='@S9S_MB_2U_LIB.S9S_MB_2U(SCH_1):PAGE289',
 PHYS_PAGE='311',
 XY='(-2500,1250)',
 ROT='0',
 VER='1',
 PACK_TYPE='TH',
 CDS_LIB='pure_quanta',
 CDS_PART_NAME='HOLE_TH-EMPTY,HOLE1079',
 MATERIAL='EMPTY',
 PRIM_FILE='./archive_libs/logical/hole/chips/chips.prt';

PART_NAME
 H16 'HOLE_TH-EMPTY,HOLE1079':;

SECTION_NUMBER 1
 '@S9S_MB_2U_LIB.S9S_MB_2U(SCH_1):PAGE289_I63@PURE_QUANTA.HOLE(CHIPS)':
 C_PATH='@s9s_mb_2u_lib.s9s_mb_2u(sch_1):page289_i63@pure_quanta.hole(chips)',
 P_PATH='@s9s_mb_2u_lib.s9s_mb_2u(sch_1):page311_i63@pure_quanta.hole(chips)',
 PATH='I63',
 DRAWING='@S9S_MB_2U_LIB.S9S_MB_2U(SCH_1):PAGE289',
 PHYS_PAGE='311',
 XY='(-2525,750)',
 ROT='0',
 VER='1',
 PACK_TYPE='TH',
 CDS_LIB='pure_quanta',
 CDS_PART_NAME='HOLE_TH-EMPTY,HOLE1079',
 MATERIAL='EMPTY',
 PRIM_FILE='./archive_libs/logical/hole/chips/chips.prt';

PART_NAME
 H17 'HOLE_TH-EMPTY,HOLE1079':;

SECTION_NUMBER 1
 '@S9S_MB_2U_LIB.S9S_MB_2U(SCH_1):PAGE289_I75@PURE_QUANTA.HOLE(CHIPS)':
 C_PATH='@s9s_mb_2u_lib.s9s_mb_2u(sch_1):page289_i75@pure_quanta.hole(chips)',
 P_PATH='@s9s_mb_2u_lib.s9s_mb_2u(sch_1):page311_i75@pure_quanta.hole(chips)',
 PATH='I75',
 DRAWING='@S9S_MB_2U_LIB.S9S_MB_2U(SCH_1):PAGE289',
 PHYS_PAGE='311',
 XY='(-2000,1250)',
 ROT='0',
 VER='1',
 PACK_TYPE='TH',
 CDS_LIB='pure_quanta',
 CDS_PART_NAME='HOLE_TH-EMPTY,HOLE1079',
 MATERIAL='EMPTY',
 PRIM_FILE='./archive_libs/logical/hole/chips/chips.prt';

PART_NAME
 H18 'HOLE_TH-EMPTY,HOLE1079':;

SECTION_NUMBER 1
 '@S9S_MB_2U_LIB.S9S_MB_2U(SCH_1):PAGE289_I61@PURE_QUANTA.HOLE(CHIPS)':
 C_PATH='@s9s_mb_2u_lib.s9s_mb_2u(sch_1):page289_i61@pure_quanta.hole(chips)',
 P_PATH='@s9s_mb_2u_lib.s9s_mb_2u(sch_1):page311_i61@pure_quanta.hole(chips)',
 PATH='I61',
 DRAWING='@S9S_MB_2U_LIB.S9S_MB_2U(SCH_1):PAGE289',
 PHYS_PAGE='311',
 XY='(-2025,750)',
 ROT='0',
 VER='1',
 PACK_TYPE='TH',
 CDS_LIB='pure_quanta',
 CDS_PART_NAME='HOLE_TH-EMPTY,HOLE1079',
 MATERIAL='EMPTY',
 PRIM_FILE='./archive_libs/logical/hole/chips/chips.prt';

PART_NAME
 H19 'HOLE_TH-EMPTY,HOLE1079':;

SECTION_NUMBER 1
 '@S9S_MB_2U_LIB.S9S_MB_2U(SCH_1):PAGE289_I74@PURE_QUANTA.HOLE(CHIPS)':
 C_PATH='@s9s_mb_2u_lib.s9s_mb_2u(sch_1):page289_i74@pure_quanta.hole(chips)',
 P_PATH='@s9s_mb_2u_lib.s9s_mb_2u(sch_1):page311_i74@pure_quanta.hole(chips)',
 PATH='I74',
 DRAWING='@S9S_MB_2U_LIB.S9S_MB_2U(SCH_1):PAGE289',
 PHYS_PAGE='311',
 XY='(-1500,1250)',
 ROT='0',
 VER='1',
 PACK_TYPE='TH',
 CDS_LIB='pure_quanta',
 CDS_PART_NAME='HOLE_TH-EMPTY,HOLE1079',
 MATERIAL='EMPTY',
 PRIM_FILE='./archive_libs/logical/hole/chips/chips.prt';

PART_NAME
 H20 'HOLE_TH-EMPTY,HOLE1079':;

SECTION_NUMBER 1
 '@S9S_MB_2U_LIB.S9S_MB_2U(SCH_1):PAGE289_I60@PURE_QUANTA.HOLE(CHIPS)':
 C_PATH='@s9s_mb_2u_lib.s9s_mb_2u(sch_1):page289_i60@pure_quanta.hole(chips)',
 P_PATH='@s9s_mb_2u_lib.s9s_mb_2u(sch_1):page311_i60@pure_quanta.hole(chips)',
 PATH='I60',
 DRAWING='@S9S_MB_2U_LIB.S9S_MB_2U(SCH_1):PAGE289',
 PHYS_PAGE='311',
 XY='(-1525,750)',
 ROT='0',
 VER='1',
 PACK_TYPE='TH',
 CDS_LIB='pure_quanta',
 CDS_PART_NAME='HOLE_TH-EMPTY,HOLE1079',
 MATERIAL='EMPTY',
 PRIM_FILE='./archive_libs/logical/hole/chips/chips.prt';

PART_NAME
 H21 'HOLE_TH-EMPTY,HOLE1079':;

SECTION_NUMBER 1
 '@S9S_MB_2U_LIB.S9S_MB_2U(SCH_1):PAGE289_I73@PURE_QUANTA.HOLE(CHIPS)':
 C_PATH='@s9s_mb_2u_lib.s9s_mb_2u(sch_1):page289_i73@pure_quanta.hole(chips)',
 P_PATH='@s9s_mb_2u_lib.s9s_mb_2u(sch_1):page311_i73@pure_quanta.hole(chips)',
 PATH='I73',
 DRAWING='@S9S_MB_2U_LIB.S9S_MB_2U(SCH_1):PAGE289',
 PHYS_PAGE='311',
 XY='(-1000,1250)',
 ROT='0',
 VER='1',
 PACK_TYPE='TH',
 CDS_LIB='pure_quanta',
 CDS_PART_NAME='HOLE_TH-EMPTY,HOLE1079',
 MATERIAL='EMPTY',
 PRIM_FILE='./archive_libs/logical/hole/chips/chips.prt';

PART_NAME
 H22 'HOLE_TH-EMPTY,HOLE1079':;

SECTION_NUMBER 1
 '@S9S_MB_2U_LIB.S9S_MB_2U(SCH_1):PAGE289_I21@PURE_QUANTA.HOLE(CHIPS)':
 C_PATH='@s9s_mb_2u_lib.s9s_mb_2u(sch_1):page289_i21@pure_quanta.hole(chips)',
 P_PATH='@s9s_mb_2u_lib.s9s_mb_2u(sch_1):page311_i21@pure_quanta.hole(chips)',
 PATH='I21',
 DRAWING='@S9S_MB_2U_LIB.S9S_MB_2U(SCH_1):PAGE289',
 PHYS_PAGE='311',
 XY='(-1025,750)',
 ROT='0',
 VER='1',
 PACK_TYPE='TH',
 CDS_LIB='pure_quanta',
 CDS_PART_NAME='HOLE_TH-EMPTY,HOLE1079',
 MATERIAL='EMPTY',
 PRIM_FILE='./archive_libs/logical/hole/chips/chips.prt';

PART_NAME
 H23 'HOLE_TH-EMPTY,HOLE1079':;

SECTION_NUMBER 1
 '@S9S_MB_2U_LIB.S9S_MB_2U(SCH_1):PAGE289_I72@PURE_QUANTA.HOLE(CHIPS)':
 C_PATH='@s9s_mb_2u_lib.s9s_mb_2u(sch_1):page289_i72@pure_quanta.hole(chips)',
 P_PATH='@s9s_mb_2u_lib.s9s_mb_2u(sch_1):page311_i72@pure_quanta.hole(chips)',
 PATH='I72',
 DRAWING='@S9S_MB_2U_LIB.S9S_MB_2U(SCH_1):PAGE289',
 PHYS_PAGE='311',
 XY='(-475,1250)',
 ROT='0',
 VER='1',
 PACK_TYPE='TH',
 CDS_LIB='pure_quanta',
 CDS_PART_NAME='HOLE_TH-EMPTY,HOLE1079',
 MATERIAL='EMPTY',
 PRIM_FILE='./archive_libs/logical/hole/chips/chips.prt';

PART_NAME
 H24 'HOLE_TH-EMPTY,HOLE1079':;

SECTION_NUMBER 1
 '@S9S_MB_2U_LIB.S9S_MB_2U(SCH_1):PAGE289_I20@PURE_QUANTA.HOLE(CHIPS)':
 C_PATH='@s9s_mb_2u_lib.s9s_mb_2u(sch_1):page289_i20@pure_quanta.hole(chips)',
 P_PATH='@s9s_mb_2u_lib.s9s_mb_2u(sch_1):page311_i20@pure_quanta.hole(chips)',
 PATH='I20',
 DRAWING='@S9S_MB_2U_LIB.S9S_MB_2U(SCH_1):PAGE289',
 PHYS_PAGE='311',
 XY='(-500,750)',
 ROT='0',
 VER='1',
 PACK_TYPE='TH',
 CDS_LIB='pure_quanta',
 CDS_PART_NAME='HOLE_TH-EMPTY,HOLE1079',
 MATERIAL='EMPTY',
 PRIM_FILE='./archive_libs/logical/hole/chips/chips.prt';

PART_NAME
 H25 'HOLE_TH-EMPTY,HOLE1079':;

SECTION_NUMBER 1
 '@S9S_MB_2U_LIB.S9S_MB_2U(SCH_1):PAGE289_I64@PURE_QUANTA.HOLE(CHIPS)':
 C_PATH='@s9s_mb_2u_lib.s9s_mb_2u(sch_1):page289_i64@pure_quanta.hole(chips)',
 P_PATH='@s9s_mb_2u_lib.s9s_mb_2u(sch_1):page311_i64@pure_quanta.hole(chips)',
 PATH='I64',
 DRAWING='@S9S_MB_2U_LIB.S9S_MB_2U(SCH_1):PAGE289',
 PHYS_PAGE='311',
 XY='(25,1250)',
 ROT='0',
 VER='1',
 PACK_TYPE='TH',
 CDS_LIB='pure_quanta',
 CDS_PART_NAME='HOLE_TH-EMPTY,HOLE1079',
 MATERIAL='EMPTY',
 PRIM_FILE='./archive_libs/logical/hole/chips/chips.prt';

PART_NAME
 H26 'HOLE_TH-EMPTY,HOLE1079':;

SECTION_NUMBER 1
 '@S9S_MB_2U_LIB.S9S_MB_2U(SCH_1):PAGE289_I19@PURE_QUANTA.HOLE(CHIPS)':
 C_PATH='@s9s_mb_2u_lib.s9s_mb_2u(sch_1):page289_i19@pure_quanta.hole(chips)',
 P_PATH='@s9s_mb_2u_lib.s9s_mb_2u(sch_1):page311_i19@pure_quanta.hole(chips)',
 PATH='I19',
 DRAWING='@S9S_MB_2U_LIB.S9S_MB_2U(SCH_1):PAGE289',
 PHYS_PAGE='311',
 XY='(0,750)',
 ROT='0',
 VER='1',
 PACK_TYPE='TH',
 CDS_LIB='pure_quanta',
 CDS_PART_NAME='HOLE_TH-EMPTY,HOLE1079',
 MATERIAL='EMPTY',
 PRIM_FILE='./archive_libs/logical/hole/chips/chips.prt';

PART_NAME
 H27 'HOLE_TH-EMPTY,DUMMY50':;

SECTION_NUMBER 1
 '@S9S_MB_2U_LIB.S9S_MB_2U(SCH_1):PAGE289_I12@PURE_QUANTA.HOLE(CHIPS)':
 C_PATH='@s9s_mb_2u_lib.s9s_mb_2u(sch_1):page289_i12@pure_quanta.hole(chips)',
 P_PATH='@s9s_mb_2u_lib.s9s_mb_2u(sch_1):page311_i12@pure_quanta.hole(chips)',
 PATH='I12',
 DRAWING='@S9S_MB_2U_LIB.S9S_MB_2U(SCH_1):PAGE289',
 PHYS_PAGE='311',
 XY='(275,2275)',
 ROT='0',
 VER='1',
 PACK_TYPE='TH',
 CDS_LIB='pure_quanta',
 CDS_PART_NAME='HOLE_TH-EMPTY,DUMMY50',
 MATERIAL='EMPTY',
 PRIM_FILE='./archive_libs/logical/hole/chips/chips.prt';

PART_NAME
 H28 'HOLE_TH-EMPTY,DUMMY50':;

SECTION_NUMBER 1
 '@S9S_MB_2U_LIB.S9S_MB_2U(SCH_1):PAGE289_I11@PURE_QUANTA.HOLE(CHIPS)':
 C_PATH='@s9s_mb_2u_lib.s9s_mb_2u(sch_1):page289_i11@pure_quanta.hole(chips)',
 P_PATH='@s9s_mb_2u_lib.s9s_mb_2u(sch_1):page311_i11@pure_quanta.hole(chips)',
 PATH='I11',
 DRAWING='@S9S_MB_2U_LIB.S9S_MB_2U(SCH_1):PAGE289',
 PHYS_PAGE='311',
 XY='(775,2275)',
 ROT='0',
 VER='1',
 PACK_TYPE='TH',
 CDS_LIB='pure_quanta',
 CDS_PART_NAME='HOLE_TH-EMPTY,DUMMY50',
 MATERIAL='EMPTY',
 PRIM_FILE='./archive_libs/logical/hole/chips/chips.prt';

PART_NAME
 H29 'HOLE_TH-EMPTY,DUMMY50':;

SECTION_NUMBER 1
 '@S9S_MB_2U_LIB.S9S_MB_2U(SCH_1):PAGE289_I8@PURE_QUANTA.HOLE(CHIPS)':
 C_PATH='@s9s_mb_2u_lib.s9s_mb_2u(sch_1):page289_i8@pure_quanta.hole(chips)',
 P_PATH='@s9s_mb_2u_lib.s9s_mb_2u(sch_1):page311_i8@pure_quanta.hole(chips)',
 PATH='I8',
 DRAWING='@S9S_MB_2U_LIB.S9S_MB_2U(SCH_1):PAGE289',
 PHYS_PAGE='311',
 XY='(1300,2275)',
 ROT='0',
 VER='1',
 PACK_TYPE='TH',
 CDS_LIB='pure_quanta',
 CDS_PART_NAME='HOLE_TH-EMPTY,DUMMY50',
 MATERIAL='EMPTY',
 PRIM_FILE='./archive_libs/logical/hole/chips/chips.prt';

PART_NAME
 H30 'HOLE_TH-EMPTY,DUMMY50':;

SECTION_NUMBER 1
 '@S9S_MB_2U_LIB.S9S_MB_2U(SCH_1):PAGE289_I7@PURE_QUANTA.HOLE(CHIPS)':
 C_PATH='@s9s_mb_2u_lib.s9s_mb_2u(sch_1):page289_i7@pure_quanta.hole(chips)',
 P_PATH='@s9s_mb_2u_lib.s9s_mb_2u(sch_1):page311_i7@pure_quanta.hole(chips)',
 PATH='I7',
 DRAWING='@S9S_MB_2U_LIB.S9S_MB_2U(SCH_1):PAGE289',
 PHYS_PAGE='311',
 XY='(1800,2275)',
 ROT='0',
 VER='1',
 PACK_TYPE='TH',
 CDS_LIB='pure_quanta',
 CDS_PART_NAME='HOLE_TH-EMPTY,DUMMY50',
 MATERIAL='EMPTY',
 PRIM_FILE='./archive_libs/logical/hole/chips/chips.prt';

PART_NAME
 H31 'HOLE_TH-EMPTY,HOLE1248':;

SECTION_NUMBER 1
 '@S9S_MB_2U_LIB.S9S_MB_2U(SCH_1):PAGE289_I56@PURE_QUANTA.HOLE(CHIPS)':
 C_PATH='@s9s_mb_2u_lib.s9s_mb_2u(sch_1):page289_i56@pure_quanta.hole(chips)',
 P_PATH='@s9s_mb_2u_lib.s9s_mb_2u(sch_1):page311_i56@pure_quanta.hole(chips)',
 PATH='I56',
 DRAWING='@S9S_MB_2U_LIB.S9S_MB_2U(SCH_1):PAGE289',
 PHYS_PAGE='311',
 XY='(3875,2150)',
 ROT='0',
 VER='1',
 PACK_TYPE='TH',
 CDS_LIB='pure_quanta',
 CDS_PART_NAME='HOLE_TH-EMPTY,HOLE1248',
 MATERIAL='EMPTY',
 PRIM_FILE='./archive_libs/logical/hole/chips/chips.prt';

PART_NAME
 H32 'HOLE_TH-EMPTY,HOLE1248':;

SECTION_NUMBER 1
 '@S9S_MB_2U_LIB.S9S_MB_2U(SCH_1):PAGE289_I54@PURE_QUANTA.HOLE(CHIPS)':
 C_PATH='@s9s_mb_2u_lib.s9s_mb_2u(sch_1):page289_i54@pure_quanta.hole(chips)',
 P_PATH='@s9s_mb_2u_lib.s9s_mb_2u(sch_1):page311_i54@pure_quanta.hole(chips)',
 PATH='I54',
 DRAWING='@S9S_MB_2U_LIB.S9S_MB_2U(SCH_1):PAGE289',
 PHYS_PAGE='311',
 XY='(4375,2150)',
 ROT='0',
 VER='1',
 PACK_TYPE='TH',
 CDS_LIB='pure_quanta',
 CDS_PART_NAME='HOLE_TH-EMPTY,HOLE1248',
 MATERIAL='EMPTY',
 PRIM_FILE='./archive_libs/logical/hole/chips/chips.prt';

PART_NAME
 H36 'HOLE_TH-EMPTY,TMP-Q_HOLE78':;

SECTION_NUMBER 1
 '@S9S_MB_2U_LIB.S9S_MB_2U(SCH_1):PAGE289_I10@PURE_QUANTA.HOLE(CHIPS)':
 C_PATH='@s9s_mb_2u_lib.s9s_mb_2u(sch_1):page289_i10@pure_quanta.hole(chips)',
 P_PATH='@s9s_mb_2u_lib.s9s_mb_2u(sch_1):page311_i10@pure_quanta.hole(chips)',
 PATH='I10',
 DRAWING='@S9S_MB_2U_LIB.S9S_MB_2U(SCH_1):PAGE289',
 PHYS_PAGE='311',
 XY='(3100,1175)',
 ROT='0',
 VER='1',
 PACK_TYPE='TH',
 CDS_LIB='pure_quanta',
 CDS_PART_NAME='HOLE_TH-EMPTY,TMP-Q_HOLE78',
 MATERIAL='EMPTY',
 PRIM_FILE='./archive_libs/logical/hole/chips/chips.prt';

PART_NAME
 H38 'HOLE_TH-EMPTY,TMP-Q_HOLE78':;

SECTION_NUMBER 1
 '@S9S_MB_2U_LIB.S9S_MB_2U(SCH_1):PAGE289_I9@PURE_QUANTA.HOLE(CHIPS)':
 C_PATH='@s9s_mb_2u_lib.s9s_mb_2u(sch_1):page289_i9@pure_quanta.hole(chips)',
 P_PATH='@s9s_mb_2u_lib.s9s_mb_2u(sch_1):page311_i9@pure_quanta.hole(chips)',
 PATH='I9',
 DRAWING='@S9S_MB_2U_LIB.S9S_MB_2U(SCH_1):PAGE289',
 PHYS_PAGE='311',
 XY='(3600,1175)',
 ROT='0',
 VER='1',
 PACK_TYPE='TH',
 CDS_LIB='pure_quanta',
 CDS_PART_NAME='HOLE_TH-EMPTY,TMP-Q_HOLE78',
 MATERIAL='EMPTY',
 PRIM_FILE='./archive_libs/logical/hole/chips/chips.prt';

PART_NAME
 H44 'HOLE_TH-EMPTY,SP_HOLE1199':;

SECTION_NUMBER 1
 '@S9S_MB_2U_LIB.S9S_MB_2U(SCH_1):PAGE289_I216@PURE_QUANTA.HOLE(CHIPS)':
 C_PATH='@s9s_mb_2u_lib.s9s_mb_2u(sch_1):page289_i216@pure_quanta.hole(chips)',
 P_PATH='@s9s_mb_2u_lib.s9s_mb_2u(sch_1):page311_i216@pure_quanta.hole(chips)',
 PATH='I216',
 DRAWING='@S9S_MB_2U_LIB.S9S_MB_2U(SCH_1):PAGE289',
 PHYS_PAGE='311',
 XY='(-2450,2250)',
 ROT='0',
 VER='1',
 PACK_TYPE='TH',
 LOCATION='H44',
 CDS_LIB='pure_quanta',
 CDS_PART_NAME='HOLE_TH-EMPTY,SP_HOLE1199',
 MATERIAL='EMPTY',
 PRIM_FILE='./archive_libs/logical/hole/chips/chips.prt';

PART_NAME
 H45 'HOLE_TH-EMPTY,SP_HOLE1199':;

SECTION_NUMBER 1
 '@S9S_MB_2U_LIB.S9S_MB_2U(SCH_1):PAGE289_I217@PURE_QUANTA.HOLE(CHIPS)':
 C_PATH='@s9s_mb_2u_lib.s9s_mb_2u(sch_1):page289_i217@pure_quanta.hole(chips)',
 P_PATH='@s9s_mb_2u_lib.s9s_mb_2u(sch_1):page311_i217@pure_quanta.hole(chips)',
 PATH='I217',
 DRAWING='@S9S_MB_2U_LIB.S9S_MB_2U(SCH_1):PAGE289',
 PHYS_PAGE='311',
 XY='(-1825,2250)',
 ROT='0',
 VER='1',
 PACK_TYPE='TH',
 LOCATION='H45',
 CDS_LIB='pure_quanta',
 CDS_PART_NAME='HOLE_TH-EMPTY,SP_HOLE1199',
 MATERIAL='EMPTY',
 PRIM_FILE='./archive_libs/logical/hole/chips/chips.prt';

PART_NAME
 H47 'HOLE_TH-EMPTY,SP_HOLE1199':;

SECTION_NUMBER 1
 '@S9S_MB_2U_LIB.S9S_MB_2U(SCH_1):PAGE289_I218@PURE_QUANTA.HOLE(CHIPS)':
 C_PATH='@s9s_mb_2u_lib.s9s_mb_2u(sch_1):page289_i218@pure_quanta.hole(chips)',
 P_PATH='@s9s_mb_2u_lib.s9s_mb_2u(sch_1):page311_i218@pure_quanta.hole(chips)',
 PATH='I218',
 DRAWING='@S9S_MB_2U_LIB.S9S_MB_2U(SCH_1):PAGE289',
 PHYS_PAGE='311',
 XY='(-1175,2250)',
 ROT='0',
 VER='1',
 PACK_TYPE='TH',
 LOCATION='H47',
 CDS_LIB='pure_quanta',
 CDS_PART_NAME='HOLE_TH-EMPTY,SP_HOLE1199',
 MATERIAL='EMPTY',
 PRIM_FILE='./archive_libs/logical/hole/chips/chips.prt';

PART_NAME
 H49 'HOLE_TH-EMPTY,SP_HOLE1199':;

SECTION_NUMBER 1
 '@S9S_MB_2U_LIB.S9S_MB_2U(SCH_1):PAGE289_I219@PURE_QUANTA.HOLE(CHIPS)':
 C_PATH='@s9s_mb_2u_lib.s9s_mb_2u(sch_1):page289_i219@pure_quanta.hole(chips)',
 P_PATH='@s9s_mb_2u_lib.s9s_mb_2u(sch_1):page311_i219@pure_quanta.hole(chips)',
 PATH='I219',
 DRAWING='@S9S_MB_2U_LIB.S9S_MB_2U(SCH_1):PAGE289',
 PHYS_PAGE='311',
 XY='(-525,2250)',
 ROT='0',
 VER='1',
 PACK_TYPE='TH',
 LOCATION='H49',
 CDS_LIB='pure_quanta',
 CDS_PART_NAME='HOLE_TH-EMPTY,SP_HOLE1199',
 MATERIAL='EMPTY',
 PRIM_FILE='./archive_libs/logical/hole/chips/chips.prt';

PART_NAME
 H74 'HOLE_TH-EMPTY,HOLE1247':;

SECTION_NUMBER 1
 '@S9S_MB_2U_LIB.S9S_MB_2U(SCH_1):PAGE289_I58@PURE_QUANTA.HOLE(CHIPS)':
 C_PATH='@s9s_mb_2u_lib.s9s_mb_2u(sch_1):page289_i58@pure_quanta.hole(chips)',
 P_PATH='@s9s_mb_2u_lib.s9s_mb_2u(sch_1):page311_i58@pure_quanta.hole(chips)',
 PATH='I58',
 DRAWING='@S9S_MB_2U_LIB.S9S_MB_2U(SCH_1):PAGE289',
 PHYS_PAGE='311',
 XY='(2550,2225)',
 ROT='0',
 VER='1',
 PACK_TYPE='TH',
 CDS_LIB='pure_quanta',
 CDS_PART_NAME='HOLE_TH-EMPTY,HOLE1247',
 MATERIAL='EMPTY',
 PRIM_FILE='./archive_libs/logical/hole/chips/chips.prt';

PART_NAME
 H75 'HOLE_TH-EMPTY,HOLE1247':;

SECTION_NUMBER 1
 '@S9S_MB_2U_LIB.S9S_MB_2U(SCH_1):PAGE289_I57@PURE_QUANTA.HOLE(CHIPS)':
 C_PATH='@s9s_mb_2u_lib.s9s_mb_2u(sch_1):page289_i57@pure_quanta.hole(chips)',
 P_PATH='@s9s_mb_2u_lib.s9s_mb_2u(sch_1):page311_i57@pure_quanta.hole(chips)',
 PATH='I57',
 DRAWING='@S9S_MB_2U_LIB.S9S_MB_2U(SCH_1):PAGE289',
 PHYS_PAGE='311',
 XY='(3050,2225)',
 ROT='0',
 VER='1',
 PACK_TYPE='TH',
 CDS_LIB='pure_quanta',
 CDS_PART_NAME='HOLE_TH-EMPTY,HOLE1247',
 MATERIAL='EMPTY',
 PRIM_FILE='./archive_libs/logical/hole/chips/chips.prt';

PART_NAME
 H76 'HOLE_TH-EMPTY,HOLE1187':;

SECTION_NUMBER 1
 '@S9S_MB_2U_LIB.S9S_MB_2U(SCH_1):PAGE289_I18@PURE_QUANTA.HOLE(CHIPS)':
 C_PATH='@s9s_mb_2u_lib.s9s_mb_2u(sch_1):page289_i18@pure_quanta.hole(chips)',
 P_PATH='@s9s_mb_2u_lib.s9s_mb_2u(sch_1):page311_i18@pure_quanta.hole(chips)',
 PATH='I18',
 DRAWING='@S9S_MB_2U_LIB.S9S_MB_2U(SCH_1):PAGE289',
 PHYS_PAGE='311',
 XY='(775,1050)',
 ROT='0',
 VER='1',
 PACK_TYPE='TH',
 CDS_LIB='pure_quanta',
 CDS_PART_NAME='HOLE_TH-EMPTY,HOLE1187',
 MATERIAL='EMPTY',
 PRIM_FILE='./archive_libs/logical/hole/chips/chips.prt';

PART_NAME
 H77 'HOLE_TH-EMPTY,HOLE1187':;

SECTION_NUMBER 1
 '@S9S_MB_2U_LIB.S9S_MB_2U(SCH_1):PAGE289_I87@PURE_QUANTA.HOLE(CHIPS)':
 C_PATH='@s9s_mb_2u_lib.s9s_mb_2u(sch_1):page289_i87@pure_quanta.hole(chips)',
 P_PATH='@s9s_mb_2u_lib.s9s_mb_2u(sch_1):page311_i87@pure_quanta.hole(chips)',
 PATH='I87',
 DRAWING='@S9S_MB_2U_LIB.S9S_MB_2U(SCH_1):PAGE289',
 PHYS_PAGE='311',
 XY='(1325,1050)',
 ROT='0',
 VER='1',
 PACK_TYPE='TH',
 CDS_LIB='pure_quanta',
 CDS_PART_NAME='HOLE_TH-EMPTY,HOLE1187',
 MATERIAL='EMPTY',
 PRIM_FILE='./archive_libs/logical/hole/chips/chips.prt';

PART_NAME
 H86 'HOLE_TH-EMPTY,HOLE596':;

SECTION_NUMBER 1
 '@S9S_MB_2U_LIB.S9S_MB_2U(SCH_1):PAGE289_I140@PURE_QUANTA.HOLE(CHIPS)':
 C_PATH='@s9s_mb_2u_lib.s9s_mb_2u(sch_1):page289_i140@pure_quanta.hole(chips)',
 P_PATH='@s9s_mb_2u_lib.s9s_mb_2u(sch_1):page311_i140@pure_quanta.hole(chips)',
 PATH='I140',
 DRAWING='@S9S_MB_2U_LIB.S9S_MB_2U(SCH_1):PAGE289',
 PHYS_PAGE='311',
 XY='(-2475,4400)',
 ROT='0',
 VER='1',
 PACK_TYPE='TH',
 CDS_LIB='pure_quanta',
 CDS_PART_NAME='HOLE_TH-EMPTY,HOLE596',
 MATERIAL='EMPTY',
 PRIM_FILE='./archive_libs/logical/hole/chips/chips.prt';

PART_NAME
 H87 'HOLE_TH-EMPTY,HOLE596':;

SECTION_NUMBER 1
 '@S9S_MB_2U_LIB.S9S_MB_2U(SCH_1):PAGE289_I168@PURE_QUANTA.HOLE(CHIPS)':
 C_PATH='@s9s_mb_2u_lib.s9s_mb_2u(sch_1):page289_i168@pure_quanta.hole(chips)',
 P_PATH='@s9s_mb_2u_lib.s9s_mb_2u(sch_1):page311_i168@pure_quanta.hole(chips)',
 PATH='I168',
 DRAWING='@S9S_MB_2U_LIB.S9S_MB_2U(SCH_1):PAGE289',
 PHYS_PAGE='311',
 XY='(-2475,3525)',
 ROT='0',
 VER='1',
 PACK_TYPE='TH',
 CDS_LIB='pure_quanta',
 CDS_PART_NAME='HOLE_TH-EMPTY,HOLE596',
 MATERIAL='EMPTY',
 PRIM_FILE='./archive_libs/logical/hole/chips/chips.prt';

PART_NAME
 H88 'HOLE_TH-EMPTY,HOLE596':;

SECTION_NUMBER 1
 '@S9S_MB_2U_LIB.S9S_MB_2U(SCH_1):PAGE289_I144@PURE_QUANTA.HOLE(CHIPS)':
 C_PATH='@s9s_mb_2u_lib.s9s_mb_2u(sch_1):page289_i144@pure_quanta.hole(chips)',
 P_PATH='@s9s_mb_2u_lib.s9s_mb_2u(sch_1):page311_i144@pure_quanta.hole(chips)',
 PATH='I144',
 DRAWING='@S9S_MB_2U_LIB.S9S_MB_2U(SCH_1):PAGE289',
 PHYS_PAGE='311',
 XY='(-1775,4400)',
 ROT='0',
 VER='1',
 PACK_TYPE='TH',
 CDS_LIB='pure_quanta',
 CDS_PART_NAME='HOLE_TH-EMPTY,HOLE596',
 MATERIAL='EMPTY',
 PRIM_FILE='./archive_libs/logical/hole/chips/chips.prt';

PART_NAME
 H89 'HOLE_TH-EMPTY,HOLE596':;

SECTION_NUMBER 1
 '@S9S_MB_2U_LIB.S9S_MB_2U(SCH_1):PAGE289_I167@PURE_QUANTA.HOLE(CHIPS)':
 C_PATH='@s9s_mb_2u_lib.s9s_mb_2u(sch_1):page289_i167@pure_quanta.hole(chips)',
 P_PATH='@s9s_mb_2u_lib.s9s_mb_2u(sch_1):page311_i167@pure_quanta.hole(chips)',
 PATH='I167',
 DRAWING='@S9S_MB_2U_LIB.S9S_MB_2U(SCH_1):PAGE289',
 PHYS_PAGE='311',
 XY='(-1775,3525)',
 ROT='0',
 VER='1',
 PACK_TYPE='TH',
 CDS_LIB='pure_quanta',
 CDS_PART_NAME='HOLE_TH-EMPTY,HOLE596',
 MATERIAL='EMPTY',
 PRIM_FILE='./archive_libs/logical/hole/chips/chips.prt';

PART_NAME
 H90 'HOLE_TH-EMPTY,HOLE372':;

SECTION_NUMBER 1
 '@S9S_MB_2U_LIB.S9S_MB_2U(SCH_1):PAGE289_I254@PURE_QUANTA.HOLE(CHIPS)':
 C_PATH='@s9s_mb_2u_lib.s9s_mb_2u(sch_1):page289_i254@pure_quanta.hole(chips)',
 P_PATH='@s9s_mb_2u_lib.s9s_mb_2u(sch_1):page311_i254@pure_quanta.hole(chips)',
 PATH='I254',
 DRAWING='@S9S_MB_2U_LIB.S9S_MB_2U(SCH_1):PAGE289',
 PHYS_PAGE='311',
 XY='(5275,4050)',
 ROT='0',
 VER='1',
 PACK_TYPE='TH',
 LOCATION='H90',
 CDS_LIB='pure_quanta',
 CDS_PART_NAME='HOLE_TH-EMPTY,HOLE372',
 MATERIAL='EMPTY',
 PRIM_FILE='./archive_libs/logical/hole/chips/chips.prt';

PART_NAME
 H91 'HOLE_TH-EMPTY,HOLE596':;

SECTION_NUMBER 1
 '@S9S_MB_2U_LIB.S9S_MB_2U(SCH_1):PAGE289_I147@PURE_QUANTA.HOLE(CHIPS)':
 C_PATH='@s9s_mb_2u_lib.s9s_mb_2u(sch_1):page289_i147@pure_quanta.hole(chips)',
 P_PATH='@s9s_mb_2u_lib.s9s_mb_2u(sch_1):page311_i147@pure_quanta.hole(chips)',
 PATH='I147',
 DRAWING='@S9S_MB_2U_LIB.S9S_MB_2U(SCH_1):PAGE289',
 PHYS_PAGE='311',
 XY='(-1100,4400)',
 ROT='0',
 VER='1',
 PACK_TYPE='TH',
 CDS_LIB='pure_quanta',
 CDS_PART_NAME='HOLE_TH-EMPTY,HOLE596',
 MATERIAL='EMPTY',
 PRIM_FILE='./archive_libs/logical/hole/chips/chips.prt';

PART_NAME
 H92 'HOLE_TH-EMPTY,HOLE596':;

SECTION_NUMBER 1
 '@S9S_MB_2U_LIB.S9S_MB_2U(SCH_1):PAGE289_I166@PURE_QUANTA.HOLE(CHIPS)':
 C_PATH='@s9s_mb_2u_lib.s9s_mb_2u(sch_1):page289_i166@pure_quanta.hole(chips)',
 P_PATH='@s9s_mb_2u_lib.s9s_mb_2u(sch_1):page311_i166@pure_quanta.hole(chips)',
 PATH='I166',
 DRAWING='@S9S_MB_2U_LIB.S9S_MB_2U(SCH_1):PAGE289',
 PHYS_PAGE='311',
 XY='(-1100,3525)',
 ROT='0',
 VER='1',
 PACK_TYPE='TH',
 CDS_LIB='pure_quanta',
 CDS_PART_NAME='HOLE_TH-EMPTY,HOLE596',
 MATERIAL='EMPTY',
 PRIM_FILE='./archive_libs/logical/hole/chips/chips.prt';

PART_NAME
 H93 'HOLE_TH-EMPTY,HOLE596':;

SECTION_NUMBER 1
 '@S9S_MB_2U_LIB.S9S_MB_2U(SCH_1):PAGE289_I148@PURE_QUANTA.HOLE(CHIPS)':
 C_PATH='@s9s_mb_2u_lib.s9s_mb_2u(sch_1):page289_i148@pure_quanta.hole(chips)',
 P_PATH='@s9s_mb_2u_lib.s9s_mb_2u(sch_1):page311_i148@pure_quanta.hole(chips)',
 PATH='I148',
 DRAWING='@S9S_MB_2U_LIB.S9S_MB_2U(SCH_1):PAGE289',
 PHYS_PAGE='311',
 XY='(-425,4400)',
 ROT='0',
 VER='1',
 PACK_TYPE='TH',
 CDS_LIB='pure_quanta',
 CDS_PART_NAME='HOLE_TH-EMPTY,HOLE596',
 MATERIAL='EMPTY',
 PRIM_FILE='./archive_libs/logical/hole/chips/chips.prt';

PART_NAME
 H94 'HOLE_TH-EMPTY,HOLE596':;

SECTION_NUMBER 1
 '@S9S_MB_2U_LIB.S9S_MB_2U(SCH_1):PAGE289_I165@PURE_QUANTA.HOLE(CHIPS)':
 C_PATH='@s9s_mb_2u_lib.s9s_mb_2u(sch_1):page289_i165@pure_quanta.hole(chips)',
 P_PATH='@s9s_mb_2u_lib.s9s_mb_2u(sch_1):page311_i165@pure_quanta.hole(chips)',
 PATH='I165',
 DRAWING='@S9S_MB_2U_LIB.S9S_MB_2U(SCH_1):PAGE289',
 PHYS_PAGE='311',
 XY='(-425,3525)',
 ROT='0',
 VER='1',
 PACK_TYPE='TH',
 CDS_LIB='pure_quanta',
 CDS_PART_NAME='HOLE_TH-EMPTY,HOLE596',
 MATERIAL='EMPTY',
 PRIM_FILE='./archive_libs/logical/hole/chips/chips.prt';

PART_NAME
 H95 'HOLE_TH-EMPTY,HOLE596':;

SECTION_NUMBER 1
 '@S9S_MB_2U_LIB.S9S_MB_2U(SCH_1):PAGE289_I150@PURE_QUANTA.HOLE(CHIPS)':
 C_PATH='@s9s_mb_2u_lib.s9s_mb_2u(sch_1):page289_i150@pure_quanta.hole(chips)',
 P_PATH='@s9s_mb_2u_lib.s9s_mb_2u(sch_1):page311_i150@pure_quanta.hole(chips)',
 PATH='I150',
 DRAWING='@S9S_MB_2U_LIB.S9S_MB_2U(SCH_1):PAGE289',
 PHYS_PAGE='311',
 XY='(250,4400)',
 ROT='0',
 VER='1',
 PACK_TYPE='TH',
 CDS_LIB='pure_quanta',
 CDS_PART_NAME='HOLE_TH-EMPTY,HOLE596',
 MATERIAL='EMPTY',
 PRIM_FILE='./archive_libs/logical/hole/chips/chips.prt';

PART_NAME
 H96 'HOLE_TH-EMPTY,HOLE596':;

SECTION_NUMBER 1
 '@S9S_MB_2U_LIB.S9S_MB_2U(SCH_1):PAGE289_I161@PURE_QUANTA.HOLE(CHIPS)':
 C_PATH='@s9s_mb_2u_lib.s9s_mb_2u(sch_1):page289_i161@pure_quanta.hole(chips)',
 P_PATH='@s9s_mb_2u_lib.s9s_mb_2u(sch_1):page311_i161@pure_quanta.hole(chips)',
 PATH='I161',
 DRAWING='@S9S_MB_2U_LIB.S9S_MB_2U(SCH_1):PAGE289',
 PHYS_PAGE='311',
 XY='(250,3525)',
 ROT='0',
 VER='1',
 PACK_TYPE='TH',
 CDS_LIB='pure_quanta',
 CDS_PART_NAME='HOLE_TH-EMPTY,HOLE596',
 MATERIAL='EMPTY',
 PRIM_FILE='./archive_libs/logical/hole/chips/chips.prt';

PART_NAME
 H97 'HOLE_TH-EMPTY,HOLE596':;

SECTION_NUMBER 1
 '@S9S_MB_2U_LIB.S9S_MB_2U(SCH_1):PAGE289_I149@PURE_QUANTA.HOLE(CHIPS)':
 C_PATH='@s9s_mb_2u_lib.s9s_mb_2u(sch_1):page289_i149@pure_quanta.hole(chips)',
 P_PATH='@s9s_mb_2u_lib.s9s_mb_2u(sch_1):page311_i149@pure_quanta.hole(chips)',
 PATH='I149',
 DRAWING='@S9S_MB_2U_LIB.S9S_MB_2U(SCH_1):PAGE289',
 PHYS_PAGE='311',
 XY='(925,4400)',
 ROT='0',
 VER='1',
 PACK_TYPE='TH',
 CDS_LIB='pure_quanta',
 CDS_PART_NAME='HOLE_TH-EMPTY,HOLE596',
 MATERIAL='EMPTY',
 PRIM_FILE='./archive_libs/logical/hole/chips/chips.prt';

PART_NAME
 H98 'HOLE_TH-EMPTY,HOLE596':;

SECTION_NUMBER 1
 '@S9S_MB_2U_LIB.S9S_MB_2U(SCH_1):PAGE289_I160@PURE_QUANTA.HOLE(CHIPS)':
 C_PATH='@s9s_mb_2u_lib.s9s_mb_2u(sch_1):page289_i160@pure_quanta.hole(chips)',
 P_PATH='@s9s_mb_2u_lib.s9s_mb_2u(sch_1):page311_i160@pure_quanta.hole(chips)',
 PATH='I160',
 DRAWING='@S9S_MB_2U_LIB.S9S_MB_2U(SCH_1):PAGE289',
 PHYS_PAGE='311',
 XY='(925,3525)',
 ROT='0',
 VER='1',
 PACK_TYPE='TH',
 CDS_LIB='pure_quanta',
 CDS_PART_NAME='HOLE_TH-EMPTY,HOLE596',
 MATERIAL='EMPTY',
 PRIM_FILE='./archive_libs/logical/hole/chips/chips.prt';

PART_NAME
 H99 'HOLE_TH-EMPTY,HOLE596':;

SECTION_NUMBER 1
 '@S9S_MB_2U_LIB.S9S_MB_2U(SCH_1):PAGE289_I155@PURE_QUANTA.HOLE(CHIPS)':
 C_PATH='@s9s_mb_2u_lib.s9s_mb_2u(sch_1):page289_i155@pure_quanta.hole(chips)',
 P_PATH='@s9s_mb_2u_lib.s9s_mb_2u(sch_1):page311_i155@pure_quanta.hole(chips)',
 PATH='I155',
 DRAWING='@S9S_MB_2U_LIB.S9S_MB_2U(SCH_1):PAGE289',
 PHYS_PAGE='311',
 XY='(1625,4425)',
 ROT='0',
 VER='1',
 PACK_TYPE='TH',
 CDS_LIB='pure_quanta',
 CDS_PART_NAME='HOLE_TH-EMPTY,HOLE596',
 MATERIAL='EMPTY',
 PRIM_FILE='./archive_libs/logical/hole/chips/chips.prt';

PART_NAME
 H100 'HOLE_TH-EMPTY,HOLE596':;

SECTION_NUMBER 1
 '@S9S_MB_2U_LIB.S9S_MB_2U(SCH_1):PAGE289_I159@PURE_QUANTA.HOLE(CHIPS)':
 C_PATH='@s9s_mb_2u_lib.s9s_mb_2u(sch_1):page289_i159@pure_quanta.hole(chips)',
 P_PATH='@s9s_mb_2u_lib.s9s_mb_2u(sch_1):page311_i159@pure_quanta.hole(chips)',
 PATH='I159',
 DRAWING='@S9S_MB_2U_LIB.S9S_MB_2U(SCH_1):PAGE289',
 PHYS_PAGE='311',
 XY='(1625,3550)',
 ROT='0',
 VER='1',
 PACK_TYPE='TH',
 CDS_LIB='pure_quanta',
 CDS_PART_NAME='HOLE_TH-EMPTY,HOLE596',
 MATERIAL='EMPTY',
 PRIM_FILE='./archive_libs/logical/hole/chips/chips.prt';

PART_NAME
 H101 'HOLE_TH-EMPTY,HOLE596':;

SECTION_NUMBER 1
 '@S9S_MB_2U_LIB.S9S_MB_2U(SCH_1):PAGE289_I154@PURE_QUANTA.HOLE(CHIPS)':
 C_PATH='@s9s_mb_2u_lib.s9s_mb_2u(sch_1):page289_i154@pure_quanta.hole(chips)',
 P_PATH='@s9s_mb_2u_lib.s9s_mb_2u(sch_1):page311_i154@pure_quanta.hole(chips)',
 PATH='I154',
 DRAWING='@S9S_MB_2U_LIB.S9S_MB_2U(SCH_1):PAGE289',
 PHYS_PAGE='311',
 XY='(2300,4425)',
 ROT='0',
 VER='1',
 PACK_TYPE='TH',
 CDS_LIB='pure_quanta',
 CDS_PART_NAME='HOLE_TH-EMPTY,HOLE596',
 MATERIAL='EMPTY',
 PRIM_FILE='./archive_libs/logical/hole/chips/chips.prt';

PART_NAME
 H102 'HOLE_TH-EMPTY,HOLE596':;

SECTION_NUMBER 1
 '@S9S_MB_2U_LIB.S9S_MB_2U(SCH_1):PAGE289_I158@PURE_QUANTA.HOLE(CHIPS)':
 C_PATH='@s9s_mb_2u_lib.s9s_mb_2u(sch_1):page289_i158@pure_quanta.hole(chips)',
 P_PATH='@s9s_mb_2u_lib.s9s_mb_2u(sch_1):page311_i158@pure_quanta.hole(chips)',
 PATH='I158',
 DRAWING='@S9S_MB_2U_LIB.S9S_MB_2U(SCH_1):PAGE289',
 PHYS_PAGE='311',
 XY='(2300,3550)',
 ROT='0',
 VER='1',
 PACK_TYPE='TH',
 CDS_LIB='pure_quanta',
 CDS_PART_NAME='HOLE_TH-EMPTY,HOLE596',
 MATERIAL='EMPTY',
 PRIM_FILE='./archive_libs/logical/hole/chips/chips.prt';

PART_NAME
 H103 'HOLE_TH-EMPTY,HOLE596':;

SECTION_NUMBER 1
 '@S9S_MB_2U_LIB.S9S_MB_2U(SCH_1):PAGE289_I174@PURE_QUANTA.HOLE(CHIPS)':
 C_PATH='@s9s_mb_2u_lib.s9s_mb_2u(sch_1):page289_i174@pure_quanta.hole(chips)',
 P_PATH='@s9s_mb_2u_lib.s9s_mb_2u(sch_1):page311_i174@pure_quanta.hole(chips)',
 PATH='I174',
 DRAWING='@S9S_MB_2U_LIB.S9S_MB_2U(SCH_1):PAGE289',
 PHYS_PAGE='311',
 XY='(3025,4425)',
 ROT='0',
 VER='1',
 PACK_TYPE='TH',
 CDS_LIB='pure_quanta',
 CDS_PART_NAME='HOLE_TH-EMPTY,HOLE596',
 MATERIAL='EMPTY',
 PRIM_FILE='./archive_libs/logical/hole/chips/chips.prt';

PART_NAME
 H104 'HOLE_TH-EMPTY,HOLE596':;

SECTION_NUMBER 1
 '@S9S_MB_2U_LIB.S9S_MB_2U(SCH_1):PAGE289_I175@PURE_QUANTA.HOLE(CHIPS)':
 C_PATH='@s9s_mb_2u_lib.s9s_mb_2u(sch_1):page289_i175@pure_quanta.hole(chips)',
 P_PATH='@s9s_mb_2u_lib.s9s_mb_2u(sch_1):page311_i175@pure_quanta.hole(chips)',
 PATH='I175',
 DRAWING='@S9S_MB_2U_LIB.S9S_MB_2U(SCH_1):PAGE289',
 PHYS_PAGE='311',
 XY='(3025,3550)',
 ROT='0',
 VER='1',
 PACK_TYPE='TH',
 CDS_LIB='pure_quanta',
 CDS_PART_NAME='HOLE_TH-EMPTY,HOLE596',
 MATERIAL='EMPTY',
 PRIM_FILE='./archive_libs/logical/hole/chips/chips.prt';

PART_NAME
 H105 'HOLE_TH-EMPTY,HOLE596':;

SECTION_NUMBER 1
 '@S9S_MB_2U_LIB.S9S_MB_2U(SCH_1):PAGE289_I192@PURE_QUANTA.HOLE(CHIPS)':
 C_PATH='@s9s_mb_2u_lib.s9s_mb_2u(sch_1):page289_i192@pure_quanta.hole(chips)',
 P_PATH='@s9s_mb_2u_lib.s9s_mb_2u(sch_1):page311_i192@pure_quanta.hole(chips)',
 PATH='I192',
 DRAWING='@S9S_MB_2U_LIB.S9S_MB_2U(SCH_1):PAGE289',
 PHYS_PAGE='311',
 XY='(3675,4425)',
 ROT='0',
 VER='1',
 PACK_TYPE='TH',
 CDS_LIB='pure_quanta',
 CDS_PART_NAME='HOLE_TH-EMPTY,HOLE596',
 MATERIAL='EMPTY',
 PRIM_FILE='./archive_libs/logical/hole/chips/chips.prt';

PART_NAME
 H106 'HOLE_TH-EMPTY,HOLE596':;

SECTION_NUMBER 1
 '@S9S_MB_2U_LIB.S9S_MB_2U(SCH_1):PAGE289_I190@PURE_QUANTA.HOLE(CHIPS)':
 C_PATH='@s9s_mb_2u_lib.s9s_mb_2u(sch_1):page289_i190@pure_quanta.hole(chips)',
 P_PATH='@s9s_mb_2u_lib.s9s_mb_2u(sch_1):page311_i190@pure_quanta.hole(chips)',
 PATH='I190',
 DRAWING='@S9S_MB_2U_LIB.S9S_MB_2U(SCH_1):PAGE289',
 PHYS_PAGE='311',
 XY='(3675,3550)',
 ROT='0',
 VER='1',
 PACK_TYPE='TH',
 CDS_LIB='pure_quanta',
 CDS_PART_NAME='HOLE_TH-EMPTY,HOLE596',
 MATERIAL='EMPTY',
 PRIM_FILE='./archive_libs/logical/hole/chips/chips.prt';

PART_NAME
 H111 'GND_HOLE_TH-EMPTY,GND_HOLE140':;

SECTION_NUMBER 1
 '@S9S_MB_2U_LIB.S9S_MB_2U(SCH_1):PAGE289_I204@PURE_QUANTA.GND_HOLE(CHIPS)':
 C_PATH='@s9s_mb_2u_lib.s9s_mb_2u(sch_1):page289_i204@pure_quanta.gnd_hole(chips~
)',
 P_PATH='@s9s_mb_2u_lib.s9s_mb_2u(sch_1):page311_i204@pure_quanta.gnd_hole(chips~
)',
 PATH='I204',
 DRAWING='@S9S_MB_2U_LIB.S9S_MB_2U(SCH_1):PAGE289',
 PHYS_PAGE='311',
 XY='(-2325,-525)',
 ROT='0',
 VER='1',
 PACK_TYPE='TH',
 CDS_LIB='pure_quanta',
 CDS_PART_NAME='GND_HOLE_TH-EMPTY,GND_HOLE140',
 MATERIAL='EMPTY',
 PRIM_FILE='./archive_libs/logical/gnd_hole/chips/chips.prt';

PART_NAME
 H112 'GND_HOLE_TH-EMPTY,GND_HOLE140':;

SECTION_NUMBER 1
 '@S9S_MB_2U_LIB.S9S_MB_2U(SCH_1):PAGE289_I207@PURE_QUANTA.GND_HOLE(CHIPS)':
 C_PATH='@s9s_mb_2u_lib.s9s_mb_2u(sch_1):page289_i207@pure_quanta.gnd_hole(chips~
)',
 P_PATH='@s9s_mb_2u_lib.s9s_mb_2u(sch_1):page311_i207@pure_quanta.gnd_hole(chips~
)',
 PATH='I207',
 DRAWING='@S9S_MB_2U_LIB.S9S_MB_2U(SCH_1):PAGE289',
 PHYS_PAGE='311',
 XY='(-1550,-525)',
 ROT='0',
 VER='1',
 PACK_TYPE='TH',
 CDS_LIB='pure_quanta',
 CDS_PART_NAME='GND_HOLE_TH-EMPTY,GND_HOLE140',
 MATERIAL='EMPTY',
 PRIM_FILE='./archive_libs/logical/gnd_hole/chips/chips.prt';

PART_NAME
 H113 'GND_HOLE_TH-EMPTY,TMP-QGND_HOLA':;

SECTION_NUMBER 1
 '@S9S_MB_2U_LIB.S9S_MB_2U(SCH_1):PAGE289_I247@PURE_QUANTA.GND_HOLE(CHIPS)':
 C_PATH='@s9s_mb_2u_lib.s9s_mb_2u(sch_1):page289_i247@pure_quanta.gnd_hole(chips~
)',
 P_PATH='@s9s_mb_2u_lib.s9s_mb_2u(sch_1):page311_i247@pure_quanta.gnd_hole(chips~
)',
 PATH='I247',
 DRAWING='@S9S_MB_2U_LIB.S9S_MB_2U(SCH_1):PAGE289',
 PHYS_PAGE='311',
 XY='(-450,-525)',
 ROT='0',
 VER='1',
 PACK_TYPE='TH',
 LOCATION='H113',
 CDS_LIB='pure_quanta',
 CDS_PART_NAME='GND_HOLE_TH-EMPTY,TMP-QGND_HOLA',
 MATERIAL='EMPTY',
 PRIM_FILE='./archive_libs/logical/gnd_hole/chips/chips.prt';

PART_NAME
 H114 'GND_HOLE_TH-EMPTY,TMP-QGND_HOLA':;

SECTION_NUMBER 1
 '@S9S_MB_2U_LIB.S9S_MB_2U(SCH_1):PAGE289_I248@PURE_QUANTA.GND_HOLE(CHIPS)':
 C_PATH='@s9s_mb_2u_lib.s9s_mb_2u(sch_1):page289_i248@pure_quanta.gnd_hole(chips~
)',
 P_PATH='@s9s_mb_2u_lib.s9s_mb_2u(sch_1):page311_i248@pure_quanta.gnd_hole(chips~
)',
 PATH='I248',
 DRAWING='@S9S_MB_2U_LIB.S9S_MB_2U(SCH_1):PAGE289',
 PHYS_PAGE='311',
 XY='(325,-525)',
 ROT='0',
 VER='1',
 PACK_TYPE='TH',
 LOCATION='H114',
 CDS_LIB='pure_quanta',
 CDS_PART_NAME='GND_HOLE_TH-EMPTY,TMP-QGND_HOLA',
 MATERIAL='EMPTY',
 PRIM_FILE='./archive_libs/logical/gnd_hole/chips/chips.prt';

PART_NAME
 H115 'GND_HOLE_TH-EMPTY,GND_HOLE514':;

SECTION_NUMBER 1
 '@S9S_MB_2U_LIB.S9S_MB_2U(SCH_1):PAGE289_I202@PURE_QUANTA.GND_HOLE(CHIPS)':
 C_PATH='@s9s_mb_2u_lib.s9s_mb_2u(sch_1):page289_i202@pure_quanta.gnd_hole(chips~
)',
 P_PATH='@s9s_mb_2u_lib.s9s_mb_2u(sch_1):page311_i202@pure_quanta.gnd_hole(chips~
)',
 PATH='I202',
 DRAWING='@S9S_MB_2U_LIB.S9S_MB_2U(SCH_1):PAGE289',
 PHYS_PAGE='311',
 XY='(1350,-525)',
 ROT='0',
 VER='1',
 PACK_TYPE='TH',
 CDS_LIB='pure_quanta',
 CDS_PART_NAME='GND_HOLE_TH-EMPTY,GND_HOLE514',
 MATERIAL='EMPTY',
 PRIM_FILE='./archive_libs/logical/gnd_hole/chips/chips.prt';

PART_NAME
 H120 'HOLE_TH-EMPTY,TMP-C_T2I_ALEX_1A':;

SECTION_NUMBER 1
 '@S9S_MB_2U_LIB.S9S_MB_2U(SCH_1):PAGE289_I224@PURE_QUANTA.HOLE(CHIPS)':
 C_PATH='@s9s_mb_2u_lib.s9s_mb_2u(sch_1):page289_i224@pure_quanta.hole(chips)',
 P_PATH='@s9s_mb_2u_lib.s9s_mb_2u(sch_1):page311_i224@pure_quanta.hole(chips)',
 PATH='I224',
 DRAWING='@S9S_MB_2U_LIB.S9S_MB_2U(SCH_1):PAGE289',
 PHYS_PAGE='311',
 XY='(2750,-825)',
 ROT='0',
 VER='1',
 PACK_TYPE='TH',
 CDS_LIB='pure_quanta',
 CDS_PART_NAME='HOLE_TH-EMPTY,TMP-C_T2I_ALEX_1A',
 MATERIAL='EMPTY',
 PRIM_FILE='./archive_libs/logical/hole/chips/chips.prt';

PART_NAME
 H122 'HOLE_TH-EMPTY,TMP-C_T2I_ALEX_1A':;

SECTION_NUMBER 1
 '@S9S_MB_2U_LIB.S9S_MB_2U(SCH_1):PAGE289_I225@PURE_QUANTA.HOLE(CHIPS)':
 C_PATH='@s9s_mb_2u_lib.s9s_mb_2u(sch_1):page289_i225@pure_quanta.hole(chips)',
 P_PATH='@s9s_mb_2u_lib.s9s_mb_2u(sch_1):page311_i225@pure_quanta.hole(chips)',
 PATH='I225',
 DRAWING='@S9S_MB_2U_LIB.S9S_MB_2U(SCH_1):PAGE289',
 PHYS_PAGE='311',
 XY='(3500,-850)',
 ROT='0',
 VER='1',
 PACK_TYPE='TH',
 CDS_LIB='pure_quanta',
 CDS_PART_NAME='HOLE_TH-EMPTY,TMP-C_T2I_ALEX_1A',
 MATERIAL='EMPTY',
 PRIM_FILE='./archive_libs/logical/hole/chips/chips.prt';

PART_NAME
 H124 'HOLE_TH-EMPTY,TMP-C_T2I_ALEX_1A':;

SECTION_NUMBER 1
 '@S9S_MB_2U_LIB.S9S_MB_2U(SCH_1):PAGE289_I226@PURE_QUANTA.HOLE(CHIPS)':
 C_PATH='@s9s_mb_2u_lib.s9s_mb_2u(sch_1):page289_i226@pure_quanta.hole(chips)',
 P_PATH='@s9s_mb_2u_lib.s9s_mb_2u(sch_1):page311_i226@pure_quanta.hole(chips)',
 PATH='I226',
 DRAWING='@S9S_MB_2U_LIB.S9S_MB_2U(SCH_1):PAGE289',
 PHYS_PAGE='311',
 XY='(4275,-850)',
 ROT='0',
 VER='1',
 PACK_TYPE='TH',
 CDS_LIB='pure_quanta',
 CDS_PART_NAME='HOLE_TH-EMPTY,TMP-C_T2I_ALEX_1A',
 MATERIAL='EMPTY',
 PRIM_FILE='./archive_libs/logical/hole/chips/chips.prt';

PART_NAME
 H125 'HOLE_TH-EMPTY,TMP-C_T2I_ALEX_1A':;

SECTION_NUMBER 1
 '@S9S_MB_2U_LIB.S9S_MB_2U(SCH_1):PAGE289_I229@PURE_QUANTA.HOLE(CHIPS)':
 C_PATH='@s9s_mb_2u_lib.s9s_mb_2u(sch_1):page289_i229@pure_quanta.hole(chips)',
 P_PATH='@s9s_mb_2u_lib.s9s_mb_2u(sch_1):page311_i229@pure_quanta.hole(chips)',
 PATH='I229',
 DRAWING='@S9S_MB_2U_LIB.S9S_MB_2U(SCH_1):PAGE289',
 PHYS_PAGE='311',
 XY='(4300,-375)',
 ROT='0',
 VER='1',
 PACK_TYPE='TH',
 CDS_LIB='pure_quanta',
 CDS_PART_NAME='HOLE_TH-EMPTY,TMP-C_T2I_ALEX_1A',
 MATERIAL='EMPTY',
 PRIM_FILE='./archive_libs/logical/hole/chips/chips.prt';

PART_NAME
 H126 'HOLE_TH-EMPTY,TMP-C_T2I_ALEX_1A':;

SECTION_NUMBER 1
 '@S9S_MB_2U_LIB.S9S_MB_2U(SCH_1):PAGE289_I227@PURE_QUANTA.HOLE(CHIPS)':
 C_PATH='@s9s_mb_2u_lib.s9s_mb_2u(sch_1):page289_i227@pure_quanta.hole(chips)',
 P_PATH='@s9s_mb_2u_lib.s9s_mb_2u(sch_1):page311_i227@pure_quanta.hole(chips)',
 PATH='I227',
 DRAWING='@S9S_MB_2U_LIB.S9S_MB_2U(SCH_1):PAGE289',
 PHYS_PAGE='311',
 XY='(5050,-850)',
 ROT='0',
 VER='1',
 PACK_TYPE='TH',
 CDS_LIB='pure_quanta',
 CDS_PART_NAME='HOLE_TH-EMPTY,TMP-C_T2I_ALEX_1A',
 MATERIAL='EMPTY',
 PRIM_FILE='./archive_libs/logical/hole/chips/chips.prt';

PART_NAME
 H127 'HOLE_TH-EMPTY,TMP-C_T2I_ALEX_1A':;

SECTION_NUMBER 1
 '@S9S_MB_2U_LIB.S9S_MB_2U(SCH_1):PAGE289_I228@PURE_QUANTA.HOLE(CHIPS)':
 C_PATH='@s9s_mb_2u_lib.s9s_mb_2u(sch_1):page289_i228@pure_quanta.hole(chips)',
 P_PATH='@s9s_mb_2u_lib.s9s_mb_2u(sch_1):page311_i228@pure_quanta.hole(chips)',
 PATH='I228',
 DRAWING='@S9S_MB_2U_LIB.S9S_MB_2U(SCH_1):PAGE289',
 PHYS_PAGE='311',
 XY='(5075,-375)',
 ROT='0',
 VER='1',
 PACK_TYPE='TH',
 CDS_LIB='pure_quanta',
 CDS_PART_NAME='HOLE_TH-EMPTY,TMP-C_T2I_ALEX_1A',
 MATERIAL='EMPTY',
 PRIM_FILE='./archive_libs/logical/hole/chips/chips.prt';

PART_NAME
 H128 'HOLE_TH-EMPTY,HOLE596':;

SECTION_NUMBER 1
 '@S9S_MB_2U_LIB.S9S_MB_2U(SCH_1):PAGE289_I232@PURE_QUANTA.HOLE(CHIPS)':
 C_PATH='@s9s_mb_2u_lib.s9s_mb_2u(sch_1):page289_i232@pure_quanta.hole(chips)',
 P_PATH='@s9s_mb_2u_lib.s9s_mb_2u(sch_1):page311_i232@pure_quanta.hole(chips)',
 PATH='I232',
 DRAWING='@S9S_MB_2U_LIB.S9S_MB_2U(SCH_1):PAGE289',
 PHYS_PAGE='311',
 XY='(4350,4425)',
 ROT='0',
 VER='1',
 PACK_TYPE='TH',
 CDS_LIB='pure_quanta',
 CDS_PART_NAME='HOLE_TH-EMPTY,HOLE596',
 MATERIAL='EMPTY',
 PRIM_FILE='./archive_libs/logical/hole/chips/chips.prt';

PART_NAME
 H129 'HOLE_TH-EMPTY,HOLE1195':;

SECTION_NUMBER 1
 '@S9S_MB_2U_LIB.S9S_MB_2U(SCH_1):PAGE289_I249@PURE_QUANTA.HOLE(CHIPS)':
 C_PATH='@s9s_mb_2u_lib.s9s_mb_2u(sch_1):page289_i249@pure_quanta.hole(chips)',
 P_PATH='@s9s_mb_2u_lib.s9s_mb_2u(sch_1):page311_i249@pure_quanta.hole(chips)',
 PATH='I249',
 DRAWING='@S9S_MB_2U_LIB.S9S_MB_2U(SCH_1):PAGE289',
 PHYS_PAGE='311',
 XY='(5400,1150)',
 ROT='0',
 VER='1',
 PACK_TYPE='TH',
 LOCATION='H129',
 CDS_LIB='pure_quanta',
 CDS_PART_NAME='HOLE_TH-EMPTY,HOLE1195',
 MATERIAL='EMPTY',
 PRIM_FILE='./archive_libs/logical/hole/chips/chips.prt';

PART_NAME
 J1 'SCONN288_ADR50017P130CC-SCONN2A':;

SECTION_NUMBER 1
 '@S9S_MB_2U_LIB.S9S_MB_2U(SCH_1):PAGE82_I198@PURE_QUANTA.SCONN288_ADR50017P130CC(CHIPS)':
 C_PATH='@s9s_mb_2u_lib.s9s_mb_2u(sch_1):page82_i198@pure_quanta.sconn288_adr500~
17p130cc(chips)',
 P_PATH='@s9s_mb_2u_lib.s9s_mb_2u(sch_1):page82_i198@pure_quanta.sconn288_adr500~
17p130cc(chips)',
 PATH='I198',
 DRAWING='@S9S_MB_2U_LIB.S9S_MB_2U(SCH_1):PAGE82',
 PHYS_PAGE='82',
 XY='(-1475,2575)',
 ROT='0',
 VER='1',
 CDS_LIB='pure_quanta',
 CDS_PART_NAME='SCONN288_ADR50017P130CC-SCONN2A',
 PART_TYPE='SMLF',
 MATERIAL='IO',
 VALUE='SCONN288_ADR50017-P130CC',
 PRIM_FILE='./archive_libs/logical/sconn288_adr50017p130cc/chips/chips.prt';

SECTION_NUMBER 2
 '@S9S_MB_2U_LIB.S9S_MB_2U(SCH_1):PAGE82_I202@PURE_QUANTA.SCONN288_ADR50017P130CC(CHIPS)':
 C_PATH='@s9s_mb_2u_lib.s9s_mb_2u(sch_1):page82_i202@pure_quanta.sconn288_adr500~
17p130cc(chips)',
 P_PATH='@s9s_mb_2u_lib.s9s_mb_2u(sch_1):page82_i202@pure_quanta.sconn288_adr500~
17p130cc(chips)',
 PATH='I202',
 DRAWING='@S9S_MB_2U_LIB.S9S_MB_2U(SCH_1):PAGE82',
 PHYS_PAGE='82',
 XY='(1300,3300)',
 ROT='0',
 VER='2',
 LOCATION='J1',
 CDS_LIB='pure_quanta',
 CDS_PART_NAME='SCONN288_ADR50017P130CC-SCONN2A',
 PART_TYPE='SMLF',
 MATERIAL='IO',
 VALUE='SCONN288_ADR50017-P130CC',
 PRIM_FILE='./archive_libs/logical/sconn288_adr50017p130cc/chips/chips.prt';

SECTION_NUMBER 3
 '@S9S_MB_2U_LIB.S9S_MB_2U(SCH_1):PAGE82_I203@PURE_QUANTA.SCONN288_ADR50017P130CC(CHIPS)':
 C_PATH='@s9s_mb_2u_lib.s9s_mb_2u(sch_1):page82_i203@pure_quanta.sconn288_adr500~
17p130cc(chips)',
 P_PATH='@s9s_mb_2u_lib.s9s_mb_2u(sch_1):page82_i203@pure_quanta.sconn288_adr500~
17p130cc(chips)',
 PATH='I203',
 DRAWING='@S9S_MB_2U_LIB.S9S_MB_2U(SCH_1):PAGE82',
 PHYS_PAGE='82',
 XY='(4625,2675)',
 ROT='0',
 VER='3',
 LOCATION='J1',
 CDS_LIB='pure_quanta',
 CDS_PART_NAME='SCONN288_ADR50017P130CC-SCONN2A',
 PART_TYPE='SMLF',
 MATERIAL='IO',
 VALUE='SCONN288_ADR50017-P130CC',
 PRIM_FILE='./archive_libs/logical/sconn288_adr50017p130cc/chips/chips.prt';

PART_NAME
 J2 'SCONN288_ADR50017P087CC-SCONN2A':;

SECTION_NUMBER 1
 '@S9S_MB_2U_LIB.S9S_MB_2U(SCH_1):PAGE83_I177@PURE_QUANTA.SCONN288_ADR50017P087CC(CHIPS)':
 C_PATH='@s9s_mb_2u_lib.s9s_mb_2u(sch_1):page83_i177@pure_quanta.sconn288_adr500~
17p087cc(chips)',
 P_PATH='@s9s_mb_2u_lib.s9s_mb_2u(sch_1):page83_i177@pure_quanta.sconn288_adr500~
17p087cc(chips)',
 PATH='I177',
 DRAWING='@S9S_MB_2U_LIB.S9S_MB_2U(SCH_1):PAGE83',
 PHYS_PAGE='83',
 XY='(-825,2475)',
 ROT='0',
 VER='1',
 CDS_LIB='pure_quanta',
 CDS_PART_NAME='SCONN288_ADR50017P087CC-SCONN2A',
 PART_TYPE='SMLF',
 MATERIAL='IO',
 VALUE='SCONN288_ADR50017-P087CC',
 PRIM_FILE='./archive_libs/logical/sconn288_adr50017p087cc/chips/chips.prt';

SECTION_NUMBER 2
 '@S9S_MB_2U_LIB.S9S_MB_2U(SCH_1):PAGE83_I181@PURE_QUANTA.SCONN288_ADR50017P087CC(CHIPS)':
 C_PATH='@s9s_mb_2u_lib.s9s_mb_2u(sch_1):page83_i181@pure_quanta.sconn288_adr500~
17p087cc(chips)',
 P_PATH='@s9s_mb_2u_lib.s9s_mb_2u(sch_1):page83_i181@pure_quanta.sconn288_adr500~
17p087cc(chips)',
 PATH='I181',
 DRAWING='@S9S_MB_2U_LIB.S9S_MB_2U(SCH_1):PAGE83',
 PHYS_PAGE='83',
 XY='(1825,3200)',
 ROT='0',
 VER='2',
 LOCATION='J2',
 CDS_LIB='pure_quanta',
 CDS_PART_NAME='SCONN288_ADR50017P087CC-SCONN2A',
 PART_TYPE='SMLF',
 MATERIAL='IO',
 VALUE='SCONN288_ADR50017-P087CC',
 PRIM_FILE='./archive_libs/logical/sconn288_adr50017p087cc/chips/chips.prt';

SECTION_NUMBER 3
 '@S9S_MB_2U_LIB.S9S_MB_2U(SCH_1):PAGE83_I179@PURE_QUANTA.SCONN288_ADR50017P087CC(CHIPS)':
 C_PATH='@s9s_mb_2u_lib.s9s_mb_2u(sch_1):page83_i179@pure_quanta.sconn288_adr500~
17p087cc(chips)',
 P_PATH='@s9s_mb_2u_lib.s9s_mb_2u(sch_1):page83_i179@pure_quanta.sconn288_adr500~
17p087cc(chips)',
 PATH='I179',
 DRAWING='@S9S_MB_2U_LIB.S9S_MB_2U(SCH_1):PAGE83',
 PHYS_PAGE='83',
 XY='(5200,2575)',
 ROT='0',
 VER='3',
 CDS_LIB='pure_quanta',
 CDS_PART_NAME='SCONN288_ADR50017P087CC-SCONN2A',
 PART_TYPE='SMLF',
 MATERIAL='IO',
 VALUE='SCONN288_ADR50017-P087CC',
 PRIM_FILE='./archive_libs/logical/sconn288_adr50017p087cc/chips/chips.prt';

PART_NAME
 J3 'SCONN288_ADR50017P130CC-SCONN2A':;

SECTION_NUMBER 1
 '@S9S_MB_2U_LIB.S9S_MB_2U(SCH_1):PAGE84_I180@PURE_QUANTA.SCONN288_ADR50017P130CC(CHIPS)':
 C_PATH='@s9s_mb_2u_lib.s9s_mb_2u(sch_1):page84_i180@pure_quanta.sconn288_adr500~
17p130cc(chips)',
 P_PATH='@s9s_mb_2u_lib.s9s_mb_2u(sch_1):page84_i180@pure_quanta.sconn288_adr500~
17p130cc(chips)',
 PATH='I180',
 DRAWING='@S9S_MB_2U_LIB.S9S_MB_2U(SCH_1):PAGE84',
 PHYS_PAGE='84',
 XY='(-925,2175)',
 ROT='0',
 VER='1',
 LOCATION='J3',
 CDS_LIB='pure_quanta',
 CDS_PART_NAME='SCONN288_ADR50017P130CC-SCONN2A',
 PART_TYPE='SMLF',
 MATERIAL='IO',
 VALUE='SCONN288_ADR50017-P130CC',
 PRIM_FILE='./archive_libs/logical/sconn288_adr50017p130cc/chips/chips.prt';

SECTION_NUMBER 2
 '@S9S_MB_2U_LIB.S9S_MB_2U(SCH_1):PAGE84_I179@PURE_QUANTA.SCONN288_ADR50017P130CC(CHIPS)':
 C_PATH='@s9s_mb_2u_lib.s9s_mb_2u(sch_1):page84_i179@pure_quanta.sconn288_adr500~
17p130cc(chips)',
 P_PATH='@s9s_mb_2u_lib.s9s_mb_2u(sch_1):page84_i179@pure_quanta.sconn288_adr500~
17p130cc(chips)',
 PATH='I179',
 DRAWING='@S9S_MB_2U_LIB.S9S_MB_2U(SCH_1):PAGE84',
 PHYS_PAGE='84',
 XY='(1725,2900)',
 ROT='0',
 VER='2',
 LOCATION='J3',
 CDS_LIB='pure_quanta',
 CDS_PART_NAME='SCONN288_ADR50017P130CC-SCONN2A',
 PART_TYPE='SMLF',
 MATERIAL='IO',
 VALUE='SCONN288_ADR50017-P130CC',
 PRIM_FILE='./archive_libs/logical/sconn288_adr50017p130cc/chips/chips.prt';

SECTION_NUMBER 3
 '@S9S_MB_2U_LIB.S9S_MB_2U(SCH_1):PAGE84_I178@PURE_QUANTA.SCONN288_ADR50017P130CC(CHIPS)':
 C_PATH='@s9s_mb_2u_lib.s9s_mb_2u(sch_1):page84_i178@pure_quanta.sconn288_adr500~
17p130cc(chips)',
 P_PATH='@s9s_mb_2u_lib.s9s_mb_2u(sch_1):page84_i178@pure_quanta.sconn288_adr500~
17p130cc(chips)',
 PATH='I178',
 DRAWING='@S9S_MB_2U_LIB.S9S_MB_2U(SCH_1):PAGE84',
 PHYS_PAGE='84',
 XY='(5175,2275)',
 ROT='0',
 VER='3',
 LOCATION='J3',
 CDS_LIB='pure_quanta',
 CDS_PART_NAME='SCONN288_ADR50017P130CC-SCONN2A',
 PART_TYPE='SMLF',
 MATERIAL='IO',
 VALUE='SCONN288_ADR50017-P130CC',
 PRIM_FILE='./archive_libs/logical/sconn288_adr50017p130cc/chips/chips.prt';

PART_NAME
 J4 'SCONN288_ADR50017P087CC-SCONN2A':;

SECTION_NUMBER 1
 '@S9S_MB_2U_LIB.S9S_MB_2U(SCH_1):PAGE85_I23@PURE_QUANTA.SCONN288_ADR50017P087CC(CHIPS)':
 C_PATH='@s9s_mb_2u_lib.s9s_mb_2u(sch_1):page85_i23@pure_quanta.sconn288_adr5001~
7p087cc(chips)',
 P_PATH='@s9s_mb_2u_lib.s9s_mb_2u(sch_1):page85_i23@pure_quanta.sconn288_adr5001~
7p087cc(chips)',
 PATH='I23',
 DRAWING='@S9S_MB_2U_LIB.S9S_MB_2U(SCH_1):PAGE85',
 PHYS_PAGE='85',
 XY='(-1350,2675)',
 ROT='0',
 VER='1',
 CDS_LIB='pure_quanta',
 CDS_PART_NAME='SCONN288_ADR50017P087CC-SCONN2A',
 PART_TYPE='SMLF',
 MATERIAL='IO',
 VALUE='SCONN288_ADR50017-P087CC',
 PRIM_FILE='./archive_libs/logical/sconn288_adr50017p087cc/chips/chips.prt';

SECTION_NUMBER 2
 '@S9S_MB_2U_LIB.S9S_MB_2U(SCH_1):PAGE85_I178@PURE_QUANTA.SCONN288_ADR50017P087CC(CHIPS)':
 C_PATH='@s9s_mb_2u_lib.s9s_mb_2u(sch_1):page85_i178@pure_quanta.sconn288_adr500~
17p087cc(chips)',
 P_PATH='@s9s_mb_2u_lib.s9s_mb_2u(sch_1):page85_i178@pure_quanta.sconn288_adr500~
17p087cc(chips)',
 PATH='I178',
 DRAWING='@S9S_MB_2U_LIB.S9S_MB_2U(SCH_1):PAGE85',
 PHYS_PAGE='85',
 XY='(1325,3400)',
 ROT='0',
 VER='2',
 LOCATION='J4',
 CDS_LIB='pure_quanta',
 CDS_PART_NAME='SCONN288_ADR50017P087CC-SCONN2A',
 PART_TYPE='SMLF',
 MATERIAL='IO',
 VALUE='SCONN288_ADR50017-P087CC',
 PRIM_FILE='./archive_libs/logical/sconn288_adr50017p087cc/chips/chips.prt';

SECTION_NUMBER 3
 '@S9S_MB_2U_LIB.S9S_MB_2U(SCH_1):PAGE85_I174@PURE_QUANTA.SCONN288_ADR50017P087CC(CHIPS)':
 C_PATH='@s9s_mb_2u_lib.s9s_mb_2u(sch_1):page85_i174@pure_quanta.sconn288_adr500~
17p087cc(chips)',
 P_PATH='@s9s_mb_2u_lib.s9s_mb_2u(sch_1):page85_i174@pure_quanta.sconn288_adr500~
17p087cc(chips)',
 PATH='I174',
 DRAWING='@S9S_MB_2U_LIB.S9S_MB_2U(SCH_1):PAGE85',
 PHYS_PAGE='85',
 XY='(4750,2775)',
 ROT='0',
 VER='3',
 CDS_LIB='pure_quanta',
 CDS_PART_NAME='SCONN288_ADR50017P087CC-SCONN2A',
 PART_TYPE='SMLF',
 MATERIAL='IO',
 VALUE='SCONN288_ADR50017-P087CC',
 PRIM_FILE='./archive_libs/logical/sconn288_adr50017p087cc/chips/chips.prt';

PART_NAME
 J5 'SCONN288_ADR50017P130CC-SCONN2A':;

SECTION_NUMBER 1
 '@S9S_MB_2U_LIB.S9S_MB_2U(SCH_1):PAGE86_I24@PURE_QUANTA.SCONN288_ADR50017P130CC(CHIPS)':
 C_PATH='@s9s_mb_2u_lib.s9s_mb_2u(sch_1):page86_i24@pure_quanta.sconn288_adr5001~
7p130cc(chips)',
 P_PATH='@s9s_mb_2u_lib.s9s_mb_2u(sch_1):page86_i24@pure_quanta.sconn288_adr5001~
7p130cc(chips)',
 PATH='I24',
 DRAWING='@S9S_MB_2U_LIB.S9S_MB_2U(SCH_1):PAGE86',
 PHYS_PAGE='86',
 XY='(-2050,2425)',
 ROT='0',
 VER='1',
 CDS_LIB='pure_quanta',
 CDS_PART_NAME='SCONN288_ADR50017P130CC-SCONN2A',
 PART_TYPE='SMLF',
 MATERIAL='IO',
 VALUE='SCONN288_ADR50017-P130CC',
 PRIM_FILE='./archive_libs/logical/sconn288_adr50017p130cc/chips/chips.prt';

SECTION_NUMBER 2
 '@S9S_MB_2U_LIB.S9S_MB_2U(SCH_1):PAGE86_I178@PURE_QUANTA.SCONN288_ADR50017P130CC(CHIPS)':
 C_PATH='@s9s_mb_2u_lib.s9s_mb_2u(sch_1):page86_i178@pure_quanta.sconn288_adr500~
17p130cc(chips)',
 P_PATH='@s9s_mb_2u_lib.s9s_mb_2u(sch_1):page86_i178@pure_quanta.sconn288_adr500~
17p130cc(chips)',
 PATH='I178',
 DRAWING='@S9S_MB_2U_LIB.S9S_MB_2U(SCH_1):PAGE86',
 PHYS_PAGE='86',
 XY='(625,3150)',
 ROT='0',
 VER='2',
 LOCATION='J5',
 CDS_LIB='pure_quanta',
 CDS_PART_NAME='SCONN288_ADR50017P130CC-SCONN2A',
 PART_TYPE='SMLF',
 MATERIAL='IO',
 VALUE='SCONN288_ADR50017-P130CC',
 PRIM_FILE='./archive_libs/logical/sconn288_adr50017p130cc/chips/chips.prt';

SECTION_NUMBER 3
 '@S9S_MB_2U_LIB.S9S_MB_2U(SCH_1):PAGE86_I174@PURE_QUANTA.SCONN288_ADR50017P130CC(CHIPS)':
 C_PATH='@s9s_mb_2u_lib.s9s_mb_2u(sch_1):page86_i174@pure_quanta.sconn288_adr500~
17p130cc(chips)',
 P_PATH='@s9s_mb_2u_lib.s9s_mb_2u(sch_1):page86_i174@pure_quanta.sconn288_adr500~
17p130cc(chips)',
 PATH='I174',
 DRAWING='@S9S_MB_2U_LIB.S9S_MB_2U(SCH_1):PAGE86',
 PHYS_PAGE='86',
 XY='(4050,2525)',
 ROT='0',
 VER='3',
 CDS_LIB='pure_quanta',
 CDS_PART_NAME='SCONN288_ADR50017P130CC-SCONN2A',
 PART_TYPE='SMLF',
 MATERIAL='IO',
 VALUE='SCONN288_ADR50017-P130CC',
 PRIM_FILE='./archive_libs/logical/sconn288_adr50017p130cc/chips/chips.prt';

PART_NAME
 J6 'SCONN288_ADR50017P087CC-SCONN2A':;

SECTION_NUMBER 1
 '@S9S_MB_2U_LIB.S9S_MB_2U(SCH_1):PAGE87_I46@PURE_QUANTA.SCONN288_ADR50017P087CC(CHIPS)':
 C_PATH='@s9s_mb_2u_lib.s9s_mb_2u(sch_1):page87_i46@pure_quanta.sconn288_adr5001~
7p087cc(chips)',
 P_PATH='@s9s_mb_2u_lib.s9s_mb_2u(sch_1):page87_i46@pure_quanta.sconn288_adr5001~
7p087cc(chips)',
 PATH='I46',
 DRAWING='@S9S_MB_2U_LIB.S9S_MB_2U(SCH_1):PAGE87',
 PHYS_PAGE='87',
 XY='(-1275,2475)',
 ROT='0',
 VER='1',
 CDS_LIB='pure_quanta',
 CDS_PART_NAME='SCONN288_ADR50017P087CC-SCONN2A',
 PART_TYPE='SMLF',
 MATERIAL='IO',
 VALUE='SCONN288_ADR50017-P087CC',
 PRIM_FILE='./archive_libs/logical/sconn288_adr50017p087cc/chips/chips.prt';

SECTION_NUMBER 2
 '@S9S_MB_2U_LIB.S9S_MB_2U(SCH_1):PAGE87_I178@PURE_QUANTA.SCONN288_ADR50017P087CC(CHIPS)':
 C_PATH='@s9s_mb_2u_lib.s9s_mb_2u(sch_1):page87_i178@pure_quanta.sconn288_adr500~
17p087cc(chips)',
 P_PATH='@s9s_mb_2u_lib.s9s_mb_2u(sch_1):page87_i178@pure_quanta.sconn288_adr500~
17p087cc(chips)',
 PATH='I178',
 DRAWING='@S9S_MB_2U_LIB.S9S_MB_2U(SCH_1):PAGE87',
 PHYS_PAGE='87',
 XY='(1400,3200)',
 ROT='0',
 VER='2',
 LOCATION='J6',
 CDS_LIB='pure_quanta',
 CDS_PART_NAME='SCONN288_ADR50017P087CC-SCONN2A',
 PART_TYPE='SMLF',
 MATERIAL='IO',
 VALUE='SCONN288_ADR50017-P087CC',
 PRIM_FILE='./archive_libs/logical/sconn288_adr50017p087cc/chips/chips.prt';

SECTION_NUMBER 3
 '@S9S_MB_2U_LIB.S9S_MB_2U(SCH_1):PAGE87_I175@PURE_QUANTA.SCONN288_ADR50017P087CC(CHIPS)':
 C_PATH='@s9s_mb_2u_lib.s9s_mb_2u(sch_1):page87_i175@pure_quanta.sconn288_adr500~
17p087cc(chips)',
 P_PATH='@s9s_mb_2u_lib.s9s_mb_2u(sch_1):page87_i175@pure_quanta.sconn288_adr500~
17p087cc(chips)',
 PATH='I175',
 DRAWING='@S9S_MB_2U_LIB.S9S_MB_2U(SCH_1):PAGE87',
 PHYS_PAGE='87',
 XY='(4825,2575)',
 ROT='0',
 VER='3',
 CDS_LIB='pure_quanta',
 CDS_PART_NAME='SCONN288_ADR50017P087CC-SCONN2A',
 PART_TYPE='SMLF',
 MATERIAL='IO',
 VALUE='SCONN288_ADR50017-P087CC',
 PRIM_FILE='./archive_libs/logical/sconn288_adr50017p087cc/chips/chips.prt';

PART_NAME
 J7 'SCONN288_ADR50017P130CC-SCONN2A':;

SECTION_NUMBER 1
 '@S9S_MB_2U_LIB.S9S_MB_2U(SCH_1):PAGE88_I12@PURE_QUANTA.SCONN288_ADR50017P130CC(CHIPS)':
 C_PATH='@s9s_mb_2u_lib.s9s_mb_2u(sch_1):page88_i12@pure_quanta.sconn288_adr5001~
7p130cc(chips)',
 P_PATH='@s9s_mb_2u_lib.s9s_mb_2u(sch_1):page88_i12@pure_quanta.sconn288_adr5001~
7p130cc(chips)',
 PATH='I12',
 DRAWING='@S9S_MB_2U_LIB.S9S_MB_2U(SCH_1):PAGE88',
 PHYS_PAGE='88',
 XY='(-1075,2325)',
 ROT='0',
 VER='1',
 CDS_LIB='pure_quanta',
 CDS_PART_NAME='SCONN288_ADR50017P130CC-SCONN2A',
 PART_TYPE='SMLF',
 MATERIAL='IO',
 VALUE='SCONN288_ADR50017-P130CC',
 PRIM_FILE='./archive_libs/logical/sconn288_adr50017p130cc/chips/chips.prt';

SECTION_NUMBER 2
 '@S9S_MB_2U_LIB.S9S_MB_2U(SCH_1):PAGE88_I178@PURE_QUANTA.SCONN288_ADR50017P130CC(CHIPS)':
 C_PATH='@s9s_mb_2u_lib.s9s_mb_2u(sch_1):page88_i178@pure_quanta.sconn288_adr500~
17p130cc(chips)',
 P_PATH='@s9s_mb_2u_lib.s9s_mb_2u(sch_1):page88_i178@pure_quanta.sconn288_adr500~
17p130cc(chips)',
 PATH='I178',
 DRAWING='@S9S_MB_2U_LIB.S9S_MB_2U(SCH_1):PAGE88',
 PHYS_PAGE='88',
 XY='(1600,3050)',
 ROT='0',
 VER='2',
 LOCATION='J7',
 CDS_LIB='pure_quanta',
 CDS_PART_NAME='SCONN288_ADR50017P130CC-SCONN2A',
 PART_TYPE='SMLF',
 MATERIAL='IO',
 VALUE='SCONN288_ADR50017-P130CC',
 PRIM_FILE='./archive_libs/logical/sconn288_adr50017p130cc/chips/chips.prt';

SECTION_NUMBER 3
 '@S9S_MB_2U_LIB.S9S_MB_2U(SCH_1):PAGE88_I168@PURE_QUANTA.SCONN288_ADR50017P130CC(CHIPS)':
 C_PATH='@s9s_mb_2u_lib.s9s_mb_2u(sch_1):page88_i168@pure_quanta.sconn288_adr500~
17p130cc(chips)',
 P_PATH='@s9s_mb_2u_lib.s9s_mb_2u(sch_1):page88_i168@pure_quanta.sconn288_adr500~
17p130cc(chips)',
 PATH='I168',
 DRAWING='@S9S_MB_2U_LIB.S9S_MB_2U(SCH_1):PAGE88',
 PHYS_PAGE='88',
 XY='(5025,2425)',
 ROT='0',
 VER='3',
 CDS_LIB='pure_quanta',
 CDS_PART_NAME='SCONN288_ADR50017P130CC-SCONN2A',
 PART_TYPE='SMLF',
 MATERIAL='IO',
 VALUE='SCONN288_ADR50017-P130CC',
 PRIM_FILE='./archive_libs/logical/sconn288_adr50017p130cc/chips/chips.prt';

PART_NAME
 J8 'SCONN288_ADR50017P087CC-SCONN2A':;

SECTION_NUMBER 1
 '@S9S_MB_2U_LIB.S9S_MB_2U(SCH_1):PAGE89_I50@PURE_QUANTA.SCONN288_ADR50017P087CC(CHIPS)':
 C_PATH='@s9s_mb_2u_lib.s9s_mb_2u(sch_1):page89_i50@pure_quanta.sconn288_adr5001~
7p087cc(chips)',
 P_PATH='@s9s_mb_2u_lib.s9s_mb_2u(sch_1):page89_i50@pure_quanta.sconn288_adr5001~
7p087cc(chips)',
 PATH='I50',
 DRAWING='@S9S_MB_2U_LIB.S9S_MB_2U(SCH_1):PAGE89',
 PHYS_PAGE='89',
 XY='(-1525,2475)',
 ROT='0',
 VER='1',
 CDS_LIB='pure_quanta',
 CDS_PART_NAME='SCONN288_ADR50017P087CC-SCONN2A',
 PART_TYPE='SMLF',
 MATERIAL='IO',
 VALUE='SCONN288_ADR50017-P087CC',
 PRIM_FILE='./archive_libs/logical/sconn288_adr50017p087cc/chips/chips.prt';

SECTION_NUMBER 2
 '@S9S_MB_2U_LIB.S9S_MB_2U(SCH_1):PAGE89_I178@PURE_QUANTA.SCONN288_ADR50017P087CC(CHIPS)':
 C_PATH='@s9s_mb_2u_lib.s9s_mb_2u(sch_1):page89_i178@pure_quanta.sconn288_adr500~
17p087cc(chips)',
 P_PATH='@s9s_mb_2u_lib.s9s_mb_2u(sch_1):page89_i178@pure_quanta.sconn288_adr500~
17p087cc(chips)',
 PATH='I178',
 DRAWING='@S9S_MB_2U_LIB.S9S_MB_2U(SCH_1):PAGE89',
 PHYS_PAGE='89',
 XY='(1150,3200)',
 ROT='0',
 VER='2',
 LOCATION='J8',
 CDS_LIB='pure_quanta',
 CDS_PART_NAME='SCONN288_ADR50017P087CC-SCONN2A',
 PART_TYPE='SMLF',
 MATERIAL='IO',
 VALUE='SCONN288_ADR50017-P087CC',
 PRIM_FILE='./archive_libs/logical/sconn288_adr50017p087cc/chips/chips.prt';

SECTION_NUMBER 3
 '@S9S_MB_2U_LIB.S9S_MB_2U(SCH_1):PAGE89_I175@PURE_QUANTA.SCONN288_ADR50017P087CC(CHIPS)':
 C_PATH='@s9s_mb_2u_lib.s9s_mb_2u(sch_1):page89_i175@pure_quanta.sconn288_adr500~
17p087cc(chips)',
 P_PATH='@s9s_mb_2u_lib.s9s_mb_2u(sch_1):page89_i175@pure_quanta.sconn288_adr500~
17p087cc(chips)',
 PATH='I175',
 DRAWING='@S9S_MB_2U_LIB.S9S_MB_2U(SCH_1):PAGE89',
 PHYS_PAGE='89',
 XY='(4575,2575)',
 ROT='0',
 VER='3',
 CDS_LIB='pure_quanta',
 CDS_PART_NAME='SCONN288_ADR50017P087CC-SCONN2A',
 PART_TYPE='SMLF',
 MATERIAL='IO',
 VALUE='SCONN288_ADR50017-P087CC',
 PRIM_FILE='./archive_libs/logical/sconn288_adr50017p087cc/chips/chips.prt';

PART_NAME
 J9 'SCONN288_ADR50017P130CC-SCONN2A':;

SECTION_NUMBER 1
 '@S9S_MB_2U_LIB.S9S_MB_2U(SCH_1):PAGE90_I12@PURE_QUANTA.SCONN288_ADR50017P130CC(CHIPS)':
 C_PATH='@s9s_mb_2u_lib.s9s_mb_2u(sch_1):page90_i12@pure_quanta.sconn288_adr5001~
7p130cc(chips)',
 P_PATH='@s9s_mb_2u_lib.s9s_mb_2u(sch_1):page90_i12@pure_quanta.sconn288_adr5001~
7p130cc(chips)',
 PATH='I12',
 DRAWING='@S9S_MB_2U_LIB.S9S_MB_2U(SCH_1):PAGE90',
 PHYS_PAGE='90',
 XY='(-825,2300)',
 ROT='0',
 VER='1',
 CDS_LIB='pure_quanta',
 CDS_PART_NAME='SCONN288_ADR50017P130CC-SCONN2A',
 PART_TYPE='SMLF',
 MATERIAL='IO',
 VALUE='SCONN288_ADR50017-P130CC',
 PRIM_FILE='./archive_libs/logical/sconn288_adr50017p130cc/chips/chips.prt';

SECTION_NUMBER 2
 '@S9S_MB_2U_LIB.S9S_MB_2U(SCH_1):PAGE90_I178@PURE_QUANTA.SCONN288_ADR50017P130CC(CHIPS)':
 C_PATH='@s9s_mb_2u_lib.s9s_mb_2u(sch_1):page90_i178@pure_quanta.sconn288_adr500~
17p130cc(chips)',
 P_PATH='@s9s_mb_2u_lib.s9s_mb_2u(sch_1):page90_i178@pure_quanta.sconn288_adr500~
17p130cc(chips)',
 PATH='I178',
 DRAWING='@S9S_MB_2U_LIB.S9S_MB_2U(SCH_1):PAGE90',
 PHYS_PAGE='90',
 XY='(1850,3025)',
 ROT='0',
 VER='2',
 LOCATION='J9',
 CDS_LIB='pure_quanta',
 CDS_PART_NAME='SCONN288_ADR50017P130CC-SCONN2A',
 PART_TYPE='SMLF',
 MATERIAL='IO',
 VALUE='SCONN288_ADR50017-P130CC',
 PRIM_FILE='./archive_libs/logical/sconn288_adr50017p130cc/chips/chips.prt';

SECTION_NUMBER 3
 '@S9S_MB_2U_LIB.S9S_MB_2U(SCH_1):PAGE90_I147@PURE_QUANTA.SCONN288_ADR50017P130CC(CHIPS)':
 C_PATH='@s9s_mb_2u_lib.s9s_mb_2u(sch_1):page90_i147@pure_quanta.sconn288_adr500~
17p130cc(chips)',
 P_PATH='@s9s_mb_2u_lib.s9s_mb_2u(sch_1):page90_i147@pure_quanta.sconn288_adr500~
17p130cc(chips)',
 PATH='I147',
 DRAWING='@S9S_MB_2U_LIB.S9S_MB_2U(SCH_1):PAGE90',
 PHYS_PAGE='90',
 XY='(5275,2400)',
 ROT='0',
 VER='3',
 CDS_LIB='pure_quanta',
 CDS_PART_NAME='SCONN288_ADR50017P130CC-SCONN2A',
 PART_TYPE='SMLF',
 MATERIAL='IO',
 VALUE='SCONN288_ADR50017-P130CC',
 PRIM_FILE='./archive_libs/logical/sconn288_adr50017p130cc/chips/chips.prt';

PART_NAME
 J10 'SCONN288_ADR50017P087CC-SCONN2A':;

SECTION_NUMBER 1
 '@S9S_MB_2U_LIB.S9S_MB_2U(SCH_1):PAGE91_I13@PURE_QUANTA.SCONN288_ADR50017P087CC(CHIPS)':
 C_PATH='@s9s_mb_2u_lib.s9s_mb_2u(sch_1):page91_i13@pure_quanta.sconn288_adr5001~
7p087cc(chips)',
 P_PATH='@s9s_mb_2u_lib.s9s_mb_2u(sch_1):page91_i13@pure_quanta.sconn288_adr5001~
7p087cc(chips)',
 PATH='I13',
 DRAWING='@S9S_MB_2U_LIB.S9S_MB_2U(SCH_1):PAGE91',
 PHYS_PAGE='91',
 XY='(-1050,2400)',
 ROT='0',
 VER='1',
 CDS_LIB='pure_quanta',
 CDS_PART_NAME='SCONN288_ADR50017P087CC-SCONN2A',
 PART_TYPE='SMLF',
 MATERIAL='IO',
 VALUE='SCONN288_ADR50017-P087CC',
 PRIM_FILE='./archive_libs/logical/sconn288_adr50017p087cc/chips/chips.prt';

SECTION_NUMBER 2
 '@S9S_MB_2U_LIB.S9S_MB_2U(SCH_1):PAGE91_I178@PURE_QUANTA.SCONN288_ADR50017P087CC(CHIPS)':
 C_PATH='@s9s_mb_2u_lib.s9s_mb_2u(sch_1):page91_i178@pure_quanta.sconn288_adr500~
17p087cc(chips)',
 P_PATH='@s9s_mb_2u_lib.s9s_mb_2u(sch_1):page91_i178@pure_quanta.sconn288_adr500~
17p087cc(chips)',
 PATH='I178',
 DRAWING='@S9S_MB_2U_LIB.S9S_MB_2U(SCH_1):PAGE91',
 PHYS_PAGE='91',
 XY='(1625,3125)',
 ROT='0',
 VER='2',
 LOCATION='J10',
 CDS_LIB='pure_quanta',
 CDS_PART_NAME='SCONN288_ADR50017P087CC-SCONN2A',
 PART_TYPE='SMLF',
 MATERIAL='IO',
 VALUE='SCONN288_ADR50017-P087CC',
 PRIM_FILE='./archive_libs/logical/sconn288_adr50017p087cc/chips/chips.prt';

SECTION_NUMBER 3
 '@S9S_MB_2U_LIB.S9S_MB_2U(SCH_1):PAGE91_I148@PURE_QUANTA.SCONN288_ADR50017P087CC(CHIPS)':
 C_PATH='@s9s_mb_2u_lib.s9s_mb_2u(sch_1):page91_i148@pure_quanta.sconn288_adr500~
17p087cc(chips)',
 P_PATH='@s9s_mb_2u_lib.s9s_mb_2u(sch_1):page91_i148@pure_quanta.sconn288_adr500~
17p087cc(chips)',
 PATH='I148',
 DRAWING='@S9S_MB_2U_LIB.S9S_MB_2U(SCH_1):PAGE91',
 PHYS_PAGE='91',
 XY='(5050,2500)',
 ROT='0',
 VER='3',
 CDS_LIB='pure_quanta',
 CDS_PART_NAME='SCONN288_ADR50017P087CC-SCONN2A',
 PART_TYPE='SMLF',
 MATERIAL='IO',
 VALUE='SCONN288_ADR50017-P087CC',
 PRIM_FILE='./archive_libs/logical/sconn288_adr50017p087cc/chips/chips.prt';

PART_NAME
 J11 'SCONN288_ADR50017P130CC-SCONN2A':;

SECTION_NUMBER 1
 '@S9S_MB_2U_LIB.S9S_MB_2U(SCH_1):PAGE92_I25@PURE_QUANTA.SCONN288_ADR50017P130CC(CHIPS)':
 C_PATH='@s9s_mb_2u_lib.s9s_mb_2u(sch_1):page92_i25@pure_quanta.sconn288_adr5001~
7p130cc(chips)',
 P_PATH='@s9s_mb_2u_lib.s9s_mb_2u(sch_1):page92_i25@pure_quanta.sconn288_adr5001~
7p130cc(chips)',
 PATH='I25',
 DRAWING='@S9S_MB_2U_LIB.S9S_MB_2U(SCH_1):PAGE92',
 PHYS_PAGE='92',
 XY='(-1925,2675)',
 ROT='0',
 VER='1',
 CDS_LIB='pure_quanta',
 CDS_PART_NAME='SCONN288_ADR50017P130CC-SCONN2A',
 PART_TYPE='SMLF',
 MATERIAL='IO',
 VALUE='SCONN288_ADR50017-P130CC',
 PRIM_FILE='./archive_libs/logical/sconn288_adr50017p130cc/chips/chips.prt';

SECTION_NUMBER 2
 '@S9S_MB_2U_LIB.S9S_MB_2U(SCH_1):PAGE92_I178@PURE_QUANTA.SCONN288_ADR50017P130CC(CHIPS)':
 C_PATH='@s9s_mb_2u_lib.s9s_mb_2u(sch_1):page92_i178@pure_quanta.sconn288_adr500~
17p130cc(chips)',
 P_PATH='@s9s_mb_2u_lib.s9s_mb_2u(sch_1):page92_i178@pure_quanta.sconn288_adr500~
17p130cc(chips)',
 PATH='I178',
 DRAWING='@S9S_MB_2U_LIB.S9S_MB_2U(SCH_1):PAGE92',
 PHYS_PAGE='92',
 XY='(750,3400)',
 ROT='0',
 VER='2',
 LOCATION='J11',
 CDS_LIB='pure_quanta',
 CDS_PART_NAME='SCONN288_ADR50017P130CC-SCONN2A',
 PART_TYPE='SMLF',
 MATERIAL='IO',
 VALUE='SCONN288_ADR50017-P130CC',
 PRIM_FILE='./archive_libs/logical/sconn288_adr50017p130cc/chips/chips.prt';

SECTION_NUMBER 3
 '@S9S_MB_2U_LIB.S9S_MB_2U(SCH_1):PAGE92_I175@PURE_QUANTA.SCONN288_ADR50017P130CC(CHIPS)':
 C_PATH='@s9s_mb_2u_lib.s9s_mb_2u(sch_1):page92_i175@pure_quanta.sconn288_adr500~
17p130cc(chips)',
 P_PATH='@s9s_mb_2u_lib.s9s_mb_2u(sch_1):page92_i175@pure_quanta.sconn288_adr500~
17p130cc(chips)',
 PATH='I175',
 DRAWING='@S9S_MB_2U_LIB.S9S_MB_2U(SCH_1):PAGE92',
 PHYS_PAGE='92',
 XY='(4175,2775)',
 ROT='0',
 VER='3',
 CDS_LIB='pure_quanta',
 CDS_PART_NAME='SCONN288_ADR50017P130CC-SCONN2A',
 PART_TYPE='SMLF',
 MATERIAL='IO',
 VALUE='SCONN288_ADR50017-P130CC',
 PRIM_FILE='./archive_libs/logical/sconn288_adr50017p130cc/chips/chips.prt';

PART_NAME
 J12 'SCONN288_ADR50017P087CC-SCONN2A':;

SECTION_NUMBER 1
 '@S9S_MB_2U_LIB.S9S_MB_2U(SCH_1):PAGE93_I24@PURE_QUANTA.SCONN288_ADR50017P087CC(CHIPS)':
 C_PATH='@s9s_mb_2u_lib.s9s_mb_2u(sch_1):page93_i24@pure_quanta.sconn288_adr5001~
7p087cc(chips)',
 P_PATH='@s9s_mb_2u_lib.s9s_mb_2u(sch_1):page93_i24@pure_quanta.sconn288_adr5001~
7p087cc(chips)',
 PATH='I24',
 DRAWING='@S9S_MB_2U_LIB.S9S_MB_2U(SCH_1):PAGE93',
 PHYS_PAGE='93',
 XY='(-1250,2700)',
 ROT='0',
 VER='1',
 CDS_LIB='pure_quanta',
 CDS_PART_NAME='SCONN288_ADR50017P087CC-SCONN2A',
 PART_TYPE='SMLF',
 MATERIAL='IO',
 VALUE='SCONN288_ADR50017-P087CC',
 PRIM_FILE='./archive_libs/logical/sconn288_adr50017p087cc/chips/chips.prt';

SECTION_NUMBER 2
 '@S9S_MB_2U_LIB.S9S_MB_2U(SCH_1):PAGE93_I178@PURE_QUANTA.SCONN288_ADR50017P087CC(CHIPS)':
 C_PATH='@s9s_mb_2u_lib.s9s_mb_2u(sch_1):page93_i178@pure_quanta.sconn288_adr500~
17p087cc(chips)',
 P_PATH='@s9s_mb_2u_lib.s9s_mb_2u(sch_1):page93_i178@pure_quanta.sconn288_adr500~
17p087cc(chips)',
 PATH='I178',
 DRAWING='@S9S_MB_2U_LIB.S9S_MB_2U(SCH_1):PAGE93',
 PHYS_PAGE='93',
 XY='(1425,3425)',
 ROT='0',
 VER='2',
 LOCATION='J12',
 CDS_LIB='pure_quanta',
 CDS_PART_NAME='SCONN288_ADR50017P087CC-SCONN2A',
 PART_TYPE='SMLF',
 MATERIAL='IO',
 VALUE='SCONN288_ADR50017-P087CC',
 PRIM_FILE='./archive_libs/logical/sconn288_adr50017p087cc/chips/chips.prt';

SECTION_NUMBER 3
 '@S9S_MB_2U_LIB.S9S_MB_2U(SCH_1):PAGE93_I175@PURE_QUANTA.SCONN288_ADR50017P087CC(CHIPS)':
 C_PATH='@s9s_mb_2u_lib.s9s_mb_2u(sch_1):page93_i175@pure_quanta.sconn288_adr500~
17p087cc(chips)',
 P_PATH='@s9s_mb_2u_lib.s9s_mb_2u(sch_1):page93_i175@pure_quanta.sconn288_adr500~
17p087cc(chips)',
 PATH='I175',
 DRAWING='@S9S_MB_2U_LIB.S9S_MB_2U(SCH_1):PAGE93',
 PHYS_PAGE='93',
 XY='(4850,2800)',
 ROT='0',
 VER='3',
 CDS_LIB='pure_quanta',
 CDS_PART_NAME='SCONN288_ADR50017P087CC-SCONN2A',
 PART_TYPE='SMLF',
 MATERIAL='IO',
 VALUE='SCONN288_ADR50017-P087CC',
 PRIM_FILE='./archive_libs/logical/sconn288_adr50017p087cc/chips/chips.prt';

PART_NAME
 J13 'SCONN288_ADR50017P130CC-SCONN2A':;

SECTION_NUMBER 1
 '@S9S_MB_2U_LIB.S9S_MB_2U(SCH_1):PAGE94_I11@PURE_QUANTA.SCONN288_ADR50017P130CC(CHIPS)':
 C_PATH='@s9s_mb_2u_lib.s9s_mb_2u(sch_1):page94_i11@pure_quanta.sconn288_adr5001~
7p130cc(chips)',
 P_PATH='@s9s_mb_2u_lib.s9s_mb_2u(sch_1):page94_i11@pure_quanta.sconn288_adr5001~
7p130cc(chips)',
 PATH='I11',
 DRAWING='@S9S_MB_2U_LIB.S9S_MB_2U(SCH_1):PAGE94',
 PHYS_PAGE='94',
 XY='(-1350,2625)',
 ROT='0',
 VER='1',
 CDS_LIB='pure_quanta',
 CDS_PART_NAME='SCONN288_ADR50017P130CC-SCONN2A',
 PART_TYPE='SMLF',
 MATERIAL='IO',
 VALUE='SCONN288_ADR50017-P130CC',
 PRIM_FILE='./archive_libs/logical/sconn288_adr50017p130cc/chips/chips.prt';

SECTION_NUMBER 2
 '@S9S_MB_2U_LIB.S9S_MB_2U(SCH_1):PAGE94_I178@PURE_QUANTA.SCONN288_ADR50017P130CC(CHIPS)':
 C_PATH='@s9s_mb_2u_lib.s9s_mb_2u(sch_1):page94_i178@pure_quanta.sconn288_adr500~
17p130cc(chips)',
 P_PATH='@s9s_mb_2u_lib.s9s_mb_2u(sch_1):page94_i178@pure_quanta.sconn288_adr500~
17p130cc(chips)',
 PATH='I178',
 DRAWING='@S9S_MB_2U_LIB.S9S_MB_2U(SCH_1):PAGE94',
 PHYS_PAGE='94',
 XY='(1325,3350)',
 ROT='0',
 VER='2',
 LOCATION='J13',
 CDS_LIB='pure_quanta',
 CDS_PART_NAME='SCONN288_ADR50017P130CC-SCONN2A',
 PART_TYPE='SMLF',
 MATERIAL='IO',
 VALUE='SCONN288_ADR50017-P130CC',
 PRIM_FILE='./archive_libs/logical/sconn288_adr50017p130cc/chips/chips.prt';

SECTION_NUMBER 3
 '@S9S_MB_2U_LIB.S9S_MB_2U(SCH_1):PAGE94_I164@PURE_QUANTA.SCONN288_ADR50017P130CC(CHIPS)':
 C_PATH='@s9s_mb_2u_lib.s9s_mb_2u(sch_1):page94_i164@pure_quanta.sconn288_adr500~
17p130cc(chips)',
 P_PATH='@s9s_mb_2u_lib.s9s_mb_2u(sch_1):page94_i164@pure_quanta.sconn288_adr500~
17p130cc(chips)',
 PATH='I164',
 DRAWING='@S9S_MB_2U_LIB.S9S_MB_2U(SCH_1):PAGE94',
 PHYS_PAGE='94',
 XY='(4750,2725)',
 ROT='0',
 VER='3',
 CDS_LIB='pure_quanta',
 CDS_PART_NAME='SCONN288_ADR50017P130CC-SCONN2A',
 PART_TYPE='SMLF',
 MATERIAL='IO',
 VALUE='SCONN288_ADR50017-P130CC',
 PRIM_FILE='./archive_libs/logical/sconn288_adr50017p130cc/chips/chips.prt';

PART_NAME
 J14 'SCONN288_ADR50017P087CC-SCONN2A':;

SECTION_NUMBER 1
 '@S9S_MB_2U_LIB.S9S_MB_2U(SCH_1):PAGE95_I47@PURE_QUANTA.SCONN288_ADR50017P087CC(CHIPS)':
 C_PATH='@s9s_mb_2u_lib.s9s_mb_2u(sch_1):page95_i47@pure_quanta.sconn288_adr5001~
7p087cc(chips)',
 P_PATH='@s9s_mb_2u_lib.s9s_mb_2u(sch_1):page95_i47@pure_quanta.sconn288_adr5001~
7p087cc(chips)',
 PATH='I47',
 DRAWING='@S9S_MB_2U_LIB.S9S_MB_2U(SCH_1):PAGE95',
 PHYS_PAGE='95',
 XY='(-225,1600)',
 ROT='0',
 VER='1',
 CDS_LIB='pure_quanta',
 CDS_PART_NAME='SCONN288_ADR50017P087CC-SCONN2A',
 PART_TYPE='SMLF',
 MATERIAL='IO',
 VALUE='SCONN288_ADR50017-P087CC',
 PRIM_FILE='./archive_libs/logical/sconn288_adr50017p087cc/chips/chips.prt';

SECTION_NUMBER 2
 '@S9S_MB_2U_LIB.S9S_MB_2U(SCH_1):PAGE95_I178@PURE_QUANTA.SCONN288_ADR50017P087CC(CHIPS)':
 C_PATH='@s9s_mb_2u_lib.s9s_mb_2u(sch_1):page95_i178@pure_quanta.sconn288_adr500~
17p087cc(chips)',
 P_PATH='@s9s_mb_2u_lib.s9s_mb_2u(sch_1):page95_i178@pure_quanta.sconn288_adr500~
17p087cc(chips)',
 PATH='I178',
 DRAWING='@S9S_MB_2U_LIB.S9S_MB_2U(SCH_1):PAGE95',
 PHYS_PAGE='95',
 XY='(2475,2325)',
 ROT='0',
 VER='2',
 LOCATION='J14',
 CDS_LIB='pure_quanta',
 CDS_PART_NAME='SCONN288_ADR50017P087CC-SCONN2A',
 PART_TYPE='SMLF',
 MATERIAL='IO',
 VALUE='SCONN288_ADR50017-P087CC',
 PRIM_FILE='./archive_libs/logical/sconn288_adr50017p087cc/chips/chips.prt';

SECTION_NUMBER 3
 '@S9S_MB_2U_LIB.S9S_MB_2U(SCH_1):PAGE95_I176@PURE_QUANTA.SCONN288_ADR50017P087CC(CHIPS)':
 C_PATH='@s9s_mb_2u_lib.s9s_mb_2u(sch_1):page95_i176@pure_quanta.sconn288_adr500~
17p087cc(chips)',
 P_PATH='@s9s_mb_2u_lib.s9s_mb_2u(sch_1):page95_i176@pure_quanta.sconn288_adr500~
17p087cc(chips)',
 PATH='I176',
 DRAWING='@S9S_MB_2U_LIB.S9S_MB_2U(SCH_1):PAGE95',
 PHYS_PAGE='95',
 XY='(5875,1700)',
 ROT='0',
 VER='3',
 CDS_LIB='pure_quanta',
 CDS_PART_NAME='SCONN288_ADR50017P087CC-SCONN2A',
 PART_TYPE='SMLF',
 MATERIAL='IO',
 VALUE='SCONN288_ADR50017-P087CC',
 PRIM_FILE='./archive_libs/logical/sconn288_adr50017p087cc/chips/chips.prt';

PART_NAME
 J15 'SCONN288_ADR50017P130CC-SCONN2A':;

SECTION_NUMBER 1
 '@S9S_MB_2U_LIB.S9S_MB_2U(SCH_1):PAGE96_I48@PURE_QUANTA.SCONN288_ADR50017P130CC(CHIPS)':
 C_PATH='@s9s_mb_2u_lib.s9s_mb_2u(sch_1):page96_i48@pure_quanta.sconn288_adr5001~
7p130cc(chips)',
 P_PATH='@s9s_mb_2u_lib.s9s_mb_2u(sch_1):page96_i48@pure_quanta.sconn288_adr5001~
7p130cc(chips)',
 PATH='I48',
 DRAWING='@S9S_MB_2U_LIB.S9S_MB_2U(SCH_1):PAGE96',
 PHYS_PAGE='96',
 XY='(-1675,2250)',
 ROT='0',
 VER='1',
 CDS_LIB='pure_quanta',
 CDS_PART_NAME='SCONN288_ADR50017P130CC-SCONN2A',
 PART_TYPE='SMLF',
 MATERIAL='IO',
 VALUE='SCONN288_ADR50017-P130CC',
 PRIM_FILE='./archive_libs/logical/sconn288_adr50017p130cc/chips/chips.prt';

SECTION_NUMBER 2
 '@S9S_MB_2U_LIB.S9S_MB_2U(SCH_1):PAGE96_I178@PURE_QUANTA.SCONN288_ADR50017P130CC(CHIPS)':
 C_PATH='@s9s_mb_2u_lib.s9s_mb_2u(sch_1):page96_i178@pure_quanta.sconn288_adr500~
17p130cc(chips)',
 P_PATH='@s9s_mb_2u_lib.s9s_mb_2u(sch_1):page96_i178@pure_quanta.sconn288_adr500~
17p130cc(chips)',
 PATH='I178',
 DRAWING='@S9S_MB_2U_LIB.S9S_MB_2U(SCH_1):PAGE96',
 PHYS_PAGE='96',
 XY='(1000,2975)',
 ROT='0',
 VER='2',
 LOCATION='J15',
 CDS_LIB='pure_quanta',
 CDS_PART_NAME='SCONN288_ADR50017P130CC-SCONN2A',
 PART_TYPE='SMLF',
 MATERIAL='IO',
 VALUE='SCONN288_ADR50017-P130CC',
 PRIM_FILE='./archive_libs/logical/sconn288_adr50017p130cc/chips/chips.prt';

SECTION_NUMBER 3
 '@S9S_MB_2U_LIB.S9S_MB_2U(SCH_1):PAGE96_I176@PURE_QUANTA.SCONN288_ADR50017P130CC(CHIPS)':
 C_PATH='@s9s_mb_2u_lib.s9s_mb_2u(sch_1):page96_i176@pure_quanta.sconn288_adr500~
17p130cc(chips)',
 P_PATH='@s9s_mb_2u_lib.s9s_mb_2u(sch_1):page96_i176@pure_quanta.sconn288_adr500~
17p130cc(chips)',
 PATH='I176',
 DRAWING='@S9S_MB_2U_LIB.S9S_MB_2U(SCH_1):PAGE96',
 PHYS_PAGE='96',
 XY='(4425,2350)',
 ROT='0',
 VER='3',
 CDS_LIB='pure_quanta',
 CDS_PART_NAME='SCONN288_ADR50017P130CC-SCONN2A',
 PART_TYPE='SMLF',
 MATERIAL='IO',
 VALUE='SCONN288_ADR50017-P130CC',
 PRIM_FILE='./archive_libs/logical/sconn288_adr50017p130cc/chips/chips.prt';

PART_NAME
 J16 'SCONN288_ADR50017P087CC-SCONN2A':;

SECTION_NUMBER 1
 '@S9S_MB_2U_LIB.S9S_MB_2U(SCH_1):PAGE97_I6@PURE_QUANTA.SCONN288_ADR50017P087CC(CHIPS)':
 C_PATH='@s9s_mb_2u_lib.s9s_mb_2u(sch_1):page97_i6@pure_quanta.sconn288_adr50017~
p087cc(chips)',
 P_PATH='@s9s_mb_2u_lib.s9s_mb_2u(sch_1):page97_i6@pure_quanta.sconn288_adr50017~
p087cc(chips)',
 PATH='I6',
 DRAWING='@S9S_MB_2U_LIB.S9S_MB_2U(SCH_1):PAGE97',
 PHYS_PAGE='97',
 XY='(-1175,2425)',
 ROT='0',
 VER='1',
 CDS_LIB='pure_quanta',
 CDS_PART_NAME='SCONN288_ADR50017P087CC-SCONN2A',
 PART_TYPE='SMLF',
 MATERIAL='IO',
 VALUE='SCONN288_ADR50017-P087CC',
 PRIM_FILE='./archive_libs/logical/sconn288_adr50017p087cc/chips/chips.prt';

SECTION_NUMBER 2
 '@S9S_MB_2U_LIB.S9S_MB_2U(SCH_1):PAGE97_I178@PURE_QUANTA.SCONN288_ADR50017P087CC(CHIPS)':
 C_PATH='@s9s_mb_2u_lib.s9s_mb_2u(sch_1):page97_i178@pure_quanta.sconn288_adr500~
17p087cc(chips)',
 P_PATH='@s9s_mb_2u_lib.s9s_mb_2u(sch_1):page97_i178@pure_quanta.sconn288_adr500~
17p087cc(chips)',
 PATH='I178',
 DRAWING='@S9S_MB_2U_LIB.S9S_MB_2U(SCH_1):PAGE97',
 PHYS_PAGE='97',
 XY='(1475,3175)',
 ROT='0',
 VER='2',
 LOCATION='J16',
 CDS_LIB='pure_quanta',
 CDS_PART_NAME='SCONN288_ADR50017P087CC-SCONN2A',
 PART_TYPE='SMLF',
 MATERIAL='IO',
 VALUE='SCONN288_ADR50017-P087CC',
 PRIM_FILE='./archive_libs/logical/sconn288_adr50017p087cc/chips/chips.prt';

SECTION_NUMBER 3
 '@S9S_MB_2U_LIB.S9S_MB_2U(SCH_1):PAGE97_I64@PURE_QUANTA.SCONN288_ADR50017P087CC(CHIPS)':
 C_PATH='@s9s_mb_2u_lib.s9s_mb_2u(sch_1):page97_i64@pure_quanta.sconn288_adr5001~
7p087cc(chips)',
 P_PATH='@s9s_mb_2u_lib.s9s_mb_2u(sch_1):page97_i64@pure_quanta.sconn288_adr5001~
7p087cc(chips)',
 PATH='I64',
 DRAWING='@S9S_MB_2U_LIB.S9S_MB_2U(SCH_1):PAGE97',
 PHYS_PAGE='97',
 XY='(4925,2550)',
 ROT='0',
 VER='3',
 CDS_LIB='pure_quanta',
 CDS_PART_NAME='SCONN288_ADR50017P087CC-SCONN2A',
 PART_TYPE='SMLF',
 MATERIAL='IO',
 VALUE='SCONN288_ADR50017-P087CC',
 PRIM_FILE='./archive_libs/logical/sconn288_adr50017p087cc/chips/chips.prt';

PART_NAME
 J17 'SCONN288_ADR50017P130CC-SCONN2A':;

SECTION_NUMBER 1
 '@S9S_MB_2U_LIB.S9S_MB_2U(SCH_1):PAGE98_I12@PURE_QUANTA.SCONN288_ADR50017P130CC(CHIPS)':
 C_PATH='@s9s_mb_2u_lib.s9s_mb_2u(sch_1):page98_i12@pure_quanta.sconn288_adr5001~
7p130cc(chips)',
 P_PATH='@s9s_mb_2u_lib.s9s_mb_2u(sch_1):page98_i12@pure_quanta.sconn288_adr5001~
7p130cc(chips)',
 PATH='I12',
 DRAWING='@S9S_MB_2U_LIB.S9S_MB_2U(SCH_1):PAGE98',
 PHYS_PAGE='98',
 XY='(-800,2350)',
 ROT='0',
 VER='1',
 CDS_LIB='pure_quanta',
 CDS_PART_NAME='SCONN288_ADR50017P130CC-SCONN2A',
 PART_TYPE='SMLF',
 MATERIAL='IO',
 VALUE='SCONN288_ADR50017-P130CC',
 PRIM_FILE='./archive_libs/logical/sconn288_adr50017p130cc/chips/chips.prt';

SECTION_NUMBER 2
 '@S9S_MB_2U_LIB.S9S_MB_2U(SCH_1):PAGE98_I178@PURE_QUANTA.SCONN288_ADR50017P130CC(CHIPS)':
 C_PATH='@s9s_mb_2u_lib.s9s_mb_2u(sch_1):page98_i178@pure_quanta.sconn288_adr500~
17p130cc(chips)',
 P_PATH='@s9s_mb_2u_lib.s9s_mb_2u(sch_1):page98_i178@pure_quanta.sconn288_adr500~
17p130cc(chips)',
 PATH='I178',
 DRAWING='@S9S_MB_2U_LIB.S9S_MB_2U(SCH_1):PAGE98',
 PHYS_PAGE='98',
 XY='(1875,3075)',
 ROT='0',
 VER='2',
 LOCATION='J17',
 CDS_LIB='pure_quanta',
 CDS_PART_NAME='SCONN288_ADR50017P130CC-SCONN2A',
 PART_TYPE='SMLF',
 MATERIAL='IO',
 VALUE='SCONN288_ADR50017-P130CC',
 PRIM_FILE='./archive_libs/logical/sconn288_adr50017p130cc/chips/chips.prt';

SECTION_NUMBER 3
 '@S9S_MB_2U_LIB.S9S_MB_2U(SCH_1):PAGE98_I147@PURE_QUANTA.SCONN288_ADR50017P130CC(CHIPS)':
 C_PATH='@s9s_mb_2u_lib.s9s_mb_2u(sch_1):page98_i147@pure_quanta.sconn288_adr500~
17p130cc(chips)',
 P_PATH='@s9s_mb_2u_lib.s9s_mb_2u(sch_1):page98_i147@pure_quanta.sconn288_adr500~
17p130cc(chips)',
 PATH='I147',
 DRAWING='@S9S_MB_2U_LIB.S9S_MB_2U(SCH_1):PAGE98',
 PHYS_PAGE='98',
 XY='(5300,2450)',
 ROT='0',
 VER='3',
 CDS_LIB='pure_quanta',
 CDS_PART_NAME='SCONN288_ADR50017P130CC-SCONN2A',
 PART_TYPE='SMLF',
 MATERIAL='IO',
 VALUE='SCONN288_ADR50017-P130CC',
 PRIM_FILE='./archive_libs/logical/sconn288_adr50017p130cc/chips/chips.prt';

PART_NAME
 J18 'SCONN288_ADR50017P087CC-SCONN2A':;

SECTION_NUMBER 1
 '@S9S_MB_2U_LIB.S9S_MB_2U(SCH_1):PAGE99_I24@PURE_QUANTA.SCONN288_ADR50017P087CC(CHIPS)':
 C_PATH='@s9s_mb_2u_lib.s9s_mb_2u(sch_1):page99_i24@pure_quanta.sconn288_adr5001~
7p087cc(chips)',
 P_PATH='@s9s_mb_2u_lib.s9s_mb_2u(sch_1):page99_i24@pure_quanta.sconn288_adr5001~
7p087cc(chips)',
 PATH='I24',
 DRAWING='@S9S_MB_2U_LIB.S9S_MB_2U(SCH_1):PAGE99',
 PHYS_PAGE='99',
 XY='(-1050,2075)',
 ROT='0',
 VER='1',
 CDS_LIB='pure_quanta',
 CDS_PART_NAME='SCONN288_ADR50017P087CC-SCONN2A',
 PART_TYPE='SMLF',
 MATERIAL='IO',
 VALUE='SCONN288_ADR50017-P087CC',
 PRIM_FILE='./archive_libs/logical/sconn288_adr50017p087cc/chips/chips.prt';

SECTION_NUMBER 2
 '@S9S_MB_2U_LIB.S9S_MB_2U(SCH_1):PAGE99_I178@PURE_QUANTA.SCONN288_ADR50017P087CC(CHIPS)':
 C_PATH='@s9s_mb_2u_lib.s9s_mb_2u(sch_1):page99_i178@pure_quanta.sconn288_adr500~
17p087cc(chips)',
 P_PATH='@s9s_mb_2u_lib.s9s_mb_2u(sch_1):page99_i178@pure_quanta.sconn288_adr500~
17p087cc(chips)',
 PATH='I178',
 DRAWING='@S9S_MB_2U_LIB.S9S_MB_2U(SCH_1):PAGE99',
 PHYS_PAGE='99',
 XY='(1625,2800)',
 ROT='0',
 VER='2',
 LOCATION='J18',
 CDS_LIB='pure_quanta',
 CDS_PART_NAME='SCONN288_ADR50017P087CC-SCONN2A',
 PART_TYPE='SMLF',
 MATERIAL='IO',
 VALUE='SCONN288_ADR50017-P087CC',
 PRIM_FILE='./archive_libs/logical/sconn288_adr50017p087cc/chips/chips.prt';

SECTION_NUMBER 3
 '@S9S_MB_2U_LIB.S9S_MB_2U(SCH_1):PAGE99_I175@PURE_QUANTA.SCONN288_ADR50017P087CC(CHIPS)':
 C_PATH='@s9s_mb_2u_lib.s9s_mb_2u(sch_1):page99_i175@pure_quanta.sconn288_adr500~
17p087cc(chips)',
 P_PATH='@s9s_mb_2u_lib.s9s_mb_2u(sch_1):page99_i175@pure_quanta.sconn288_adr500~
17p087cc(chips)',
 PATH='I175',
 DRAWING='@S9S_MB_2U_LIB.S9S_MB_2U(SCH_1):PAGE99',
 PHYS_PAGE='99',
 XY='(5050,2175)',
 ROT='0',
 VER='3',
 CDS_LIB='pure_quanta',
 CDS_PART_NAME='SCONN288_ADR50017P087CC-SCONN2A',
 PART_TYPE='SMLF',
 MATERIAL='IO',
 VALUE='SCONN288_ADR50017-P087CC',
 PRIM_FILE='./archive_libs/logical/sconn288_adr50017p087cc/chips/chips.prt';

PART_NAME
 J19 'SCONN288_ADR50017P130CC-SCONN2A':;

SECTION_NUMBER 1
 '@S9S_MB_2U_LIB.S9S_MB_2U(SCH_1):PAGE100_I25@PURE_QUANTA.SCONN288_ADR50017P130CC(CHIPS)':
 C_PATH='@s9s_mb_2u_lib.s9s_mb_2u(sch_1):page100_i25@pure_quanta.sconn288_adr500~
17p130cc(chips)',
 P_PATH='@s9s_mb_2u_lib.s9s_mb_2u(sch_1):page100_i25@pure_quanta.sconn288_adr500~
17p130cc(chips)',
 PATH='I25',
 DRAWING='@S9S_MB_2U_LIB.S9S_MB_2U(SCH_1):PAGE100',
 PHYS_PAGE='100',
 XY='(-1400,2675)',
 ROT='0',
 VER='1',
 CDS_LIB='pure_quanta',
 CDS_PART_NAME='SCONN288_ADR50017P130CC-SCONN2A',
 PART_TYPE='SMLF',
 MATERIAL='IO',
 VALUE='SCONN288_ADR50017-P130CC',
 PRIM_FILE='./archive_libs/logical/sconn288_adr50017p130cc/chips/chips.prt';

SECTION_NUMBER 2
 '@S9S_MB_2U_LIB.S9S_MB_2U(SCH_1):PAGE100_I178@PURE_QUANTA.SCONN288_ADR50017P130CC(CHIPS)':
 C_PATH='@s9s_mb_2u_lib.s9s_mb_2u(sch_1):page100_i178@pure_quanta.sconn288_adr50~
017p130cc(chips)',
 P_PATH='@s9s_mb_2u_lib.s9s_mb_2u(sch_1):page100_i178@pure_quanta.sconn288_adr50~
017p130cc(chips)',
 PATH='I178',
 DRAWING='@S9S_MB_2U_LIB.S9S_MB_2U(SCH_1):PAGE100',
 PHYS_PAGE='100',
 XY='(1275,3400)',
 ROT='0',
 VER='2',
 LOCATION='J19',
 CDS_LIB='pure_quanta',
 CDS_PART_NAME='SCONN288_ADR50017P130CC-SCONN2A',
 PART_TYPE='SMLF',
 MATERIAL='IO',
 VALUE='SCONN288_ADR50017-P130CC',
 PRIM_FILE='./archive_libs/logical/sconn288_adr50017p130cc/chips/chips.prt';

SECTION_NUMBER 3
 '@S9S_MB_2U_LIB.S9S_MB_2U(SCH_1):PAGE100_I175@PURE_QUANTA.SCONN288_ADR50017P130CC(CHIPS)':
 C_PATH='@s9s_mb_2u_lib.s9s_mb_2u(sch_1):page100_i175@pure_quanta.sconn288_adr50~
017p130cc(chips)',
 P_PATH='@s9s_mb_2u_lib.s9s_mb_2u(sch_1):page100_i175@pure_quanta.sconn288_adr50~
017p130cc(chips)',
 PATH='I175',
 DRAWING='@S9S_MB_2U_LIB.S9S_MB_2U(SCH_1):PAGE100',
 PHYS_PAGE='100',
 XY='(4700,2775)',
 ROT='0',
 VER='3',
 CDS_LIB='pure_quanta',
 CDS_PART_NAME='SCONN288_ADR50017P130CC-SCONN2A',
 PART_TYPE='SMLF',
 MATERIAL='IO',
 VALUE='SCONN288_ADR50017-P130CC',
 PRIM_FILE='./archive_libs/logical/sconn288_adr50017p130cc/chips/chips.prt';

PART_NAME
 J20 'SCONN288_ADR50017P087CC-SCONN2A':;

SECTION_NUMBER 1
 '@S9S_MB_2U_LIB.S9S_MB_2U(SCH_1):PAGE101_I47@PURE_QUANTA.SCONN288_ADR50017P087CC(CHIPS)':
 C_PATH='@s9s_mb_2u_lib.s9s_mb_2u(sch_1):page101_i47@pure_quanta.sconn288_adr500~
17p087cc(chips)',
 P_PATH='@s9s_mb_2u_lib.s9s_mb_2u(sch_1):page101_i47@pure_quanta.sconn288_adr500~
17p087cc(chips)',
 PATH='I47',
 DRAWING='@S9S_MB_2U_LIB.S9S_MB_2U(SCH_1):PAGE101',
 PHYS_PAGE='101',
 XY='(-3450,2925)',
 ROT='0',
 VER='1',
 CDS_LIB='pure_quanta',
 CDS_PART_NAME='SCONN288_ADR50017P087CC-SCONN2A',
 PART_TYPE='SMLF',
 MATERIAL='IO',
 VALUE='SCONN288_ADR50017-P087CC',
 PRIM_FILE='./archive_libs/logical/sconn288_adr50017p087cc/chips/chips.prt';

SECTION_NUMBER 2
 '@S9S_MB_2U_LIB.S9S_MB_2U(SCH_1):PAGE101_I178@PURE_QUANTA.SCONN288_ADR50017P087CC(CHIPS)':
 C_PATH='@s9s_mb_2u_lib.s9s_mb_2u(sch_1):page101_i178@pure_quanta.sconn288_adr50~
017p087cc(chips)',
 P_PATH='@s9s_mb_2u_lib.s9s_mb_2u(sch_1):page101_i178@pure_quanta.sconn288_adr50~
017p087cc(chips)',
 PATH='I178',
 DRAWING='@S9S_MB_2U_LIB.S9S_MB_2U(SCH_1):PAGE101',
 PHYS_PAGE='101',
 XY='(-775,3650)',
 ROT='0',
 VER='2',
 LOCATION='J20',
 CDS_LIB='pure_quanta',
 CDS_PART_NAME='SCONN288_ADR50017P087CC-SCONN2A',
 PART_TYPE='SMLF',
 MATERIAL='IO',
 VALUE='SCONN288_ADR50017-P087CC',
 PRIM_FILE='./archive_libs/logical/sconn288_adr50017p087cc/chips/chips.prt';

SECTION_NUMBER 3
 '@S9S_MB_2U_LIB.S9S_MB_2U(SCH_1):PAGE101_I176@PURE_QUANTA.SCONN288_ADR50017P087CC(CHIPS)':
 C_PATH='@s9s_mb_2u_lib.s9s_mb_2u(sch_1):page101_i176@pure_quanta.sconn288_adr50~
017p087cc(chips)',
 P_PATH='@s9s_mb_2u_lib.s9s_mb_2u(sch_1):page101_i176@pure_quanta.sconn288_adr50~
017p087cc(chips)',
 PATH='I176',
 DRAWING='@S9S_MB_2U_LIB.S9S_MB_2U(SCH_1):PAGE101',
 PHYS_PAGE='101',
 XY='(2650,3025)',
 ROT='0',
 VER='3',
 CDS_LIB='pure_quanta',
 CDS_PART_NAME='SCONN288_ADR50017P087CC-SCONN2A',
 PART_TYPE='SMLF',
 MATERIAL='IO',
 VALUE='SCONN288_ADR50017-P087CC',
 PRIM_FILE='./archive_libs/logical/sconn288_adr50017p087cc/chips/chips.prt';

PART_NAME
 J21 'SCONN288_ADR50017P130CC-SCONN2A':;

SECTION_NUMBER 1
 '@S9S_MB_2U_LIB.S9S_MB_2U(SCH_1):PAGE102_I13@PURE_QUANTA.SCONN288_ADR50017P130CC(CHIPS)':
 C_PATH='@s9s_mb_2u_lib.s9s_mb_2u(sch_1):page102_i13@pure_quanta.sconn288_adr500~
17p130cc(chips)',
 P_PATH='@s9s_mb_2u_lib.s9s_mb_2u(sch_1):page102_i13@pure_quanta.sconn288_adr500~
17p130cc(chips)',
 PATH='I13',
 DRAWING='@S9S_MB_2U_LIB.S9S_MB_2U(SCH_1):PAGE102',
 PHYS_PAGE='102',
 XY='(-2000,2450)',
 ROT='0',
 VER='1',
 CDS_LIB='pure_quanta',
 CDS_PART_NAME='SCONN288_ADR50017P130CC-SCONN2A',
 PART_TYPE='SMLF',
 MATERIAL='IO',
 VALUE='SCONN288_ADR50017-P130CC',
 PRIM_FILE='./archive_libs/logical/sconn288_adr50017p130cc/chips/chips.prt';

SECTION_NUMBER 2
 '@S9S_MB_2U_LIB.S9S_MB_2U(SCH_1):PAGE102_I178@PURE_QUANTA.SCONN288_ADR50017P130CC(CHIPS)':
 C_PATH='@s9s_mb_2u_lib.s9s_mb_2u(sch_1):page102_i178@pure_quanta.sconn288_adr50~
017p130cc(chips)',
 P_PATH='@s9s_mb_2u_lib.s9s_mb_2u(sch_1):page102_i178@pure_quanta.sconn288_adr50~
017p130cc(chips)',
 PATH='I178',
 DRAWING='@S9S_MB_2U_LIB.S9S_MB_2U(SCH_1):PAGE102',
 PHYS_PAGE='102',
 XY='(675,3175)',
 ROT='0',
 VER='2',
 LOCATION='J21',
 CDS_LIB='pure_quanta',
 CDS_PART_NAME='SCONN288_ADR50017P130CC-SCONN2A',
 PART_TYPE='SMLF',
 MATERIAL='IO',
 VALUE='SCONN288_ADR50017-P130CC',
 PRIM_FILE='./archive_libs/logical/sconn288_adr50017p130cc/chips/chips.prt';

SECTION_NUMBER 3
 '@S9S_MB_2U_LIB.S9S_MB_2U(SCH_1):PAGE102_I169@PURE_QUANTA.SCONN288_ADR50017P130CC(CHIPS)':
 C_PATH='@s9s_mb_2u_lib.s9s_mb_2u(sch_1):page102_i169@pure_quanta.sconn288_adr50~
017p130cc(chips)',
 P_PATH='@s9s_mb_2u_lib.s9s_mb_2u(sch_1):page102_i169@pure_quanta.sconn288_adr50~
017p130cc(chips)',
 PATH='I169',
 DRAWING='@S9S_MB_2U_LIB.S9S_MB_2U(SCH_1):PAGE102',
 PHYS_PAGE='102',
 XY='(4100,2550)',
 ROT='0',
 VER='3',
 CDS_LIB='pure_quanta',
 CDS_PART_NAME='SCONN288_ADR50017P130CC-SCONN2A',
 PART_TYPE='SMLF',
 MATERIAL='IO',
 VALUE='SCONN288_ADR50017-P130CC',
 PRIM_FILE='./archive_libs/logical/sconn288_adr50017p130cc/chips/chips.prt';

PART_NAME
 J22 'SCONN288_ADR50017P087CC-SCONN2A':;

SECTION_NUMBER 1
 '@S9S_MB_2U_LIB.S9S_MB_2U(SCH_1):PAGE103_I51@PURE_QUANTA.SCONN288_ADR50017P087CC(CHIPS)':
 C_PATH='@s9s_mb_2u_lib.s9s_mb_2u(sch_1):page103_i51@pure_quanta.sconn288_adr500~
17p087cc(chips)',
 P_PATH='@s9s_mb_2u_lib.s9s_mb_2u(sch_1):page103_i51@pure_quanta.sconn288_adr500~
17p087cc(chips)',
 PATH='I51',
 DRAWING='@S9S_MB_2U_LIB.S9S_MB_2U(SCH_1):PAGE103',
 PHYS_PAGE='103',
 XY='(-2075,2175)',
 ROT='0',
 VER='1',
 CDS_LIB='pure_quanta',
 CDS_PART_NAME='SCONN288_ADR50017P087CC-SCONN2A',
 PART_TYPE='SMLF',
 MATERIAL='IO',
 VALUE='SCONN288_ADR50017-P087CC',
 PRIM_FILE='./archive_libs/logical/sconn288_adr50017p087cc/chips/chips.prt';

SECTION_NUMBER 2
 '@S9S_MB_2U_LIB.S9S_MB_2U(SCH_1):PAGE103_I178@PURE_QUANTA.SCONN288_ADR50017P087CC(CHIPS)':
 C_PATH='@s9s_mb_2u_lib.s9s_mb_2u(sch_1):page103_i178@pure_quanta.sconn288_adr50~
017p087cc(chips)',
 P_PATH='@s9s_mb_2u_lib.s9s_mb_2u(sch_1):page103_i178@pure_quanta.sconn288_adr50~
017p087cc(chips)',
 PATH='I178',
 DRAWING='@S9S_MB_2U_LIB.S9S_MB_2U(SCH_1):PAGE103',
 PHYS_PAGE='103',
 XY='(600,2900)',
 ROT='0',
 VER='2',
 LOCATION='J22',
 CDS_LIB='pure_quanta',
 CDS_PART_NAME='SCONN288_ADR50017P087CC-SCONN2A',
 PART_TYPE='SMLF',
 MATERIAL='IO',
 VALUE='SCONN288_ADR50017-P087CC',
 PRIM_FILE='./archive_libs/logical/sconn288_adr50017p087cc/chips/chips.prt';

SECTION_NUMBER 3
 '@S9S_MB_2U_LIB.S9S_MB_2U(SCH_1):PAGE103_I176@PURE_QUANTA.SCONN288_ADR50017P087CC(CHIPS)':
 C_PATH='@s9s_mb_2u_lib.s9s_mb_2u(sch_1):page103_i176@pure_quanta.sconn288_adr50~
017p087cc(chips)',
 P_PATH='@s9s_mb_2u_lib.s9s_mb_2u(sch_1):page103_i176@pure_quanta.sconn288_adr50~
017p087cc(chips)',
 PATH='I176',
 DRAWING='@S9S_MB_2U_LIB.S9S_MB_2U(SCH_1):PAGE103',
 PHYS_PAGE='103',
 XY='(4025,2275)',
 ROT='0',
 VER='3',
 CDS_LIB='pure_quanta',
 CDS_PART_NAME='SCONN288_ADR50017P087CC-SCONN2A',
 PART_TYPE='SMLF',
 MATERIAL='IO',
 VALUE='SCONN288_ADR50017-P087CC',
 PRIM_FILE='./archive_libs/logical/sconn288_adr50017p087cc/chips/chips.prt';

PART_NAME
 J23 'SCONN288_ADR50017P130CC-SCONN2A':;

SECTION_NUMBER 1
 '@S9S_MB_2U_LIB.S9S_MB_2U(SCH_1):PAGE104_I25@PURE_QUANTA.SCONN288_ADR50017P130CC(CHIPS)':
 C_PATH='@s9s_mb_2u_lib.s9s_mb_2u(sch_1):page104_i25@pure_quanta.sconn288_adr500~
17p130cc(chips)',
 P_PATH='@s9s_mb_2u_lib.s9s_mb_2u(sch_1):page104_i25@pure_quanta.sconn288_adr500~
17p130cc(chips)',
 PATH='I25',
 DRAWING='@S9S_MB_2U_LIB.S9S_MB_2U(SCH_1):PAGE104',
 PHYS_PAGE='104',
 XY='(-2500,2400)',
 ROT='0',
 VER='1',
 CDS_LIB='pure_quanta',
 CDS_PART_NAME='SCONN288_ADR50017P130CC-SCONN2A',
 PART_TYPE='SMLF',
 MATERIAL='IO',
 VALUE='SCONN288_ADR50017-P130CC',
 PRIM_FILE='./archive_libs/logical/sconn288_adr50017p130cc/chips/chips.prt';

SECTION_NUMBER 2
 '@S9S_MB_2U_LIB.S9S_MB_2U(SCH_1):PAGE104_I178@PURE_QUANTA.SCONN288_ADR50017P130CC(CHIPS)':
 C_PATH='@s9s_mb_2u_lib.s9s_mb_2u(sch_1):page104_i178@pure_quanta.sconn288_adr50~
017p130cc(chips)',
 P_PATH='@s9s_mb_2u_lib.s9s_mb_2u(sch_1):page104_i178@pure_quanta.sconn288_adr50~
017p130cc(chips)',
 PATH='I178',
 DRAWING='@S9S_MB_2U_LIB.S9S_MB_2U(SCH_1):PAGE104',
 PHYS_PAGE='104',
 XY='(175,3125)',
 ROT='0',
 VER='2',
 LOCATION='J23',
 CDS_LIB='pure_quanta',
 CDS_PART_NAME='SCONN288_ADR50017P130CC-SCONN2A',
 PART_TYPE='SMLF',
 MATERIAL='IO',
 VALUE='SCONN288_ADR50017-P130CC',
 PRIM_FILE='./archive_libs/logical/sconn288_adr50017p130cc/chips/chips.prt';

SECTION_NUMBER 3
 '@S9S_MB_2U_LIB.S9S_MB_2U(SCH_1):PAGE104_I175@PURE_QUANTA.SCONN288_ADR50017P130CC(CHIPS)':
 C_PATH='@s9s_mb_2u_lib.s9s_mb_2u(sch_1):page104_i175@pure_quanta.sconn288_adr50~
017p130cc(chips)',
 P_PATH='@s9s_mb_2u_lib.s9s_mb_2u(sch_1):page104_i175@pure_quanta.sconn288_adr50~
017p130cc(chips)',
 PATH='I175',
 DRAWING='@S9S_MB_2U_LIB.S9S_MB_2U(SCH_1):PAGE104',
 PHYS_PAGE='104',
 XY='(3600,2500)',
 ROT='0',
 VER='3',
 CDS_LIB='pure_quanta',
 CDS_PART_NAME='SCONN288_ADR50017P130CC-SCONN2A',
 PART_TYPE='SMLF',
 MATERIAL='IO',
 VALUE='SCONN288_ADR50017-P130CC',
 PRIM_FILE='./archive_libs/logical/sconn288_adr50017p130cc/chips/chips.prt';

PART_NAME
 J24 'SCONN288_ADR50017P087CC-SCONN2A':;

SECTION_NUMBER 1
 '@S9S_MB_2U_LIB.S9S_MB_2U(SCH_1):PAGE105_I178@PURE_QUANTA.SCONN288_ADR50017P087CC(CHIPS)':
 C_PATH='@s9s_mb_2u_lib.s9s_mb_2u(sch_1):page105_i178@pure_quanta.sconn288_adr50~
017p087cc(chips)',
 P_PATH='@s9s_mb_2u_lib.s9s_mb_2u(sch_1):page105_i178@pure_quanta.sconn288_adr50~
017p087cc(chips)',
 PATH='I178',
 DRAWING='@S9S_MB_2U_LIB.S9S_MB_2U(SCH_1):PAGE105',
 PHYS_PAGE='105',
 XY='(-2025,2550)',
 ROT='0',
 VER='1',
 CDS_LIB='pure_quanta',
 CDS_PART_NAME='SCONN288_ADR50017P087CC-SCONN2A',
 PART_TYPE='SMLF',
 MATERIAL='IO',
 VALUE='SCONN288_ADR50017-P087CC',
 PRIM_FILE='./archive_libs/logical/sconn288_adr50017p087cc/chips/chips.prt';

SECTION_NUMBER 2
 '@S9S_MB_2U_LIB.S9S_MB_2U(SCH_1):PAGE105_I181@PURE_QUANTA.SCONN288_ADR50017P087CC(CHIPS)':
 C_PATH='@s9s_mb_2u_lib.s9s_mb_2u(sch_1):page105_i181@pure_quanta.sconn288_adr50~
017p087cc(chips)',
 P_PATH='@s9s_mb_2u_lib.s9s_mb_2u(sch_1):page105_i181@pure_quanta.sconn288_adr50~
017p087cc(chips)',
 PATH='I181',
 DRAWING='@S9S_MB_2U_LIB.S9S_MB_2U(SCH_1):PAGE105',
 PHYS_PAGE='105',
 XY='(650,3275)',
 ROT='0',
 VER='2',
 LOCATION='J24',
 CDS_LIB='pure_quanta',
 CDS_PART_NAME='SCONN288_ADR50017P087CC-SCONN2A',
 PART_TYPE='SMLF',
 MATERIAL='IO',
 VALUE='SCONN288_ADR50017-P087CC',
 PRIM_FILE='./archive_libs/logical/sconn288_adr50017p087cc/chips/chips.prt';

SECTION_NUMBER 3
 '@S9S_MB_2U_LIB.S9S_MB_2U(SCH_1):PAGE105_I180@PURE_QUANTA.SCONN288_ADR50017P087CC(CHIPS)':
 C_PATH='@s9s_mb_2u_lib.s9s_mb_2u(sch_1):page105_i180@pure_quanta.sconn288_adr50~
017p087cc(chips)',
 P_PATH='@s9s_mb_2u_lib.s9s_mb_2u(sch_1):page105_i180@pure_quanta.sconn288_adr50~
017p087cc(chips)',
 PATH='I180',
 DRAWING='@S9S_MB_2U_LIB.S9S_MB_2U(SCH_1):PAGE105',
 PHYS_PAGE='105',
 XY='(4075,2650)',
 ROT='0',
 VER='3',
 CDS_LIB='pure_quanta',
 CDS_PART_NAME='SCONN288_ADR50017P087CC-SCONN2A',
 PART_TYPE='SMLF',
 MATERIAL='IO',
 VALUE='SCONN288_ADR50017-P087CC',
 PRIM_FILE='./archive_libs/logical/sconn288_adr50017p087cc/chips/chips.prt';

PART_NAME
 J25 'SCONN288_ADR50017P130CC-SCONN2A':;

SECTION_NUMBER 1
 '@S9S_MB_2U_LIB.S9S_MB_2U(SCH_1):PAGE106_I180@PURE_QUANTA.SCONN288_ADR50017P130CC(CHIPS)':
 C_PATH='@s9s_mb_2u_lib.s9s_mb_2u(sch_1):page106_i180@pure_quanta.sconn288_adr50~
017p130cc(chips)',
 P_PATH='@s9s_mb_2u_lib.s9s_mb_2u(sch_1):page106_i180@pure_quanta.sconn288_adr50~
017p130cc(chips)',
 PATH='I180',
 DRAWING='@S9S_MB_2U_LIB.S9S_MB_2U(SCH_1):PAGE106',
 PHYS_PAGE='106',
 XY='(-1925,2250)',
 ROT='0',
 VER='1',
 CDS_LIB='pure_quanta',
 CDS_PART_NAME='SCONN288_ADR50017P130CC-SCONN2A',
 PART_TYPE='SMLF',
 MATERIAL='IO',
 VALUE='SCONN288_ADR50017-P130CC',
 PRIM_FILE='./archive_libs/logical/sconn288_adr50017p130cc/chips/chips.prt';

SECTION_NUMBER 2
 '@S9S_MB_2U_LIB.S9S_MB_2U(SCH_1):PAGE106_I181@PURE_QUANTA.SCONN288_ADR50017P130CC(CHIPS)':
 C_PATH='@s9s_mb_2u_lib.s9s_mb_2u(sch_1):page106_i181@pure_quanta.sconn288_adr50~
017p130cc(chips)',
 P_PATH='@s9s_mb_2u_lib.s9s_mb_2u(sch_1):page106_i181@pure_quanta.sconn288_adr50~
017p130cc(chips)',
 PATH='I181',
 DRAWING='@S9S_MB_2U_LIB.S9S_MB_2U(SCH_1):PAGE106',
 PHYS_PAGE='106',
 XY='(750,2975)',
 ROT='0',
 VER='2',
 LOCATION='J25',
 CDS_LIB='pure_quanta',
 CDS_PART_NAME='SCONN288_ADR50017P130CC-SCONN2A',
 PART_TYPE='SMLF',
 MATERIAL='IO',
 VALUE='SCONN288_ADR50017-P130CC',
 PRIM_FILE='./archive_libs/logical/sconn288_adr50017p130cc/chips/chips.prt';

SECTION_NUMBER 3
 '@S9S_MB_2U_LIB.S9S_MB_2U(SCH_1):PAGE106_I178@PURE_QUANTA.SCONN288_ADR50017P130CC(CHIPS)':
 C_PATH='@s9s_mb_2u_lib.s9s_mb_2u(sch_1):page106_i178@pure_quanta.sconn288_adr50~
017p130cc(chips)',
 P_PATH='@s9s_mb_2u_lib.s9s_mb_2u(sch_1):page106_i178@pure_quanta.sconn288_adr50~
017p130cc(chips)',
 PATH='I178',
 DRAWING='@S9S_MB_2U_LIB.S9S_MB_2U(SCH_1):PAGE106',
 PHYS_PAGE='106',
 XY='(4175,2350)',
 ROT='0',
 VER='3',
 CDS_LIB='pure_quanta',
 CDS_PART_NAME='SCONN288_ADR50017P130CC-SCONN2A',
 PART_TYPE='SMLF',
 MATERIAL='IO',
 VALUE='SCONN288_ADR50017-P130CC',
 PRIM_FILE='./archive_libs/logical/sconn288_adr50017p130cc/chips/chips.prt';

PART_NAME
 J26 'SCONN288_ADR50017P087CC-SCONN2A':;

SECTION_NUMBER 1
 '@S9S_MB_2U_LIB.S9S_MB_2U(SCH_1):PAGE107_I180@PURE_QUANTA.SCONN288_ADR50017P087CC(CHIPS)':
 C_PATH='@s9s_mb_2u_lib.s9s_mb_2u(sch_1):page107_i180@pure_quanta.sconn288_adr50~
017p087cc(chips)',
 P_PATH='@s9s_mb_2u_lib.s9s_mb_2u(sch_1):page107_i180@pure_quanta.sconn288_adr50~
017p087cc(chips)',
 PATH='I180',
 DRAWING='@S9S_MB_2U_LIB.S9S_MB_2U(SCH_1):PAGE107',
 PHYS_PAGE='107',
 XY='(-1675,2650)',
 ROT='0',
 VER='1',
 CDS_LIB='pure_quanta',
 CDS_PART_NAME='SCONN288_ADR50017P087CC-SCONN2A',
 PART_TYPE='SMLF',
 MATERIAL='IO',
 VALUE='SCONN288_ADR50017-P087CC',
 PRIM_FILE='./archive_libs/logical/sconn288_adr50017p087cc/chips/chips.prt';

SECTION_NUMBER 2
 '@S9S_MB_2U_LIB.S9S_MB_2U(SCH_1):PAGE107_I181@PURE_QUANTA.SCONN288_ADR50017P087CC(CHIPS)':
 C_PATH='@s9s_mb_2u_lib.s9s_mb_2u(sch_1):page107_i181@pure_quanta.sconn288_adr50~
017p087cc(chips)',
 P_PATH='@s9s_mb_2u_lib.s9s_mb_2u(sch_1):page107_i181@pure_quanta.sconn288_adr50~
017p087cc(chips)',
 PATH='I181',
 DRAWING='@S9S_MB_2U_LIB.S9S_MB_2U(SCH_1):PAGE107',
 PHYS_PAGE='107',
 XY='(1000,3375)',
 ROT='0',
 VER='2',
 LOCATION='J26',
 CDS_LIB='pure_quanta',
 CDS_PART_NAME='SCONN288_ADR50017P087CC-SCONN2A',
 PART_TYPE='SMLF',
 MATERIAL='IO',
 VALUE='SCONN288_ADR50017-P087CC',
 PRIM_FILE='./archive_libs/logical/sconn288_adr50017p087cc/chips/chips.prt';

SECTION_NUMBER 3
 '@S9S_MB_2U_LIB.S9S_MB_2U(SCH_1):PAGE107_I179@PURE_QUANTA.SCONN288_ADR50017P087CC(CHIPS)':
 C_PATH='@s9s_mb_2u_lib.s9s_mb_2u(sch_1):page107_i179@pure_quanta.sconn288_adr50~
017p087cc(chips)',
 P_PATH='@s9s_mb_2u_lib.s9s_mb_2u(sch_1):page107_i179@pure_quanta.sconn288_adr50~
017p087cc(chips)',
 PATH='I179',
 DRAWING='@S9S_MB_2U_LIB.S9S_MB_2U(SCH_1):PAGE107',
 PHYS_PAGE='107',
 XY='(4425,2750)',
 ROT='0',
 VER='3',
 CDS_LIB='pure_quanta',
 CDS_PART_NAME='SCONN288_ADR50017P087CC-SCONN2A',
 PART_TYPE='SMLF',
 MATERIAL='IO',
 VALUE='SCONN288_ADR50017-P087CC',
 PRIM_FILE='./archive_libs/logical/sconn288_adr50017p087cc/chips/chips.prt';

PART_NAME
 J27 'SCONN288_ADR50017P130CC-SCONN2A':;

SECTION_NUMBER 1
 '@S9S_MB_2U_LIB.S9S_MB_2U(SCH_1):PAGE108_I179@PURE_QUANTA.SCONN288_ADR50017P130CC(CHIPS)':
 C_PATH='@s9s_mb_2u_lib.s9s_mb_2u(sch_1):page108_i179@pure_quanta.sconn288_adr50~
017p130cc(chips)',
 P_PATH='@s9s_mb_2u_lib.s9s_mb_2u(sch_1):page108_i179@pure_quanta.sconn288_adr50~
017p130cc(chips)',
 PATH='I179',
 DRAWING='@S9S_MB_2U_LIB.S9S_MB_2U(SCH_1):PAGE108',
 PHYS_PAGE='108',
 XY='(-1900,3625)',
 ROT='0',
 VER='1',
 CDS_LIB='pure_quanta',
 CDS_PART_NAME='SCONN288_ADR50017P130CC-SCONN2A',
 PART_TYPE='SMLF',
 MATERIAL='IO',
 VALUE='SCONN288_ADR50017-P130CC',
 PRIM_FILE='./archive_libs/logical/sconn288_adr50017p130cc/chips/chips.prt';

SECTION_NUMBER 2
 '@S9S_MB_2U_LIB.S9S_MB_2U(SCH_1):PAGE108_I180@PURE_QUANTA.SCONN288_ADR50017P130CC(CHIPS)':
 C_PATH='@s9s_mb_2u_lib.s9s_mb_2u(sch_1):page108_i180@pure_quanta.sconn288_adr50~
017p130cc(chips)',
 P_PATH='@s9s_mb_2u_lib.s9s_mb_2u(sch_1):page108_i180@pure_quanta.sconn288_adr50~
017p130cc(chips)',
 PATH='I180',
 DRAWING='@S9S_MB_2U_LIB.S9S_MB_2U(SCH_1):PAGE108',
 PHYS_PAGE='108',
 XY='(775,4350)',
 ROT='0',
 VER='2',
 LOCATION='J27',
 CDS_LIB='pure_quanta',
 CDS_PART_NAME='SCONN288_ADR50017P130CC-SCONN2A',
 PART_TYPE='SMLF',
 MATERIAL='IO',
 VALUE='SCONN288_ADR50017-P130CC',
 PRIM_FILE='./archive_libs/logical/sconn288_adr50017p130cc/chips/chips.prt';

SECTION_NUMBER 3
 '@S9S_MB_2U_LIB.S9S_MB_2U(SCH_1):PAGE108_I178@PURE_QUANTA.SCONN288_ADR50017P130CC(CHIPS)':
 C_PATH='@s9s_mb_2u_lib.s9s_mb_2u(sch_1):page108_i178@pure_quanta.sconn288_adr50~
017p130cc(chips)',
 P_PATH='@s9s_mb_2u_lib.s9s_mb_2u(sch_1):page108_i178@pure_quanta.sconn288_adr50~
017p130cc(chips)',
 PATH='I178',
 DRAWING='@S9S_MB_2U_LIB.S9S_MB_2U(SCH_1):PAGE108',
 PHYS_PAGE='108',
 XY='(4200,3725)',
 ROT='0',
 VER='3',
 CDS_LIB='pure_quanta',
 CDS_PART_NAME='SCONN288_ADR50017P130CC-SCONN2A',
 PART_TYPE='SMLF',
 MATERIAL='IO',
 VALUE='SCONN288_ADR50017-P130CC',
 PRIM_FILE='./archive_libs/logical/sconn288_adr50017p130cc/chips/chips.prt';

PART_NAME
 J28 'SCONN288_ADR50017P087CC-SCONN2A':;

SECTION_NUMBER 1
 '@S9S_MB_2U_LIB.S9S_MB_2U(SCH_1):PAGE109_I47@PURE_QUANTA.SCONN288_ADR50017P087CC(CHIPS)':
 C_PATH='@s9s_mb_2u_lib.s9s_mb_2u(sch_1):page109_i47@pure_quanta.sconn288_adr500~
17p087cc(chips)',
 P_PATH='@s9s_mb_2u_lib.s9s_mb_2u(sch_1):page109_i47@pure_quanta.sconn288_adr500~
17p087cc(chips)',
 PATH='I47',
 DRAWING='@S9S_MB_2U_LIB.S9S_MB_2U(SCH_1):PAGE109',
 PHYS_PAGE='109',
 XY='(-1625,2475)',
 ROT='0',
 VER='1',
 CDS_LIB='pure_quanta',
 CDS_PART_NAME='SCONN288_ADR50017P087CC-SCONN2A',
 PART_TYPE='SMLF',
 MATERIAL='IO',
 VALUE='SCONN288_ADR50017-P087CC',
 PRIM_FILE='./archive_libs/logical/sconn288_adr50017p087cc/chips/chips.prt';

SECTION_NUMBER 2
 '@S9S_MB_2U_LIB.S9S_MB_2U(SCH_1):PAGE109_I178@PURE_QUANTA.SCONN288_ADR50017P087CC(CHIPS)':
 C_PATH='@s9s_mb_2u_lib.s9s_mb_2u(sch_1):page109_i178@pure_quanta.sconn288_adr50~
017p087cc(chips)',
 P_PATH='@s9s_mb_2u_lib.s9s_mb_2u(sch_1):page109_i178@pure_quanta.sconn288_adr50~
017p087cc(chips)',
 PATH='I178',
 DRAWING='@S9S_MB_2U_LIB.S9S_MB_2U(SCH_1):PAGE109',
 PHYS_PAGE='109',
 XY='(1050,3200)',
 ROT='0',
 VER='2',
 LOCATION='J28',
 CDS_LIB='pure_quanta',
 CDS_PART_NAME='SCONN288_ADR50017P087CC-SCONN2A',
 PART_TYPE='SMLF',
 MATERIAL='IO',
 VALUE='SCONN288_ADR50017-P087CC',
 PRIM_FILE='./archive_libs/logical/sconn288_adr50017p087cc/chips/chips.prt';

SECTION_NUMBER 3
 '@S9S_MB_2U_LIB.S9S_MB_2U(SCH_1):PAGE109_I176@PURE_QUANTA.SCONN288_ADR50017P087CC(CHIPS)':
 C_PATH='@s9s_mb_2u_lib.s9s_mb_2u(sch_1):page109_i176@pure_quanta.sconn288_adr50~
017p087cc(chips)',
 P_PATH='@s9s_mb_2u_lib.s9s_mb_2u(sch_1):page109_i176@pure_quanta.sconn288_adr50~
017p087cc(chips)',
 PATH='I176',
 DRAWING='@S9S_MB_2U_LIB.S9S_MB_2U(SCH_1):PAGE109',
 PHYS_PAGE='109',
 XY='(4475,2575)',
 ROT='0',
 VER='3',
 CDS_LIB='pure_quanta',
 CDS_PART_NAME='SCONN288_ADR50017P087CC-SCONN2A',
 PART_TYPE='SMLF',
 MATERIAL='IO',
 VALUE='SCONN288_ADR50017-P087CC',
 PRIM_FILE='./archive_libs/logical/sconn288_adr50017p087cc/chips/chips.prt';

PART_NAME
 J29 'SCONN288_ADR50017P130CC-SCONN2A':;

SECTION_NUMBER 1
 '@S9S_MB_2U_LIB.S9S_MB_2U(SCH_1):PAGE110_I179@PURE_QUANTA.SCONN288_ADR50017P130CC(CHIPS)':
 C_PATH='@s9s_mb_2u_lib.s9s_mb_2u(sch_1):page110_i179@pure_quanta.sconn288_adr50~
017p130cc(chips)',
 P_PATH='@s9s_mb_2u_lib.s9s_mb_2u(sch_1):page110_i179@pure_quanta.sconn288_adr50~
017p130cc(chips)',
 PATH='I179',
 DRAWING='@S9S_MB_2U_LIB.S9S_MB_2U(SCH_1):PAGE110',
 PHYS_PAGE='110',
 XY='(-1750,2225)',
 ROT='0',
 VER='1',
 CDS_LIB='pure_quanta',
 CDS_PART_NAME='SCONN288_ADR50017P130CC-SCONN2A',
 PART_TYPE='SMLF',
 MATERIAL='IO',
 VALUE='SCONN288_ADR50017-P130CC',
 PRIM_FILE='./archive_libs/logical/sconn288_adr50017p130cc/chips/chips.prt';

SECTION_NUMBER 2
 '@S9S_MB_2U_LIB.S9S_MB_2U(SCH_1):PAGE110_I180@PURE_QUANTA.SCONN288_ADR50017P130CC(CHIPS)':
 C_PATH='@s9s_mb_2u_lib.s9s_mb_2u(sch_1):page110_i180@pure_quanta.sconn288_adr50~
017p130cc(chips)',
 P_PATH='@s9s_mb_2u_lib.s9s_mb_2u(sch_1):page110_i180@pure_quanta.sconn288_adr50~
017p130cc(chips)',
 PATH='I180',
 DRAWING='@S9S_MB_2U_LIB.S9S_MB_2U(SCH_1):PAGE110',
 PHYS_PAGE='110',
 XY='(925,2950)',
 ROT='0',
 VER='2',
 LOCATION='J29',
 CDS_LIB='pure_quanta',
 CDS_PART_NAME='SCONN288_ADR50017P130CC-SCONN2A',
 PART_TYPE='SMLF',
 MATERIAL='IO',
 VALUE='SCONN288_ADR50017-P130CC',
 PRIM_FILE='./archive_libs/logical/sconn288_adr50017p130cc/chips/chips.prt';

SECTION_NUMBER 3
 '@S9S_MB_2U_LIB.S9S_MB_2U(SCH_1):PAGE110_I178@PURE_QUANTA.SCONN288_ADR50017P130CC(CHIPS)':
 C_PATH='@s9s_mb_2u_lib.s9s_mb_2u(sch_1):page110_i178@pure_quanta.sconn288_adr50~
017p130cc(chips)',
 P_PATH='@s9s_mb_2u_lib.s9s_mb_2u(sch_1):page110_i178@pure_quanta.sconn288_adr50~
017p130cc(chips)',
 PATH='I178',
 DRAWING='@S9S_MB_2U_LIB.S9S_MB_2U(SCH_1):PAGE110',
 PHYS_PAGE='110',
 XY='(4350,2325)',
 ROT='0',
 VER='3',
 CDS_LIB='pure_quanta',
 CDS_PART_NAME='SCONN288_ADR50017P130CC-SCONN2A',
 PART_TYPE='SMLF',
 MATERIAL='IO',
 VALUE='SCONN288_ADR50017-P130CC',
 PRIM_FILE='./archive_libs/logical/sconn288_adr50017p130cc/chips/chips.prt';

PART_NAME
 J30 'SCONN288_ADR50017P087CC-SCONN2A':;

SECTION_NUMBER 1
 '@S9S_MB_2U_LIB.S9S_MB_2U(SCH_1):PAGE111_I179@PURE_QUANTA.SCONN288_ADR50017P087CC(CHIPS)':
 C_PATH='@s9s_mb_2u_lib.s9s_mb_2u(sch_1):page111_i179@pure_quanta.sconn288_adr50~
017p087cc(chips)',
 P_PATH='@s9s_mb_2u_lib.s9s_mb_2u(sch_1):page111_i179@pure_quanta.sconn288_adr50~
017p087cc(chips)',
 PATH='I179',
 DRAWING='@S9S_MB_2U_LIB.S9S_MB_2U(SCH_1):PAGE111',
 PHYS_PAGE='111',
 XY='(-2325,2675)',
 ROT='0',
 VER='1',
 CDS_LIB='pure_quanta',
 CDS_PART_NAME='SCONN288_ADR50017P087CC-SCONN2A',
 PART_TYPE='SMLF',
 MATERIAL='IO',
 VALUE='SCONN288_ADR50017-P087CC',
 PRIM_FILE='./archive_libs/logical/sconn288_adr50017p087cc/chips/chips.prt';

SECTION_NUMBER 2
 '@S9S_MB_2U_LIB.S9S_MB_2U(SCH_1):PAGE111_I180@PURE_QUANTA.SCONN288_ADR50017P087CC(CHIPS)':
 C_PATH='@s9s_mb_2u_lib.s9s_mb_2u(sch_1):page111_i180@pure_quanta.sconn288_adr50~
017p087cc(chips)',
 P_PATH='@s9s_mb_2u_lib.s9s_mb_2u(sch_1):page111_i180@pure_quanta.sconn288_adr50~
017p087cc(chips)',
 PATH='I180',
 DRAWING='@S9S_MB_2U_LIB.S9S_MB_2U(SCH_1):PAGE111',
 PHYS_PAGE='111',
 XY='(350,3400)',
 ROT='0',
 VER='2',
 LOCATION='J30',
 CDS_LIB='pure_quanta',
 CDS_PART_NAME='SCONN288_ADR50017P087CC-SCONN2A',
 PART_TYPE='SMLF',
 MATERIAL='IO',
 VALUE='SCONN288_ADR50017-P087CC',
 PRIM_FILE='./archive_libs/logical/sconn288_adr50017p087cc/chips/chips.prt';

SECTION_NUMBER 3
 '@S9S_MB_2U_LIB.S9S_MB_2U(SCH_1):PAGE111_I178@PURE_QUANTA.SCONN288_ADR50017P087CC(CHIPS)':
 C_PATH='@s9s_mb_2u_lib.s9s_mb_2u(sch_1):page111_i178@pure_quanta.sconn288_adr50~
017p087cc(chips)',
 P_PATH='@s9s_mb_2u_lib.s9s_mb_2u(sch_1):page111_i178@pure_quanta.sconn288_adr50~
017p087cc(chips)',
 PATH='I178',
 DRAWING='@S9S_MB_2U_LIB.S9S_MB_2U(SCH_1):PAGE111',
 PHYS_PAGE='111',
 XY='(3775,2775)',
 ROT='0',
 VER='3',
 CDS_LIB='pure_quanta',
 CDS_PART_NAME='SCONN288_ADR50017P087CC-SCONN2A',
 PART_TYPE='SMLF',
 MATERIAL='IO',
 VALUE='SCONN288_ADR50017-P087CC',
 PRIM_FILE='./archive_libs/logical/sconn288_adr50017p087cc/chips/chips.prt';

PART_NAME
 J31 'SCONN288_ADR50017P130CC-SCONN2A':;

SECTION_NUMBER 1
 '@S9S_MB_2U_LIB.S9S_MB_2U(SCH_1):PAGE112_I180@PURE_QUANTA.SCONN288_ADR50017P130CC(CHIPS)':
 C_PATH='@s9s_mb_2u_lib.s9s_mb_2u(sch_1):page112_i180@pure_quanta.sconn288_adr50~
017p130cc(chips)',
 P_PATH='@s9s_mb_2u_lib.s9s_mb_2u(sch_1):page112_i180@pure_quanta.sconn288_adr50~
017p130cc(chips)',
 PATH='I180',
 DRAWING='@S9S_MB_2U_LIB.S9S_MB_2U(SCH_1):PAGE112',
 PHYS_PAGE='112',
 XY='(-2425,2575)',
 ROT='0',
 VER='1',
 CDS_LIB='pure_quanta',
 CDS_PART_NAME='SCONN288_ADR50017P130CC-SCONN2A',
 PART_TYPE='SMLF',
 MATERIAL='IO',
 VALUE='SCONN288_ADR50017-P130CC',
 PRIM_FILE='./archive_libs/logical/sconn288_adr50017p130cc/chips/chips.prt';

SECTION_NUMBER 2
 '@S9S_MB_2U_LIB.S9S_MB_2U(SCH_1):PAGE112_I181@PURE_QUANTA.SCONN288_ADR50017P130CC(CHIPS)':
 C_PATH='@s9s_mb_2u_lib.s9s_mb_2u(sch_1):page112_i181@pure_quanta.sconn288_adr50~
017p130cc(chips)',
 P_PATH='@s9s_mb_2u_lib.s9s_mb_2u(sch_1):page112_i181@pure_quanta.sconn288_adr50~
017p130cc(chips)',
 PATH='I181',
 DRAWING='@S9S_MB_2U_LIB.S9S_MB_2U(SCH_1):PAGE112',
 PHYS_PAGE='112',
 XY='(250,3300)',
 ROT='0',
 VER='2',
 LOCATION='J31',
 CDS_LIB='pure_quanta',
 CDS_PART_NAME='SCONN288_ADR50017P130CC-SCONN2A',
 PART_TYPE='SMLF',
 MATERIAL='IO',
 VALUE='SCONN288_ADR50017-P130CC',
 PRIM_FILE='./archive_libs/logical/sconn288_adr50017p130cc/chips/chips.prt';

SECTION_NUMBER 3
 '@S9S_MB_2U_LIB.S9S_MB_2U(SCH_1):PAGE112_I178@PURE_QUANTA.SCONN288_ADR50017P130CC(CHIPS)':
 C_PATH='@s9s_mb_2u_lib.s9s_mb_2u(sch_1):page112_i178@pure_quanta.sconn288_adr50~
017p130cc(chips)',
 P_PATH='@s9s_mb_2u_lib.s9s_mb_2u(sch_1):page112_i178@pure_quanta.sconn288_adr50~
017p130cc(chips)',
 PATH='I178',
 DRAWING='@S9S_MB_2U_LIB.S9S_MB_2U(SCH_1):PAGE112',
 PHYS_PAGE='112',
 XY='(3675,2675)',
 ROT='0',
 VER='3',
 CDS_LIB='pure_quanta',
 CDS_PART_NAME='SCONN288_ADR50017P130CC-SCONN2A',
 PART_TYPE='SMLF',
 MATERIAL='IO',
 VALUE='SCONN288_ADR50017-P130CC',
 PRIM_FILE='./archive_libs/logical/sconn288_adr50017p130cc/chips/chips.prt';

PART_NAME
 J32 'SCONN288_ADR50017P087CC-SCONN2A':;

SECTION_NUMBER 1
 '@S9S_MB_2U_LIB.S9S_MB_2U(SCH_1):PAGE113_I179@PURE_QUANTA.SCONN288_ADR50017P087CC(CHIPS)':
 C_PATH='@s9s_mb_2u_lib.s9s_mb_2u(sch_1):page113_i179@pure_quanta.sconn288_adr50~
017p087cc(chips)',
 P_PATH='@s9s_mb_2u_lib.s9s_mb_2u(sch_1):page113_i179@pure_quanta.sconn288_adr50~
017p087cc(chips)',
 PATH='I179',
 DRAWING='@S9S_MB_2U_LIB.S9S_MB_2U(SCH_1):PAGE113',
 PHYS_PAGE='113',
 XY='(-3075,2725)',
 ROT='0',
 VER='1',
 CDS_LIB='pure_quanta',
 CDS_PART_NAME='SCONN288_ADR50017P087CC-SCONN2A',
 PART_TYPE='SMLF',
 MATERIAL='IO',
 VALUE='SCONN288_ADR50017-P087CC',
 PRIM_FILE='./archive_libs/logical/sconn288_adr50017p087cc/chips/chips.prt';

SECTION_NUMBER 2
 '@S9S_MB_2U_LIB.S9S_MB_2U(SCH_1):PAGE113_I180@PURE_QUANTA.SCONN288_ADR50017P087CC(CHIPS)':
 C_PATH='@s9s_mb_2u_lib.s9s_mb_2u(sch_1):page113_i180@pure_quanta.sconn288_adr50~
017p087cc(chips)',
 P_PATH='@s9s_mb_2u_lib.s9s_mb_2u(sch_1):page113_i180@pure_quanta.sconn288_adr50~
017p087cc(chips)',
 PATH='I180',
 DRAWING='@S9S_MB_2U_LIB.S9S_MB_2U(SCH_1):PAGE113',
 PHYS_PAGE='113',
 XY='(-400,3450)',
 ROT='0',
 VER='2',
 LOCATION='J32',
 CDS_LIB='pure_quanta',
 CDS_PART_NAME='SCONN288_ADR50017P087CC-SCONN2A',
 PART_TYPE='SMLF',
 MATERIAL='IO',
 VALUE='SCONN288_ADR50017-P087CC',
 PRIM_FILE='./archive_libs/logical/sconn288_adr50017p087cc/chips/chips.prt';

SECTION_NUMBER 3
 '@S9S_MB_2U_LIB.S9S_MB_2U(SCH_1):PAGE113_I177@PURE_QUANTA.SCONN288_ADR50017P087CC(CHIPS)':
 C_PATH='@s9s_mb_2u_lib.s9s_mb_2u(sch_1):page113_i177@pure_quanta.sconn288_adr50~
017p087cc(chips)',
 P_PATH='@s9s_mb_2u_lib.s9s_mb_2u(sch_1):page113_i177@pure_quanta.sconn288_adr50~
017p087cc(chips)',
 PATH='I177',
 DRAWING='@S9S_MB_2U_LIB.S9S_MB_2U(SCH_1):PAGE113',
 PHYS_PAGE='113',
 XY='(3025,2825)',
 ROT='0',
 VER='3',
 CDS_LIB='pure_quanta',
 CDS_PART_NAME='SCONN288_ADR50017P087CC-SCONN2A',
 PART_TYPE='SMLF',
 MATERIAL='IO',
 VALUE='SCONN288_ADR50017-P087CC',
 PRIM_FILE='./archive_libs/logical/sconn288_adr50017p087cc/chips/chips.prt';

PART_NAME
 J35 'SCONN168_ME1016810202011-SCONNA':;

SECTION_NUMBER 1
 '@S9S_MB_2U_LIB.S9S_MB_2U(SCH_1):PAGE146_I303@PURE_QUANTA.SCONN168_ME1016810202011(CHIPS)':
 C_PATH='@s9s_mb_2u_lib.s9s_mb_2u(sch_1):page146_i303@pure_quanta.sconn168_me101~
6810202011(chips)',
 P_PATH='@s9s_mb_2u_lib.s9s_mb_2u(sch_1):page159_i303@pure_quanta.sconn168_me101~
6810202011(chips)',
 PATH='I303',
 DRAWING='@S9S_MB_2U_LIB.S9S_MB_2U(SCH_1):PAGE146',
 PHYS_PAGE='159',
 XY='(4500,2800)',
 ROT='0',
 VER='1',
 LOCATION='J35',
 CDS_LIB='pure_quanta',
 CDS_PART_NAME='SCONN168_ME1016810202011-SCONNA',
 PART_TYPE='SMLF',
 MATERIAL='IO',
 VALUE='SCONN168_ME1016810202011',
 PRIM_FILE='./archive_libs/logical/sconn168_me1016810202011/chips/chips.prt';

PART_NAME
 J37 'SCONN168_ME1016810202011-SCONNA':;

SECTION_NUMBER 1
 '@S9S_MB_2U_LIB.S9S_MB_2U(SCH_1):PAGE150_I199@PURE_QUANTA.SCONN168_ME1016810202011(CHIPS)':
 C_PATH='@s9s_mb_2u_lib.s9s_mb_2u(sch_1):page150_i199@pure_quanta.sconn168_me101~
6810202011(chips)',
 P_PATH='@s9s_mb_2u_lib.s9s_mb_2u(sch_1):page153_i199@pure_quanta.sconn168_me101~
6810202011(chips)',
 PATH='I199',
 DRAWING='@S9S_MB_2U_LIB.S9S_MB_2U(SCH_1):PAGE150',
 PHYS_PAGE='153',
 XY='(-375,4725)',
 ROT='0',
 VER='1',
 LOCATION='J37',
 SEC='1',
 CDS_LIB='pure_quanta',
 CDS_PART_NAME='SCONN168_ME1016810202011-SCONNA',
 SEC_TYPE='',
 PART_TYPE='SMLF',
 MATERIAL='IO',
 VALUE='SCONN168_ME1016810202011',
 PRIM_FILE='./archive_libs/logical/sconn168_me1016810202011/chips/chips.prt';

PART_NAME
 J41 'SCONN168_ME1016810202011-SCONNA':;

SECTION_NUMBER 1
 '@S9S_MB_2U_LIB.S9S_MB_2U(SCH_1):PAGE227_I173@PURE_QUANTA.SCONN168_ME1016810202011(CHIPS)':
 C_PATH='@s9s_mb_2u_lib.s9s_mb_2u(sch_1):page227_i173@pure_quanta.sconn168_me101~
6810202011(chips)',
 P_PATH='@s9s_mb_2u_lib.s9s_mb_2u(sch_1):page240_i173@pure_quanta.sconn168_me101~
6810202011(chips)',
 PATH='I173',
 DRAWING='@S9S_MB_2U_LIB.S9S_MB_2U(SCH_1):PAGE227',
 PHYS_PAGE='240',
 XY='(-10400,-200)',
 ROT='2',
 VER='1',
 LOCATION='J41',
 SEC='1',
 CDS_LIB='pure_quanta',
 CDS_PART_NAME='SCONN168_ME1016810202011-SCONNA',
 SEC_TYPE='',
 PART_TYPE='SMLF',
 MATERIAL='IO',
 VALUE='SCONN168_ME1016810202011',
 PRIM_FILE='./archive_libs/logical/sconn168_me1016810202011/chips/chips.prt';

PART_NAME
 J42 'SCONN60_ASP21410801-SCONN60_ASA':;

SECTION_NUMBER 1
 '@S9S_MB_2U_LIB.S9S_MB_2U(SCH_1):PAGE133_I44@PURE_QUANTA.SCONN60_ASP21410801(CHIPS)':
 C_PATH='@s9s_mb_2u_lib.s9s_mb_2u(sch_1):page133_i44@pure_quanta.sconn60_asp2141~
0801(chips)',
 P_PATH='@s9s_mb_2u_lib.s9s_mb_2u(sch_1):page131_i44@pure_quanta.sconn60_asp2141~
0801(chips)',
 PATH='I44',
 DRAWING='@S9S_MB_2U_LIB.S9S_MB_2U(SCH_1):PAGE133',
 PHYS_PAGE='131',
 XY='(375,2425)',
 ROT='0',
 VER='1',
 CDS_LIB='pure_quanta',
 CDS_PART_NAME='SCONN60_ASP21410801-SCONN60_ASA',
 PART_TYPE='SMLF',
 MATERIAL='IO',
 VALUE='SCONN60_ASP-214108-01',
 PRIM_FILE='./archive_libs/logical/sconn60_asp21410801/chips/chips.prt';

PART_NAME
 J43 'CONN8_210HP1080BR1-CONN8_210-HA':;

SECTION_NUMBER 1
 '@S9S_MB_2U_LIB.S9S_MB_2U(SCH_1):PAGE210_I79@PURE_QUANTA.CONN8_210HP1080BR1(CHIPS)':
 C_PATH='@s9s_mb_2u_lib.s9s_mb_2u(sch_1):page210_i79@pure_quanta.conn8_210hp1080~
br1(chips)',
 P_PATH='@s9s_mb_2u_lib.s9s_mb_2u(sch_1):page221_i79@pure_quanta.conn8_210hp1080~
br1(chips)',
 PATH='I79',
 DRAWING='@S9S_MB_2U_LIB.S9S_MB_2U(SCH_1):PAGE210',
 PHYS_PAGE='221',
 XY='(-425,750)',
 ROT='0',
 VER='1',
 LOCATION='J43',
 CDS_LIB='pure_quanta',
 CDS_PART_NAME='CONN8_210HP1080BR1-CONN8_210-HA',
 PART_TYPE='THLF',
 MATERIAL='IO',
 VALUE='CONN8_210-HP1-080BR1',
 PRIM_FILE='./archive_libs/logical/conn8_210hp1080br1/chips/chips.prt';

PART_NAME
 J45 'CONN60_101062636003K02LF-CONN6A':;

SECTION_NUMBER 1
 '@S9S_MB_2U_LIB.S9S_MB_2U(SCH_1):PAGE233_I12@PURE_QUANTA.CONN60_101062636003K02LF(CHIPS)':
 C_PATH='@s9s_mb_2u_lib.s9s_mb_2u(sch_1):page233_i12@pure_quanta.conn60_10106263~
6003k02lf(chips)',
 P_PATH='@s9s_mb_2u_lib.s9s_mb_2u(sch_1):page245_i12@pure_quanta.conn60_10106263~
6003k02lf(chips)',
 PATH='I12',
 DRAWING='@S9S_MB_2U_LIB.S9S_MB_2U(SCH_1):PAGE233',
 PHYS_PAGE='245',
 XY='(-3200,1150)',
 ROT='0',
 VER='1',
 LOCATION='J45',
 CDS_LIB='pure_quanta',
 CDS_PART_NAME='CONN60_101062636003K02LF-CONN6A',
 PART_TYPE='THLF',
 MATERIAL='IO',
 VALUE='CONN60_10106263-6003K02LF',
 PRIM_FILE='./archive_libs/logical/conn60_101062636003k02lf/chips/chips.prt';

PART_NAME
 J59 'SCONN75K_APCI0155P004A-SCONN75A':;

SECTION_NUMBER 1
 '@S9S_MB_2U_LIB.S9S_MB_2U(SCH_1):PAGE182_I178@PURE_QUANTA.SCONN75K_APCI0155P004A(CHIPS)':
 C_PATH='@s9s_mb_2u_lib.s9s_mb_2u(sch_1):page182_i178@pure_quanta.sconn75k_apci0~
155p004a(chips)',
 P_PATH='@s9s_mb_2u_lib.s9s_mb_2u(sch_1):page190_i178@pure_quanta.sconn75k_apci0~
155p004a(chips)',
 PATH='I178',
 DRAWING='@S9S_MB_2U_LIB.S9S_MB_2U(SCH_1):PAGE182',
 PIN_NAMES_ROTATE='True',
 PHYS_PAGE='190',
 XY='(8725,3325)',
 ROT='2',
 VER='1',
 CDS_LIB='pure_quanta',
 CDS_PART_NAME='SCONN75K_APCI0155P004A-SCONN75A',
 PART_TYPE='SMLF',
 MATERIAL='EMPTY',
 VALUE='SCONN75K_APCI0155-P004A',
 PRIM_FILE='./archive_libs/logical/sconn75k_apci0155p004a/chips/chips.prt';

PART_NAME
 J63 'PICOPROBE_BXA-DELTA-L 4.0,SMLFA':;

SECTION_NUMBER 1
 '@S9S_MB_2U_LIB.S9S_MB_2U(SCH_1):PAGE287_I18@PURE_QUANTA.PICOPROBE_BXA(CHIPS)':
 C_PATH='@s9s_mb_2u_lib.s9s_mb_2u(sch_1):page287_i18@pure_quanta.picoprobe_bxa(c~
hips)',
 P_PATH='@s9s_mb_2u_lib.s9s_mb_2u(sch_1):page308_i18@pure_quanta.picoprobe_bxa(c~
hips)',
 PATH='I18',
 DRAWING='@S9S_MB_2U_LIB.S9S_MB_2U(SCH_1):PAGE287',
 PHYS_PAGE='308',
 XY='(-2400,4525)',
 ROT='0',
 VER='1',
 LOCATION='J63',
 CDS_LIB='pure_quanta',
 CDS_PART_NAME='PICOPROBE_BXA-DELTA-L 4.0,SMLFA',
 PART_TYPE='SMLF',
 MATERIAL='EMPTY',
 VALUE='DELTA-L 4.0',
 PRIM_FILE='./archive_libs/logical/picoprobe_bxa/chips/chips.prt';

PART_NAME
 J64 'PICOPROBE_BXA-DELTA-L 4.0,SMLFA':;

SECTION_NUMBER 1
 '@S9S_MB_2U_LIB.S9S_MB_2U(SCH_1):PAGE287_I17@PURE_QUANTA.PICOPROBE_BXA(CHIPS)':
 C_PATH='@s9s_mb_2u_lib.s9s_mb_2u(sch_1):page287_i17@pure_quanta.picoprobe_bxa(c~
hips)',
 P_PATH='@s9s_mb_2u_lib.s9s_mb_2u(sch_1):page308_i17@pure_quanta.picoprobe_bxa(c~
hips)',
 PATH='I17',
 DRAWING='@S9S_MB_2U_LIB.S9S_MB_2U(SCH_1):PAGE287',
 PHYS_PAGE='308',
 XY='(-2400,3950)',
 ROT='0',
 VER='1',
 LOCATION='J64',
 CDS_LIB='pure_quanta',
 CDS_PART_NAME='PICOPROBE_BXA-DELTA-L 4.0,SMLFA',
 PART_TYPE='SMLF',
 MATERIAL='EMPTY',
 VALUE='DELTA-L 4.0',
 PRIM_FILE='./archive_libs/logical/picoprobe_bxa/chips/chips.prt';

PART_NAME
 J65 'PICOPROBE_BXA-DELTA-L 4.0,SMLFA':;

SECTION_NUMBER 1
 '@S9S_MB_2U_LIB.S9S_MB_2U(SCH_1):PAGE287_I14@PURE_QUANTA.PICOPROBE_BXA(CHIPS)':
 C_PATH='@s9s_mb_2u_lib.s9s_mb_2u(sch_1):page287_i14@pure_quanta.picoprobe_bxa(c~
hips)',
 P_PATH='@s9s_mb_2u_lib.s9s_mb_2u(sch_1):page308_i14@pure_quanta.picoprobe_bxa(c~
hips)',
 PATH='I14',
 DRAWING='@S9S_MB_2U_LIB.S9S_MB_2U(SCH_1):PAGE287',
 PHYS_PAGE='308',
 XY='(-2400,3050)',
 ROT='0',
 VER='1',
 LOCATION='J65',
 CDS_LIB='pure_quanta',
 CDS_PART_NAME='PICOPROBE_BXA-DELTA-L 4.0,SMLFA',
 PART_TYPE='SMLF',
 MATERIAL='EMPTY',
 VALUE='DELTA-L 4.0',
 PRIM_FILE='./archive_libs/logical/picoprobe_bxa/chips/chips.prt';

PART_NAME
 J66 'PICOPROBE_BXA-DELTA-L 4.0,SMLFA':;

SECTION_NUMBER 1
 '@S9S_MB_2U_LIB.S9S_MB_2U(SCH_1):PAGE287_I12@PURE_QUANTA.PICOPROBE_BXA(CHIPS)':
 C_PATH='@s9s_mb_2u_lib.s9s_mb_2u(sch_1):page287_i12@pure_quanta.picoprobe_bxa(c~
hips)',
 P_PATH='@s9s_mb_2u_lib.s9s_mb_2u(sch_1):page308_i12@pure_quanta.picoprobe_bxa(c~
hips)',
 PATH='I12',
 DRAWING='@S9S_MB_2U_LIB.S9S_MB_2U(SCH_1):PAGE287',
 PHYS_PAGE='308',
 XY='(-2400,2475)',
 ROT='0',
 VER='1',
 LOCATION='J66',
 CDS_LIB='pure_quanta',
 CDS_PART_NAME='PICOPROBE_BXA-DELTA-L 4.0,SMLFA',
 PART_TYPE='SMLF',
 MATERIAL='EMPTY',
 VALUE='DELTA-L 4.0',
 PRIM_FILE='./archive_libs/logical/picoprobe_bxa/chips/chips.prt';

PART_NAME
 J67 'PICOPROBE_BXA-DELTA-L 4.0,SMLFA':;

SECTION_NUMBER 1
 '@S9S_MB_2U_LIB.S9S_MB_2U(SCH_1):PAGE287_I11@PURE_QUANTA.PICOPROBE_BXA(CHIPS)':
 C_PATH='@s9s_mb_2u_lib.s9s_mb_2u(sch_1):page287_i11@pure_quanta.picoprobe_bxa(c~
hips)',
 P_PATH='@s9s_mb_2u_lib.s9s_mb_2u(sch_1):page308_i11@pure_quanta.picoprobe_bxa(c~
hips)',
 PATH='I11',
 DRAWING='@S9S_MB_2U_LIB.S9S_MB_2U(SCH_1):PAGE287',
 PHYS_PAGE='308',
 XY='(-2400,1625)',
 ROT='0',
 VER='1',
 LOCATION='J67',
 CDS_LIB='pure_quanta',
 CDS_PART_NAME='PICOPROBE_BXA-DELTA-L 4.0,SMLFA',
 PART_TYPE='SMLF',
 MATERIAL='EMPTY',
 VALUE='DELTA-L 4.0',
 PRIM_FILE='./archive_libs/logical/picoprobe_bxa/chips/chips.prt';

PART_NAME
 J68 'PICOPROBE_BXA-DELTA-L 4.0,SMLFA':;

SECTION_NUMBER 1
 '@S9S_MB_2U_LIB.S9S_MB_2U(SCH_1):PAGE287_I8@PURE_QUANTA.PICOPROBE_BXA(CHIPS)':
 C_PATH='@s9s_mb_2u_lib.s9s_mb_2u(sch_1):page287_i8@pure_quanta.picoprobe_bxa(ch~
ips)',
 P_PATH='@s9s_mb_2u_lib.s9s_mb_2u(sch_1):page308_i8@pure_quanta.picoprobe_bxa(ch~
ips)',
 PATH='I8',
 DRAWING='@S9S_MB_2U_LIB.S9S_MB_2U(SCH_1):PAGE287',
 PHYS_PAGE='308',
 XY='(-2400,1050)',
 ROT='0',
 VER='1',
 LOCATION='J68',
 CDS_LIB='pure_quanta',
 CDS_PART_NAME='PICOPROBE_BXA-DELTA-L 4.0,SMLFA',
 PART_TYPE='SMLF',
 MATERIAL='EMPTY',
 VALUE='DELTA-L 4.0',
 PRIM_FILE='./archive_libs/logical/picoprobe_bxa/chips/chips.prt';

PART_NAME
 J69 'PICOPROBE_BXA-DELTA-L 4.0,SMLFA':;

SECTION_NUMBER 1
 '@S9S_MB_2U_LIB.S9S_MB_2U(SCH_1):PAGE287_I24@PURE_QUANTA.PICOPROBE_BXA(CHIPS)':
 C_PATH='@s9s_mb_2u_lib.s9s_mb_2u(sch_1):page287_i24@pure_quanta.picoprobe_bxa(c~
hips)',
 P_PATH='@s9s_mb_2u_lib.s9s_mb_2u(sch_1):page308_i24@pure_quanta.picoprobe_bxa(c~
hips)',
 PATH='I24',
 DRAWING='@S9S_MB_2U_LIB.S9S_MB_2U(SCH_1):PAGE287',
 PHYS_PAGE='308',
 XY='(-325,4575)',
 ROT='4',
 VER='1',
 LOCATION='J69',
 CDS_LIB='pure_quanta',
 CDS_PART_NAME='PICOPROBE_BXA-DELTA-L 4.0,SMLFA',
 PART_TYPE='SMLF',
 MATERIAL='EMPTY',
 VALUE='DELTA-L 4.0',
 PRIM_FILE='./archive_libs/logical/picoprobe_bxa/chips/chips.prt';

PART_NAME
 J70 'PICOPROBE_BXA-DELTA-L 4.0,SMLFA':;

SECTION_NUMBER 1
 '@S9S_MB_2U_LIB.S9S_MB_2U(SCH_1):PAGE287_I23@PURE_QUANTA.PICOPROBE_BXA(CHIPS)':
 C_PATH='@s9s_mb_2u_lib.s9s_mb_2u(sch_1):page287_i23@pure_quanta.picoprobe_bxa(c~
hips)',
 P_PATH='@s9s_mb_2u_lib.s9s_mb_2u(sch_1):page308_i23@pure_quanta.picoprobe_bxa(c~
hips)',
 PATH='I23',
 DRAWING='@S9S_MB_2U_LIB.S9S_MB_2U(SCH_1):PAGE287',
 PHYS_PAGE='308',
 XY='(-350,4000)',
 ROT='4',
 VER='1',
 LOCATION='J70',
 CDS_LIB='pure_quanta',
 CDS_PART_NAME='PICOPROBE_BXA-DELTA-L 4.0,SMLFA',
 PART_TYPE='SMLF',
 MATERIAL='EMPTY',
 VALUE='DELTA-L 4.0',
 PRIM_FILE='./archive_libs/logical/picoprobe_bxa/chips/chips.prt';

PART_NAME
 J71 'PICOPROBE_BXA-DELTA-L 4.0,SMLFA':;

SECTION_NUMBER 1
 '@S9S_MB_2U_LIB.S9S_MB_2U(SCH_1):PAGE287_I22@PURE_QUANTA.PICOPROBE_BXA(CHIPS)':
 C_PATH='@s9s_mb_2u_lib.s9s_mb_2u(sch_1):page287_i22@pure_quanta.picoprobe_bxa(c~
hips)',
 P_PATH='@s9s_mb_2u_lib.s9s_mb_2u(sch_1):page308_i22@pure_quanta.picoprobe_bxa(c~
hips)',
 PATH='I22',
 DRAWING='@S9S_MB_2U_LIB.S9S_MB_2U(SCH_1):PAGE287',
 PHYS_PAGE='308',
 XY='(-350,3100)',
 ROT='4',
 VER='1',
 LOCATION='J71',
 CDS_LIB='pure_quanta',
 CDS_PART_NAME='PICOPROBE_BXA-DELTA-L 4.0,SMLFA',
 PART_TYPE='SMLF',
 MATERIAL='EMPTY',
 VALUE='DELTA-L 4.0',
 PRIM_FILE='./archive_libs/logical/picoprobe_bxa/chips/chips.prt';

PART_NAME
 J72 'PICOPROBE_BXA-DELTA-L 4.0,SMLFA':;

SECTION_NUMBER 1
 '@S9S_MB_2U_LIB.S9S_MB_2U(SCH_1):PAGE287_I21@PURE_QUANTA.PICOPROBE_BXA(CHIPS)':
 C_PATH='@s9s_mb_2u_lib.s9s_mb_2u(sch_1):page287_i21@pure_quanta.picoprobe_bxa(c~
hips)',
 P_PATH='@s9s_mb_2u_lib.s9s_mb_2u(sch_1):page308_i21@pure_quanta.picoprobe_bxa(c~
hips)',
 PATH='I21',
 DRAWING='@S9S_MB_2U_LIB.S9S_MB_2U(SCH_1):PAGE287',
 PHYS_PAGE='308',
 XY='(-350,2525)',
 ROT='4',
 VER='1',
 LOCATION='J72',
 CDS_LIB='pure_quanta',
 CDS_PART_NAME='PICOPROBE_BXA-DELTA-L 4.0,SMLFA',
 PART_TYPE='SMLF',
 MATERIAL='EMPTY',
 VALUE='DELTA-L 4.0',
 PRIM_FILE='./archive_libs/logical/picoprobe_bxa/chips/chips.prt';

PART_NAME
 J73 'PICOPROBE_BXA-DELTA-L 4.0,SMLFA':;

SECTION_NUMBER 1
 '@S9S_MB_2U_LIB.S9S_MB_2U(SCH_1):PAGE287_I20@PURE_QUANTA.PICOPROBE_BXA(CHIPS)':
 C_PATH='@s9s_mb_2u_lib.s9s_mb_2u(sch_1):page287_i20@pure_quanta.picoprobe_bxa(c~
hips)',
 P_PATH='@s9s_mb_2u_lib.s9s_mb_2u(sch_1):page308_i20@pure_quanta.picoprobe_bxa(c~
hips)',
 PATH='I20',
 DRAWING='@S9S_MB_2U_LIB.S9S_MB_2U(SCH_1):PAGE287',
 PHYS_PAGE='308',
 XY='(-350,1675)',
 ROT='4',
 VER='1',
 LOCATION='J73',
 CDS_LIB='pure_quanta',
 CDS_PART_NAME='PICOPROBE_BXA-DELTA-L 4.0,SMLFA',
 PART_TYPE='SMLF',
 MATERIAL='EMPTY',
 VALUE='DELTA-L 4.0',
 PRIM_FILE='./archive_libs/logical/picoprobe_bxa/chips/chips.prt';

PART_NAME
 J74 'PICOPROBE_BXA-DELTA-L 4.0,SMLFA':;

SECTION_NUMBER 1
 '@S9S_MB_2U_LIB.S9S_MB_2U(SCH_1):PAGE287_I19@PURE_QUANTA.PICOPROBE_BXA(CHIPS)':
 C_PATH='@s9s_mb_2u_lib.s9s_mb_2u(sch_1):page287_i19@pure_quanta.picoprobe_bxa(c~
hips)',
 P_PATH='@s9s_mb_2u_lib.s9s_mb_2u(sch_1):page308_i19@pure_quanta.picoprobe_bxa(c~
hips)',
 PATH='I19',
 DRAWING='@S9S_MB_2U_LIB.S9S_MB_2U(SCH_1):PAGE287',
 PHYS_PAGE='308',
 XY='(-350,1100)',
 ROT='4',
 VER='1',
 LOCATION='J74',
 CDS_LIB='pure_quanta',
 CDS_PART_NAME='PICOPROBE_BXA-DELTA-L 4.0,SMLFA',
 PART_TYPE='SMLF',
 MATERIAL='EMPTY',
 VALUE='DELTA-L 4.0',
 PRIM_FILE='./archive_libs/logical/picoprobe_bxa/chips/chips.prt';

PART_NAME
 J75 'PICOPROBE_BXA-DELTA-L 4.0,SMLFA':;

SECTION_NUMBER 1
 '@S9S_MB_2U_LIB.S9S_MB_2U(SCH_1):PAGE287_I52@PURE_QUANTA.PICOPROBE_BXA(CHIPS)':
 C_PATH='@s9s_mb_2u_lib.s9s_mb_2u(sch_1):page287_i52@pure_quanta.picoprobe_bxa(c~
hips)',
 P_PATH='@s9s_mb_2u_lib.s9s_mb_2u(sch_1):page308_i52@pure_quanta.picoprobe_bxa(c~
hips)',
 PATH='I52',
 DRAWING='@S9S_MB_2U_LIB.S9S_MB_2U(SCH_1):PAGE287',
 PHYS_PAGE='308',
 XY='(1775,4525)',
 ROT='0',
 VER='1',
 LOCATION='J75',
 CDS_LIB='pure_quanta',
 CDS_PART_NAME='PICOPROBE_BXA-DELTA-L 4.0,SMLFA',
 PART_TYPE='SMLF',
 MATERIAL='EMPTY',
 VALUE='DELTA-L 4.0',
 PRIM_FILE='./archive_libs/logical/picoprobe_bxa/chips/chips.prt';

PART_NAME
 J76 'PICOPROBE_BXA-DELTA-L 4.0,SMLFA':;

SECTION_NUMBER 1
 '@S9S_MB_2U_LIB.S9S_MB_2U(SCH_1):PAGE287_I51@PURE_QUANTA.PICOPROBE_BXA(CHIPS)':
 C_PATH='@s9s_mb_2u_lib.s9s_mb_2u(sch_1):page287_i51@pure_quanta.picoprobe_bxa(c~
hips)',
 P_PATH='@s9s_mb_2u_lib.s9s_mb_2u(sch_1):page308_i51@pure_quanta.picoprobe_bxa(c~
hips)',
 PATH='I51',
 DRAWING='@S9S_MB_2U_LIB.S9S_MB_2U(SCH_1):PAGE287',
 PHYS_PAGE='308',
 XY='(1775,3950)',
 ROT='0',
 VER='1',
 LOCATION='J76',
 CDS_LIB='pure_quanta',
 CDS_PART_NAME='PICOPROBE_BXA-DELTA-L 4.0,SMLFA',
 PART_TYPE='SMLF',
 MATERIAL='EMPTY',
 VALUE='DELTA-L 4.0',
 PRIM_FILE='./archive_libs/logical/picoprobe_bxa/chips/chips.prt';

PART_NAME
 J77 'PICOPROBE_BXA-DELTA-L 4.0,SMLFA':;

SECTION_NUMBER 1
 '@S9S_MB_2U_LIB.S9S_MB_2U(SCH_1):PAGE287_I48@PURE_QUANTA.PICOPROBE_BXA(CHIPS)':
 C_PATH='@s9s_mb_2u_lib.s9s_mb_2u(sch_1):page287_i48@pure_quanta.picoprobe_bxa(c~
hips)',
 P_PATH='@s9s_mb_2u_lib.s9s_mb_2u(sch_1):page308_i48@pure_quanta.picoprobe_bxa(c~
hips)',
 PATH='I48',
 DRAWING='@S9S_MB_2U_LIB.S9S_MB_2U(SCH_1):PAGE287',
 PHYS_PAGE='308',
 XY='(1775,3050)',
 ROT='0',
 VER='1',
 LOCATION='J77',
 CDS_LIB='pure_quanta',
 CDS_PART_NAME='PICOPROBE_BXA-DELTA-L 4.0,SMLFA',
 PART_TYPE='SMLF',
 MATERIAL='EMPTY',
 VALUE='DELTA-L 4.0',
 PRIM_FILE='./archive_libs/logical/picoprobe_bxa/chips/chips.prt';

PART_NAME
 J78 'PICOPROBE_BXA-DELTA-L 4.0,SMLFA':;

SECTION_NUMBER 1
 '@S9S_MB_2U_LIB.S9S_MB_2U(SCH_1):PAGE287_I43@PURE_QUANTA.PICOPROBE_BXA(CHIPS)':
 C_PATH='@s9s_mb_2u_lib.s9s_mb_2u(sch_1):page287_i43@pure_quanta.picoprobe_bxa(c~
hips)',
 P_PATH='@s9s_mb_2u_lib.s9s_mb_2u(sch_1):page308_i43@pure_quanta.picoprobe_bxa(c~
hips)',
 PATH='I43',
 DRAWING='@S9S_MB_2U_LIB.S9S_MB_2U(SCH_1):PAGE287',
 PHYS_PAGE='308',
 XY='(1775,2475)',
 ROT='0',
 VER='1',
 LOCATION='J78',
 CDS_LIB='pure_quanta',
 CDS_PART_NAME='PICOPROBE_BXA-DELTA-L 4.0,SMLFA',
 PART_TYPE='SMLF',
 MATERIAL='EMPTY',
 VALUE='DELTA-L 4.0',
 PRIM_FILE='./archive_libs/logical/picoprobe_bxa/chips/chips.prt';

PART_NAME
 J79 'PICOPROBE_BXA-DELTA-L 4.0,SMLFA':;

SECTION_NUMBER 1
 '@S9S_MB_2U_LIB.S9S_MB_2U(SCH_1):PAGE287_I42@PURE_QUANTA.PICOPROBE_BXA(CHIPS)':
 C_PATH='@s9s_mb_2u_lib.s9s_mb_2u(sch_1):page287_i42@pure_quanta.picoprobe_bxa(c~
hips)',
 P_PATH='@s9s_mb_2u_lib.s9s_mb_2u(sch_1):page308_i42@pure_quanta.picoprobe_bxa(c~
hips)',
 PATH='I42',
 DRAWING='@S9S_MB_2U_LIB.S9S_MB_2U(SCH_1):PAGE287',
 PHYS_PAGE='308',
 XY='(1775,1625)',
 ROT='0',
 VER='1',
 LOCATION='J79',
 CDS_LIB='pure_quanta',
 CDS_PART_NAME='PICOPROBE_BXA-DELTA-L 4.0,SMLFA',
 PART_TYPE='SMLF',
 MATERIAL='EMPTY',
 VALUE='DELTA-L 4.0',
 PRIM_FILE='./archive_libs/logical/picoprobe_bxa/chips/chips.prt';

PART_NAME
 J80 'PICOPROBE_BXA-DELTA-L 4.0,SMLFA':;

SECTION_NUMBER 1
 '@S9S_MB_2U_LIB.S9S_MB_2U(SCH_1):PAGE287_I39@PURE_QUANTA.PICOPROBE_BXA(CHIPS)':
 C_PATH='@s9s_mb_2u_lib.s9s_mb_2u(sch_1):page287_i39@pure_quanta.picoprobe_bxa(c~
hips)',
 P_PATH='@s9s_mb_2u_lib.s9s_mb_2u(sch_1):page308_i39@pure_quanta.picoprobe_bxa(c~
hips)',
 PATH='I39',
 DRAWING='@S9S_MB_2U_LIB.S9S_MB_2U(SCH_1):PAGE287',
 PHYS_PAGE='308',
 XY='(1775,1050)',
 ROT='0',
 VER='1',
 LOCATION='J80',
 CDS_LIB='pure_quanta',
 CDS_PART_NAME='PICOPROBE_BXA-DELTA-L 4.0,SMLFA',
 PART_TYPE='SMLF',
 MATERIAL='EMPTY',
 VALUE='DELTA-L 4.0',
 PRIM_FILE='./archive_libs/logical/picoprobe_bxa/chips/chips.prt';

PART_NAME
 J81 'PICOPROBE_BXA-DELTA-L 4.0,SMLFA':;

SECTION_NUMBER 1
 '@S9S_MB_2U_LIB.S9S_MB_2U(SCH_1):PAGE287_I58@PURE_QUANTA.PICOPROBE_BXA(CHIPS)':
 C_PATH='@s9s_mb_2u_lib.s9s_mb_2u(sch_1):page287_i58@pure_quanta.picoprobe_bxa(c~
hips)',
 P_PATH='@s9s_mb_2u_lib.s9s_mb_2u(sch_1):page308_i58@pure_quanta.picoprobe_bxa(c~
hips)',
 PATH='I58',
 DRAWING='@S9S_MB_2U_LIB.S9S_MB_2U(SCH_1):PAGE287',
 PHYS_PAGE='308',
 XY='(3825,4575)',
 ROT='4',
 VER='1',
 LOCATION='J81',
 CDS_LIB='pure_quanta',
 CDS_PART_NAME='PICOPROBE_BXA-DELTA-L 4.0,SMLFA',
 PART_TYPE='SMLF',
 MATERIAL='EMPTY',
 VALUE='DELTA-L 4.0',
 PRIM_FILE='./archive_libs/logical/picoprobe_bxa/chips/chips.prt';

PART_NAME
 J82 'PICOPROBE_BXA-DELTA-L 4.0,SMLFA':;

SECTION_NUMBER 1
 '@S9S_MB_2U_LIB.S9S_MB_2U(SCH_1):PAGE287_I57@PURE_QUANTA.PICOPROBE_BXA(CHIPS)':
 C_PATH='@s9s_mb_2u_lib.s9s_mb_2u(sch_1):page287_i57@pure_quanta.picoprobe_bxa(c~
hips)',
 P_PATH='@s9s_mb_2u_lib.s9s_mb_2u(sch_1):page308_i57@pure_quanta.picoprobe_bxa(c~
hips)',
 PATH='I57',
 DRAWING='@S9S_MB_2U_LIB.S9S_MB_2U(SCH_1):PAGE287',
 PHYS_PAGE='308',
 XY='(3825,4000)',
 ROT='4',
 VER='1',
 LOCATION='J82',
 CDS_LIB='pure_quanta',
 CDS_PART_NAME='PICOPROBE_BXA-DELTA-L 4.0,SMLFA',
 PART_TYPE='SMLF',
 MATERIAL='EMPTY',
 VALUE='DELTA-L 4.0',
 PRIM_FILE='./archive_libs/logical/picoprobe_bxa/chips/chips.prt';

PART_NAME
 J83 'PICOPROBE_BXA-DELTA-L 4.0,SMLFA':;

SECTION_NUMBER 1
 '@S9S_MB_2U_LIB.S9S_MB_2U(SCH_1):PAGE287_I56@PURE_QUANTA.PICOPROBE_BXA(CHIPS)':
 C_PATH='@s9s_mb_2u_lib.s9s_mb_2u(sch_1):page287_i56@pure_quanta.picoprobe_bxa(c~
hips)',
 P_PATH='@s9s_mb_2u_lib.s9s_mb_2u(sch_1):page308_i56@pure_quanta.picoprobe_bxa(c~
hips)',
 PATH='I56',
 DRAWING='@S9S_MB_2U_LIB.S9S_MB_2U(SCH_1):PAGE287',
 PHYS_PAGE='308',
 XY='(3825,3100)',
 ROT='4',
 VER='1',
 LOCATION='J83',
 CDS_LIB='pure_quanta',
 CDS_PART_NAME='PICOPROBE_BXA-DELTA-L 4.0,SMLFA',
 PART_TYPE='SMLF',
 MATERIAL='EMPTY',
 VALUE='DELTA-L 4.0',
 PRIM_FILE='./archive_libs/logical/picoprobe_bxa/chips/chips.prt';

PART_NAME
 J84 'PICOPROBE_BXA-DELTA-L 4.0,SMLFA':;

SECTION_NUMBER 1
 '@S9S_MB_2U_LIB.S9S_MB_2U(SCH_1):PAGE287_I55@PURE_QUANTA.PICOPROBE_BXA(CHIPS)':
 C_PATH='@s9s_mb_2u_lib.s9s_mb_2u(sch_1):page287_i55@pure_quanta.picoprobe_bxa(c~
hips)',
 P_PATH='@s9s_mb_2u_lib.s9s_mb_2u(sch_1):page308_i55@pure_quanta.picoprobe_bxa(c~
hips)',
 PATH='I55',
 DRAWING='@S9S_MB_2U_LIB.S9S_MB_2U(SCH_1):PAGE287',
 PHYS_PAGE='308',
 XY='(3825,2525)',
 ROT='4',
 VER='1',
 LOCATION='J84',
 CDS_LIB='pure_quanta',
 CDS_PART_NAME='PICOPROBE_BXA-DELTA-L 4.0,SMLFA',
 PART_TYPE='SMLF',
 MATERIAL='EMPTY',
 VALUE='DELTA-L 4.0',
 PRIM_FILE='./archive_libs/logical/picoprobe_bxa/chips/chips.prt';

PART_NAME
 J85 'PICOPROBE_BXA-DELTA-L 4.0,SMLFA':;

SECTION_NUMBER 1
 '@S9S_MB_2U_LIB.S9S_MB_2U(SCH_1):PAGE287_I54@PURE_QUANTA.PICOPROBE_BXA(CHIPS)':
 C_PATH='@s9s_mb_2u_lib.s9s_mb_2u(sch_1):page287_i54@pure_quanta.picoprobe_bxa(c~
hips)',
 P_PATH='@s9s_mb_2u_lib.s9s_mb_2u(sch_1):page308_i54@pure_quanta.picoprobe_bxa(c~
hips)',
 PATH='I54',
 DRAWING='@S9S_MB_2U_LIB.S9S_MB_2U(SCH_1):PAGE287',
 PHYS_PAGE='308',
 XY='(3825,1675)',
 ROT='4',
 VER='1',
 LOCATION='J85',
 CDS_LIB='pure_quanta',
 CDS_PART_NAME='PICOPROBE_BXA-DELTA-L 4.0,SMLFA',
 PART_TYPE='SMLF',
 MATERIAL='EMPTY',
 VALUE='DELTA-L 4.0',
 PRIM_FILE='./archive_libs/logical/picoprobe_bxa/chips/chips.prt';

PART_NAME
 J86 'PICOPROBE_BXA-DELTA-L 4.0,SMLFA':;

SECTION_NUMBER 1
 '@S9S_MB_2U_LIB.S9S_MB_2U(SCH_1):PAGE287_I53@PURE_QUANTA.PICOPROBE_BXA(CHIPS)':
 C_PATH='@s9s_mb_2u_lib.s9s_mb_2u(sch_1):page287_i53@pure_quanta.picoprobe_bxa(c~
hips)',
 P_PATH='@s9s_mb_2u_lib.s9s_mb_2u(sch_1):page308_i53@pure_quanta.picoprobe_bxa(c~
hips)',
 PATH='I53',
 DRAWING='@S9S_MB_2U_LIB.S9S_MB_2U(SCH_1):PAGE287',
 PHYS_PAGE='308',
 XY='(3825,1100)',
 ROT='4',
 VER='1',
 LOCATION='J86',
 CDS_LIB='pure_quanta',
 CDS_PART_NAME='PICOPROBE_BXA-DELTA-L 4.0,SMLFA',
 PART_TYPE='SMLF',
 MATERIAL='EMPTY',
 VALUE='DELTA-L 4.0',
 PRIM_FILE='./archive_libs/logical/picoprobe_bxa/chips/chips.prt';

PART_NAME
 J90 'SCONN56_123276793-SCONN56_1-23A':;

SECTION_NUMBER 1
 '@S9S_MB_2U_LIB.S9S_MB_2U(SCH_1):PAGE297_I318@PURE_QUANTA.SCONN56_123276793(CHIPS)':
 C_PATH='@s9s_mb_2u_lib.s9s_mb_2u(sch_1):page297_i318@pure_quanta.sconn56_123276~
793(chips)',
 P_PATH='@s9s_mb_2u_lib.s9s_mb_2u(sch_1):page191_i318@pure_quanta.sconn56_123276~
793(chips)',
 PATH='I318',
 DRAWING='@S9S_MB_2U_LIB.S9S_MB_2U(SCH_1):PAGE297',
 PHYS_PAGE='191',
 XY='(500,3875)',
 ROT='0',
 VER='1',
 LOCATION='J90',
 CDS_LIB='pure_quanta',
 CDS_PART_NAME='SCONN56_123276793-SCONN56_1-23A',
 PART_TYPE='SMLF',
 MATERIAL='IO',
 VALUE='SCONN56_1-2327679-3',
 PRIM_FILE='./archive_libs/logical/sconn56_123276793/chips/chips.prt';

PART_NAME
 J90_CON 'TP_TP_BOM ONLY-NA,TP12_BOM':;

SECTION_NUMBER 1
 '@S9S_MB_2U_LIB.S9S_MB_2U(SCH_1):PAGE290_I69@PURE_QUANTA.TP(CHIPS)':
 C_PATH='@s9s_mb_2u_lib.s9s_mb_2u(sch_1):page290_i69@pure_quanta.tp(chips)',
 P_PATH='@s9s_mb_2u_lib.s9s_mb_2u(sch_1):page312_i69@pure_quanta.tp(chips)',
 PATH='I69',
 DRAWING='@S9S_MB_2U_LIB.S9S_MB_2U(SCH_1):PAGE290',
 QPN='DFHS56FR016',
 PHYS_PAGE='312',
 XY='(-1900,-475)',
 ROT='0',
 VER='1',
 PACK_TYPE='TP_BOM ONLY',
 LOCATION='J90_CON',
 CDS_LIB='pure_quanta',
 CDS_PART_NAME='TP_TP_BOM ONLY-NA,TP12_BOM',
 MATERIAL='NA',
 PRIM_FILE='./archive_libs/logical/tp/chips/chips.prt';

PART_NAME
 J100 'SCONN20_513860200CV01-SCONN20_A':;

SECTION_NUMBER 1
 '@S9S_MB_2U_LIB.S9S_MB_2U(SCH_1):PAGE215_I32@PURE_QUANTA.SCONN20_513860200CV01(CHIPS)':
 C_PATH='@s9s_mb_2u_lib.s9s_mb_2u(sch_1):page215_i32@pure_quanta.sconn20_5138602~
00cv01(chips)',
 P_PATH='@s9s_mb_2u_lib.s9s_mb_2u(sch_1):page228_i32@pure_quanta.sconn20_5138602~
00cv01(chips)',
 PATH='I32',
 DRAWING='@S9S_MB_2U_LIB.S9S_MB_2U(SCH_1):PAGE215',
 PHYS_PAGE='228',
 XY='(-1525,3275)',
 ROT='0',
 VER='1',
 LOCATION='J100',
 CDS_LIB='pure_quanta',
 CDS_PART_NAME='SCONN20_513860200CV01-SCONN20_A',
 PART_TYPE='SMLF',
 MATERIAL='IO',
 VALUE='SCONN20_51386-0200C-V01',
 PRIM_FILE='./archive_libs/logical/sconn20_513860200cv01/chips/chips.prt';

PART_NAME
 J104 'CONN14_210HP207GBR1-CONN14_210A':;

SECTION_NUMBER 1
 '@S9S_MB_2U_LIB.S9S_MB_2U(SCH_1):PAGE189_I134@PURE_QUANTA.CONN14_210HP207GBR1(CHIPS)':
 C_PATH='@s9s_mb_2u_lib.s9s_mb_2u(sch_1):page189_i134@pure_quanta.conn14_210hp20~
7gbr1(chips)',
 P_PATH='@s9s_mb_2u_lib.s9s_mb_2u(sch_1):page201_i134@pure_quanta.conn14_210hp20~
7gbr1(chips)',
 PATH='I134',
 DRAWING='@S9S_MB_2U_LIB.S9S_MB_2U(SCH_1):PAGE189',
 PHYS_PAGE='201',
 XY='(1375,3550)',
 ROT='0',
 VER='1',
 LOCATION='J104',
 CDS_LIB='pure_quanta',
 CDS_PART_NAME='CONN14_210HP207GBR1-CONN14_210A',
 PART_TYPE='THLF',
 MATERIAL='IO',
 VALUE='CONN14_210-HP2-07GBR1',
 PRIM_FILE='./archive_libs/logical/conn14_210hp207gbr1/chips/chips.prt';

PART_NAME
 J105 'CONN112_10137002101LF-CONN112_A':;

SECTION_NUMBER 1
 '@S9S_MB_2U_LIB.S9S_MB_2U(SCH_1):PAGE142_I68@PURE_QUANTA.CONN112_10137002101LF(CHIPS)':
 C_PATH='@s9s_mb_2u_lib.s9s_mb_2u(sch_1):page142_i68@pure_quanta.conn112_1013700~
2101lf(chips)',
 P_PATH='@s9s_mb_2u_lib.s9s_mb_2u(sch_1):page136_i68@pure_quanta.conn112_1013700~
2101lf(chips)',
 PATH='I68',
 DRAWING='@S9S_MB_2U_LIB.S9S_MB_2U(SCH_1):PAGE142',
 PHYS_PAGE='136',
 XY='(950,2150)',
 ROT='0',
 VER='1',
 LOCATION='J105',
 CDS_LIB='pure_quanta',
 CDS_PART_NAME='CONN112_10137002101LF-CONN112_A',
 PART_TYPE='THLF',
 MATERIAL='IO',
 VALUE='CONN112_10137002-101LF',
 PRIM_FILE='./archive_libs/logical/conn112_10137002101lf/chips/chips.prt';

SECTION_NUMBER 2
 '@S9S_MB_2U_LIB.S9S_MB_2U(SCH_1):PAGE142_I65@PURE_QUANTA.CONN112_10137002101LF(CHIPS)':
 C_PATH='@s9s_mb_2u_lib.s9s_mb_2u(sch_1):page142_i65@pure_quanta.conn112_1013700~
2101lf(chips)',
 P_PATH='@s9s_mb_2u_lib.s9s_mb_2u(sch_1):page136_i65@pure_quanta.conn112_1013700~
2101lf(chips)',
 PATH='I65',
 DRAWING='@S9S_MB_2U_LIB.S9S_MB_2U(SCH_1):PAGE142',
 PHYS_PAGE='136',
 XY='(5875,2150)',
 ROT='0',
 VER='2',
 LOCATION='J105',
 CDS_LIB='pure_quanta',
 CDS_PART_NAME='CONN112_10137002101LF-CONN112_A',
 PART_TYPE='THLF',
 MATERIAL='IO',
 VALUE='CONN112_10137002-101LF',
 PRIM_FILE='./archive_libs/logical/conn112_10137002101lf/chips/chips.prt';

PART_NAME
 J106 'CONN112_10137002101LF-CONN112_A':;

SECTION_NUMBER 1
 '@S9S_MB_2U_LIB.S9S_MB_2U(SCH_1):PAGE144_I68@PURE_QUANTA.CONN112_10137002101LF(CHIPS)':
 C_PATH='@s9s_mb_2u_lib.s9s_mb_2u(sch_1):page144_i68@pure_quanta.conn112_1013700~
2101lf(chips)',
 P_PATH='@s9s_mb_2u_lib.s9s_mb_2u(sch_1):page137_i68@pure_quanta.conn112_1013700~
2101lf(chips)',
 PATH='I68',
 DRAWING='@S9S_MB_2U_LIB.S9S_MB_2U(SCH_1):PAGE144',
 PHYS_PAGE='137',
 XY='(0,4125)',
 ROT='0',
 VER='1',
 LOCATION='J106',
 CDS_LIB='pure_quanta',
 CDS_PART_NAME='CONN112_10137002101LF-CONN112_A',
 PART_TYPE='THLF',
 MATERIAL='IO',
 VALUE='CONN112_10137002-101LF',
 PRIM_FILE='./archive_libs/logical/conn112_10137002101lf/chips/chips.prt';

SECTION_NUMBER 2
 '@S9S_MB_2U_LIB.S9S_MB_2U(SCH_1):PAGE144_I65@PURE_QUANTA.CONN112_10137002101LF(CHIPS)':
 C_PATH='@s9s_mb_2u_lib.s9s_mb_2u(sch_1):page144_i65@pure_quanta.conn112_1013700~
2101lf(chips)',
 P_PATH='@s9s_mb_2u_lib.s9s_mb_2u(sch_1):page137_i65@pure_quanta.conn112_1013700~
2101lf(chips)',
 PATH='I65',
 DRAWING='@S9S_MB_2U_LIB.S9S_MB_2U(SCH_1):PAGE144',
 PHYS_PAGE='137',
 XY='(4625,4050)',
 ROT='0',
 VER='2',
 LOCATION='J106',
 CDS_LIB='pure_quanta',
 CDS_PART_NAME='CONN112_10137002101LF-CONN112_A',
 PART_TYPE='THLF',
 MATERIAL='IO',
 VALUE='CONN112_10137002-101LF',
 PRIM_FILE='./archive_libs/logical/conn112_10137002101lf/chips/chips.prt';

PART_NAME
 J107 'CONN112_10137002101LF-CONN112_A':;

SECTION_NUMBER 1
 '@S9S_MB_2U_LIB.S9S_MB_2U(SCH_1):PAGE317_I38@PURE_QUANTA.CONN112_10137002101LF(CHIPS)':
 C_PATH='@s9s_mb_2u_lib.s9s_mb_2u(sch_1):page317_i38@pure_quanta.conn112_1013700~
2101lf(chips)',
 P_PATH='@s9s_mb_2u_lib.s9s_mb_2u(sch_1):page138_i38@pure_quanta.conn112_1013700~
2101lf(chips)',
 PATH='I38',
 DRAWING='@S9S_MB_2U_LIB.S9S_MB_2U(SCH_1):PAGE317',
 PHYS_PAGE='138',
 XY='(-1175,425)',
 ROT='0',
 VER='1',
 LOCATION='J107',
 CDS_LIB='pure_quanta',
 CDS_PART_NAME='CONN112_10137002101LF-CONN112_A',
 PART_TYPE='THLF',
 MATERIAL='IO',
 VALUE='CONN112_10137002-101LF',
 PRIM_FILE='./archive_libs/logical/conn112_10137002101lf/chips/chips.prt';

SECTION_NUMBER 2
 '@S9S_MB_2U_LIB.S9S_MB_2U(SCH_1):PAGE317_I58@PURE_QUANTA.CONN112_10137002101LF(CHIPS)':
 C_PATH='@s9s_mb_2u_lib.s9s_mb_2u(sch_1):page317_i58@pure_quanta.conn112_1013700~
2101lf(chips)',
 P_PATH='@s9s_mb_2u_lib.s9s_mb_2u(sch_1):page138_i58@pure_quanta.conn112_1013700~
2101lf(chips)',
 PATH='I58',
 DRAWING='@S9S_MB_2U_LIB.S9S_MB_2U(SCH_1):PAGE317',
 PHYS_PAGE='138',
 XY='(3325,425)',
 ROT='0',
 VER='2',
 LOCATION='J107',
 CDS_LIB='pure_quanta',
 CDS_PART_NAME='CONN112_10137002101LF-CONN112_A',
 PART_TYPE='THLF',
 MATERIAL='IO',
 VALUE='CONN112_10137002-101LF',
 PRIM_FILE='./archive_libs/logical/conn112_10137002101lf/chips/chips.prt';

PART_NAME
 J108 'CONN112_10137002101LF-CONN112_A':;

SECTION_NUMBER 1
 '@S9S_MB_2U_LIB.S9S_MB_2U(SCH_1):PAGE320_I76@PURE_QUANTA.CONN112_10137002101LF(CHIPS)':
 C_PATH='@s9s_mb_2u_lib.s9s_mb_2u(sch_1):page320_i76@pure_quanta.conn112_1013700~
2101lf(chips)',
 P_PATH='@s9s_mb_2u_lib.s9s_mb_2u(sch_1):page139_i76@pure_quanta.conn112_1013700~
2101lf(chips)',
 PATH='I76',
 DRAWING='@S9S_MB_2U_LIB.S9S_MB_2U(SCH_1):PAGE320',
 PHYS_PAGE='139',
 XY='(-1050,425)',
 ROT='0',
 VER='1',
 LOCATION='J108',
 CDS_LIB='pure_quanta',
 CDS_PART_NAME='CONN112_10137002101LF-CONN112_A',
 PART_TYPE='THLF',
 MATERIAL='IO',
 VALUE='CONN112_10137002-101LF',
 PRIM_FILE='./archive_libs/logical/conn112_10137002101lf/chips/chips.prt';

SECTION_NUMBER 2
 '@S9S_MB_2U_LIB.S9S_MB_2U(SCH_1):PAGE320_I57@PURE_QUANTA.CONN112_10137002101LF(CHIPS)':
 C_PATH='@s9s_mb_2u_lib.s9s_mb_2u(sch_1):page320_i57@pure_quanta.conn112_1013700~
2101lf(chips)',
 P_PATH='@s9s_mb_2u_lib.s9s_mb_2u(sch_1):page139_i57@pure_quanta.conn112_1013700~
2101lf(chips)',
 PATH='I57',
 DRAWING='@S9S_MB_2U_LIB.S9S_MB_2U(SCH_1):PAGE320',
 PHYS_PAGE='139',
 XY='(3500,375)',
 ROT='0',
 VER='2',
 LOCATION='J108',
 CDS_LIB='pure_quanta',
 CDS_PART_NAME='CONN112_10137002101LF-CONN112_A',
 PART_TYPE='THLF',
 MATERIAL='IO',
 VALUE='CONN112_10137002-101LF',
 PRIM_FILE='./archive_libs/logical/conn112_10137002101lf/chips/chips.prt';

PART_NAME
 J109 'CONN112_10137002101LF-CONN112_A':;

SECTION_NUMBER 1
 '@S9S_MB_2U_LIB.S9S_MB_2U(SCH_1):PAGE319_I76@PURE_QUANTA.CONN112_10137002101LF(CHIPS)':
 C_PATH='@s9s_mb_2u_lib.s9s_mb_2u(sch_1):page319_i76@pure_quanta.conn112_1013700~
2101lf(chips)',
 P_PATH='@s9s_mb_2u_lib.s9s_mb_2u(sch_1):page140_i76@pure_quanta.conn112_1013700~
2101lf(chips)',
 PATH='I76',
 DRAWING='@S9S_MB_2U_LIB.S9S_MB_2U(SCH_1):PAGE319',
 PHYS_PAGE='140',
 XY='(-1175,425)',
 ROT='0',
 VER='1',
 LOCATION='J109',
 CDS_LIB='pure_quanta',
 CDS_PART_NAME='CONN112_10137002101LF-CONN112_A',
 PART_TYPE='THLF',
 MATERIAL='IO',
 VALUE='CONN112_10137002-101LF',
 PRIM_FILE='./archive_libs/logical/conn112_10137002101lf/chips/chips.prt';

SECTION_NUMBER 2
 '@S9S_MB_2U_LIB.S9S_MB_2U(SCH_1):PAGE319_I53@PURE_QUANTA.CONN112_10137002101LF(CHIPS)':
 C_PATH='@s9s_mb_2u_lib.s9s_mb_2u(sch_1):page319_i53@pure_quanta.conn112_1013700~
2101lf(chips)',
 P_PATH='@s9s_mb_2u_lib.s9s_mb_2u(sch_1):page140_i53@pure_quanta.conn112_1013700~
2101lf(chips)',
 PATH='I53',
 DRAWING='@S9S_MB_2U_LIB.S9S_MB_2U(SCH_1):PAGE319',
 PHYS_PAGE='140',
 XY='(3600,350)',
 ROT='0',
 VER='2',
 LOCATION='J109',
 CDS_LIB='pure_quanta',
 CDS_PART_NAME='CONN112_10137002101LF-CONN112_A',
 PART_TYPE='THLF',
 MATERIAL='IO',
 VALUE='CONN112_10137002-101LF',
 PRIM_FILE='./archive_libs/logical/conn112_10137002101lf/chips/chips.prt';

PART_NAME
 J110 'CONN112_10137002101LF-CONN112_A':;

SECTION_NUMBER 1
 '@S9S_MB_2U_LIB.S9S_MB_2U(SCH_1):PAGE318_I16@PURE_QUANTA.CONN112_10137002101LF(CHIPS)':
 C_PATH='@s9s_mb_2u_lib.s9s_mb_2u(sch_1):page318_i16@pure_quanta.conn112_1013700~
2101lf(chips)',
 P_PATH='@s9s_mb_2u_lib.s9s_mb_2u(sch_1):page141_i16@pure_quanta.conn112_1013700~
2101lf(chips)',
 PATH='I16',
 DRAWING='@S9S_MB_2U_LIB.S9S_MB_2U(SCH_1):PAGE318',
 PHYS_PAGE='141',
 XY='(-1100,400)',
 ROT='0',
 VER='1',
 LOCATION='J110',
 CDS_LIB='pure_quanta',
 CDS_PART_NAME='CONN112_10137002101LF-CONN112_A',
 PART_TYPE='THLF',
 MATERIAL='IO',
 VALUE='CONN112_10137002-101LF',
 PRIM_FILE='./archive_libs/logical/conn112_10137002101lf/chips/chips.prt';

SECTION_NUMBER 2
 '@S9S_MB_2U_LIB.S9S_MB_2U(SCH_1):PAGE318_I54@PURE_QUANTA.CONN112_10137002101LF(CHIPS)':
 C_PATH='@s9s_mb_2u_lib.s9s_mb_2u(sch_1):page318_i54@pure_quanta.conn112_1013700~
2101lf(chips)',
 P_PATH='@s9s_mb_2u_lib.s9s_mb_2u(sch_1):page141_i54@pure_quanta.conn112_1013700~
2101lf(chips)',
 PATH='I54',
 DRAWING='@S9S_MB_2U_LIB.S9S_MB_2U(SCH_1):PAGE318',
 PHYS_PAGE='141',
 XY='(3675,450)',
 ROT='0',
 VER='2',
 LOCATION='J110',
 CDS_LIB='pure_quanta',
 CDS_PART_NAME='CONN112_10137002101LF-CONN112_A',
 PART_TYPE='THLF',
 MATERIAL='IO',
 VALUE='CONN112_10137002-101LF',
 PRIM_FILE='./archive_libs/logical/conn112_10137002101lf/chips/chips.prt';

PART_NAME
 J111 'CONN112_10137002101LF-CONN112_A':;

SECTION_NUMBER 1
 '@S9S_MB_2U_LIB.S9S_MB_2U(SCH_1):PAGE148_I74@PURE_QUANTA.CONN112_10137002101LF(CHIPS)':
 C_PATH='@s9s_mb_2u_lib.s9s_mb_2u(sch_1):page148_i74@pure_quanta.conn112_1013700~
2101lf(chips)',
 P_PATH='@s9s_mb_2u_lib.s9s_mb_2u(sch_1):page142_i74@pure_quanta.conn112_1013700~
2101lf(chips)',
 PATH='I74',
 DRAWING='@S9S_MB_2U_LIB.S9S_MB_2U(SCH_1):PAGE148',
 PHYS_PAGE='142',
 XY='(-25,1775)',
 ROT='0',
 VER='1',
 LOCATION='J111',
 CDS_LIB='pure_quanta',
 CDS_PART_NAME='CONN112_10137002101LF-CONN112_A',
 PART_TYPE='THLF',
 MATERIAL='IO',
 VALUE='CONN112_10137002-101LF',
 PRIM_FILE='./archive_libs/logical/conn112_10137002101lf/chips/chips.prt';

SECTION_NUMBER 2
 '@S9S_MB_2U_LIB.S9S_MB_2U(SCH_1):PAGE148_I75@PURE_QUANTA.CONN112_10137002101LF(CHIPS)':
 C_PATH='@s9s_mb_2u_lib.s9s_mb_2u(sch_1):page148_i75@pure_quanta.conn112_1013700~
2101lf(chips)',
 P_PATH='@s9s_mb_2u_lib.s9s_mb_2u(sch_1):page142_i75@pure_quanta.conn112_1013700~
2101lf(chips)',
 PATH='I75',
 DRAWING='@S9S_MB_2U_LIB.S9S_MB_2U(SCH_1):PAGE148',
 PHYS_PAGE='142',
 XY='(4725,1775)',
 ROT='0',
 VER='2',
 LOCATION='J111',
 CDS_LIB='pure_quanta',
 CDS_PART_NAME='CONN112_10137002101LF-CONN112_A',
 PART_TYPE='THLF',
 MATERIAL='IO',
 VALUE='CONN112_10137002-101LF',
 PRIM_FILE='./archive_libs/logical/conn112_10137002101lf/chips/chips.prt';

PART_NAME
 J112 'CONN160_10131762101LF-CONN160_A':;

SECTION_NUMBER 1
 '@S9S_MB_2U_LIB.S9S_MB_2U(SCH_1):PAGE149_I75@PURE_QUANTA.CONN160_10131762101LF(CHIPS)':
 C_PATH='@s9s_mb_2u_lib.s9s_mb_2u(sch_1):page149_i75@pure_quanta.conn160_1013176~
2101lf(chips)',
 P_PATH='@s9s_mb_2u_lib.s9s_mb_2u(sch_1):page143_i75@pure_quanta.conn160_1013176~
2101lf(chips)',
 PATH='I75',
 DRAWING='@S9S_MB_2U_LIB.S9S_MB_2U(SCH_1):PAGE149',
 PHYS_PAGE='143',
 XY='(600,1675)',
 ROT='0',
 VER='1',
 LOCATION='J112',
 CDS_LIB='pure_quanta',
 CDS_PART_NAME='CONN160_10131762101LF-CONN160_A',
 PART_TYPE='THLF',
 MATERIAL='IO',
 VALUE='CONN160_10131762-101LF',
 PRIM_FILE='./archive_libs/logical/conn160_10131762101lf/chips/chips.prt';

SECTION_NUMBER 2
 '@S9S_MB_2U_LIB.S9S_MB_2U(SCH_1):PAGE149_I76@PURE_QUANTA.CONN160_10131762101LF(CHIPS)':
 C_PATH='@s9s_mb_2u_lib.s9s_mb_2u(sch_1):page149_i76@pure_quanta.conn160_1013176~
2101lf(chips)',
 P_PATH='@s9s_mb_2u_lib.s9s_mb_2u(sch_1):page143_i76@pure_quanta.conn160_1013176~
2101lf(chips)',
 PATH='I76',
 DRAWING='@S9S_MB_2U_LIB.S9S_MB_2U(SCH_1):PAGE149',
 PHYS_PAGE='143',
 XY='(5150,1750)',
 ROT='0',
 VER='2',
 LOCATION='J112',
 CDS_LIB='pure_quanta',
 CDS_PART_NAME='CONN160_10131762101LF-CONN160_A',
 PART_TYPE='THLF',
 MATERIAL='IO',
 VALUE='CONN160_10131762-101LF',
 PRIM_FILE='./archive_libs/logical/conn160_10131762101lf/chips/chips.prt';

PART_NAME
 J114 'PICOPROBE_BXA-DELTA-L 4.0,SMLFA':;

SECTION_NUMBER 1
 '@S9S_MB_2U_LIB.S9S_MB_2U(SCH_1):PAGE287_I4@PURE_QUANTA.PICOPROBE_BXA(CHIPS)':
 C_PATH='@s9s_mb_2u_lib.s9s_mb_2u(sch_1):page287_i4@pure_quanta.picoprobe_bxa(ch~
ips)',
 P_PATH='@s9s_mb_2u_lib.s9s_mb_2u(sch_1):page308_i4@pure_quanta.picoprobe_bxa(ch~
ips)',
 PATH='I4',
 DRAWING='@S9S_MB_2U_LIB.S9S_MB_2U(SCH_1):PAGE287',
 PHYS_PAGE='308',
 XY='(-2350,225)',
 ROT='0',
 VER='1',
 LOCATION='J114',
 CDS_LIB='pure_quanta',
 CDS_PART_NAME='PICOPROBE_BXA-DELTA-L 4.0,SMLFA',
 PART_TYPE='SMLF',
 MATERIAL='EMPTY',
 VALUE='DELTA-L 4.0',
 PRIM_FILE='./archive_libs/logical/picoprobe_bxa/chips/chips.prt';

PART_NAME
 J115 'PICOPROBE_BXA-DELTA-L 4.0,SMLFA':;

SECTION_NUMBER 1
 '@S9S_MB_2U_LIB.S9S_MB_2U(SCH_1):PAGE287_I3@PURE_QUANTA.PICOPROBE_BXA(CHIPS)':
 C_PATH='@s9s_mb_2u_lib.s9s_mb_2u(sch_1):page287_i3@pure_quanta.picoprobe_bxa(ch~
ips)',
 P_PATH='@s9s_mb_2u_lib.s9s_mb_2u(sch_1):page308_i3@pure_quanta.picoprobe_bxa(ch~
ips)',
 PATH='I3',
 DRAWING='@S9S_MB_2U_LIB.S9S_MB_2U(SCH_1):PAGE287',
 PHYS_PAGE='308',
 XY='(-2350,-350)',
 ROT='0',
 VER='1',
 LOCATION='J115',
 CDS_LIB='pure_quanta',
 CDS_PART_NAME='PICOPROBE_BXA-DELTA-L 4.0,SMLFA',
 PART_TYPE='SMLF',
 MATERIAL='EMPTY',
 VALUE='DELTA-L 4.0',
 PRIM_FILE='./archive_libs/logical/picoprobe_bxa/chips/chips.prt';

PART_NAME
 J116 'PICOPROBE_BXA-DELTA-L 4.0,SMLFA':;

SECTION_NUMBER 1
 '@S9S_MB_2U_LIB.S9S_MB_2U(SCH_1):PAGE287_I6@PURE_QUANTA.PICOPROBE_BXA(CHIPS)':
 C_PATH='@s9s_mb_2u_lib.s9s_mb_2u(sch_1):page287_i6@pure_quanta.picoprobe_bxa(ch~
ips)',
 P_PATH='@s9s_mb_2u_lib.s9s_mb_2u(sch_1):page308_i6@pure_quanta.picoprobe_bxa(ch~
ips)',
 PATH='I6',
 DRAWING='@S9S_MB_2U_LIB.S9S_MB_2U(SCH_1):PAGE287',
 PHYS_PAGE='308',
 XY='(-300,275)',
 ROT='4',
 VER='1',
 LOCATION='J116',
 CDS_LIB='pure_quanta',
 CDS_PART_NAME='PICOPROBE_BXA-DELTA-L 4.0,SMLFA',
 PART_TYPE='SMLF',
 MATERIAL='EMPTY',
 VALUE='DELTA-L 4.0',
 PRIM_FILE='./archive_libs/logical/picoprobe_bxa/chips/chips.prt';

PART_NAME
 J117 'PICOPROBE_BXA-DELTA-L 4.0,SMLFA':;

SECTION_NUMBER 1
 '@S9S_MB_2U_LIB.S9S_MB_2U(SCH_1):PAGE287_I5@PURE_QUANTA.PICOPROBE_BXA(CHIPS)':
 C_PATH='@s9s_mb_2u_lib.s9s_mb_2u(sch_1):page287_i5@pure_quanta.picoprobe_bxa(ch~
ips)',
 P_PATH='@s9s_mb_2u_lib.s9s_mb_2u(sch_1):page308_i5@pure_quanta.picoprobe_bxa(ch~
ips)',
 PATH='I5',
 DRAWING='@S9S_MB_2U_LIB.S9S_MB_2U(SCH_1):PAGE287',
 PHYS_PAGE='308',
 XY='(-300,-300)',
 ROT='4',
 VER='1',
 LOCATION='J117',
 CDS_LIB='pure_quanta',
 CDS_PART_NAME='PICOPROBE_BXA-DELTA-L 4.0,SMLFA',
 PART_TYPE='SMLF',
 MATERIAL='EMPTY',
 VALUE='DELTA-L 4.0',
 PRIM_FILE='./archive_libs/logical/picoprobe_bxa/chips/chips.prt';

PART_NAME
 J118 'PICOPROBE_BXA-DELTA-L 4.0,SMLFA':;

SECTION_NUMBER 1
 '@S9S_MB_2U_LIB.S9S_MB_2U(SCH_1):PAGE287_I30@PURE_QUANTA.PICOPROBE_BXA(CHIPS)':
 C_PATH='@s9s_mb_2u_lib.s9s_mb_2u(sch_1):page287_i30@pure_quanta.picoprobe_bxa(c~
hips)',
 P_PATH='@s9s_mb_2u_lib.s9s_mb_2u(sch_1):page308_i30@pure_quanta.picoprobe_bxa(c~
hips)',
 PATH='I30',
 DRAWING='@S9S_MB_2U_LIB.S9S_MB_2U(SCH_1):PAGE287',
 PHYS_PAGE='308',
 XY='(1850,250)',
 ROT='0',
 VER='1',
 LOCATION='J118',
 CDS_LIB='pure_quanta',
 CDS_PART_NAME='PICOPROBE_BXA-DELTA-L 4.0,SMLFA',
 PART_TYPE='SMLF',
 MATERIAL='EMPTY',
 VALUE='DELTA-L 4.0',
 PRIM_FILE='./archive_libs/logical/picoprobe_bxa/chips/chips.prt';

PART_NAME
 J119 'PICOPROBE_BXA-DELTA-L 4.0,SMLFA':;

SECTION_NUMBER 1
 '@S9S_MB_2U_LIB.S9S_MB_2U(SCH_1):PAGE287_I28@PURE_QUANTA.PICOPROBE_BXA(CHIPS)':
 C_PATH='@s9s_mb_2u_lib.s9s_mb_2u(sch_1):page287_i28@pure_quanta.picoprobe_bxa(c~
hips)',
 P_PATH='@s9s_mb_2u_lib.s9s_mb_2u(sch_1):page308_i28@pure_quanta.picoprobe_bxa(c~
hips)',
 PATH='I28',
 DRAWING='@S9S_MB_2U_LIB.S9S_MB_2U(SCH_1):PAGE287',
 PHYS_PAGE='308',
 XY='(1850,-325)',
 ROT='0',
 VER='1',
 LOCATION='J119',
 CDS_LIB='pure_quanta',
 CDS_PART_NAME='PICOPROBE_BXA-DELTA-L 4.0,SMLFA',
 PART_TYPE='SMLF',
 MATERIAL='EMPTY',
 VALUE='DELTA-L 4.0',
 PRIM_FILE='./archive_libs/logical/picoprobe_bxa/chips/chips.prt';

PART_NAME
 J120 'PICOPROBE_BXA-DELTA-L 4.0,SMLFA':;

SECTION_NUMBER 1
 '@S9S_MB_2U_LIB.S9S_MB_2U(SCH_1):PAGE287_I32@PURE_QUANTA.PICOPROBE_BXA(CHIPS)':
 C_PATH='@s9s_mb_2u_lib.s9s_mb_2u(sch_1):page287_i32@pure_quanta.picoprobe_bxa(c~
hips)',
 P_PATH='@s9s_mb_2u_lib.s9s_mb_2u(sch_1):page308_i32@pure_quanta.picoprobe_bxa(c~
hips)',
 PATH='I32',
 DRAWING='@S9S_MB_2U_LIB.S9S_MB_2U(SCH_1):PAGE287',
 PHYS_PAGE='308',
 XY='(3900,300)',
 ROT='4',
 VER='1',
 LOCATION='J120',
 CDS_LIB='pure_quanta',
 CDS_PART_NAME='PICOPROBE_BXA-DELTA-L 4.0,SMLFA',
 PART_TYPE='SMLF',
 MATERIAL='EMPTY',
 VALUE='DELTA-L 4.0',
 PRIM_FILE='./archive_libs/logical/picoprobe_bxa/chips/chips.prt';

PART_NAME
 J121 'PICOPROBE_BXA-DELTA-L 4.0,SMLFA':;

SECTION_NUMBER 1
 '@S9S_MB_2U_LIB.S9S_MB_2U(SCH_1):PAGE287_I31@PURE_QUANTA.PICOPROBE_BXA(CHIPS)':
 C_PATH='@s9s_mb_2u_lib.s9s_mb_2u(sch_1):page287_i31@pure_quanta.picoprobe_bxa(c~
hips)',
 P_PATH='@s9s_mb_2u_lib.s9s_mb_2u(sch_1):page308_i31@pure_quanta.picoprobe_bxa(c~
hips)',
 PATH='I31',
 DRAWING='@S9S_MB_2U_LIB.S9S_MB_2U(SCH_1):PAGE287',
 PHYS_PAGE='308',
 XY='(3900,-275)',
 ROT='4',
 VER='1',
 LOCATION='J121',
 CDS_LIB='pure_quanta',
 CDS_PART_NAME='PICOPROBE_BXA-DELTA-L 4.0,SMLFA',
 PART_TYPE='SMLF',
 MATERIAL='EMPTY',
 VALUE='DELTA-L 4.0',
 PRIM_FILE='./archive_libs/logical/picoprobe_bxa/chips/chips.prt';

PART_NAME
 J122 'CONN1_10165288101LF-CONN1_1016A':;

SECTION_NUMBER 1
 '@S9S_MB_2U_LIB.S9S_MB_2U(SCH_1):PAGE289_I238@PURE_QUANTA.CONN1_10165288101LF(CHIPS)':
 C_PATH='@s9s_mb_2u_lib.s9s_mb_2u(sch_1):page289_i238@pure_quanta.conn1_10165288~
101lf(chips)',
 P_PATH='@s9s_mb_2u_lib.s9s_mb_2u(sch_1):page311_i238@pure_quanta.conn1_10165288~
101lf(chips)',
 PATH='I238',
 DRAWING='@S9S_MB_2U_LIB.S9S_MB_2U(SCH_1):PAGE289',
 PHYS_PAGE='311',
 XY='(4150,3250)',
 ROT='0',
 VER='1',
 CDS_LIB='pure_quanta',
 CDS_PART_NAME='CONN1_10165288101LF-CONN1_1016A',
 PART_TYPE='THLF',
 MATERIAL='IO',
 VALUE='CONN1_10165288-101LF',
 PRIM_FILE='./archive_libs/logical/conn1_10165288101lf/chips/chips.prt';

PART_NAME
 J123 'CONN1_10165288101LF-CONN1_1016A':;

SECTION_NUMBER 1
 '@S9S_MB_2U_LIB.S9S_MB_2U(SCH_1):PAGE289_I239@PURE_QUANTA.CONN1_10165288101LF(CHIPS)':
 C_PATH='@s9s_mb_2u_lib.s9s_mb_2u(sch_1):page289_i239@pure_quanta.conn1_10165288~
101lf(chips)',
 P_PATH='@s9s_mb_2u_lib.s9s_mb_2u(sch_1):page311_i239@pure_quanta.conn1_10165288~
101lf(chips)',
 PATH='I239',
 DRAWING='@S9S_MB_2U_LIB.S9S_MB_2U(SCH_1):PAGE289',
 PHYS_PAGE='311',
 XY='(5150,3250)',
 ROT='0',
 VER='1',
 CDS_LIB='pure_quanta',
 CDS_PART_NAME='CONN1_10165288101LF-CONN1_1016A',
 PART_TYPE='THLF',
 MATERIAL='IO',
 VALUE='CONN1_10165288-101LF',
 PRIM_FILE='./archive_libs/logical/conn1_10165288101lf/chips/chips.prt';

PART_NAME
 JP4 'CONN3_210HP1030BR1-CONN3_210-HA':;

SECTION_NUMBER 1
 '@S9S_MB_2U_LIB.S9S_MB_2U(SCH_1):PAGE175_I256@PURE_QUANTA.CONN3_210HP1030BR1(CHIPS)':
 C_PATH='@s9s_mb_2u_lib.s9s_mb_2u(sch_1):page175_i256@pure_quanta.conn3_210hp103~
0br1(chips)',
 P_PATH='@s9s_mb_2u_lib.s9s_mb_2u(sch_1):page183_i256@pure_quanta.conn3_210hp103~
0br1(chips)',
 PATH='I256',
 DRAWING='@S9S_MB_2U_LIB.S9S_MB_2U(SCH_1):PAGE175',
 PHYS_PAGE='183',
 XY='(-3125,1525)',
 ROT='2',
 VER='1',
 CDS_LIB='pure_quanta',
 CDS_PART_NAME='CONN3_210HP1030BR1-CONN3_210-HA',
 PART_TYPE='THLF',
 MATERIAL='EMPTY',
 VALUE='CONN3_210-HP1-030BR1',
 PRIM_FILE='./archive_libs/logical/conn3_210hp1030br1/chips/chips.prt';

PART_NAME
 JP7 'CONN3_210HP1030BR1-CONN3_210-HB':;

SECTION_NUMBER 1
 '@S9S_MB_2U_LIB.S9S_MB_2U(SCH_1):PAGE223_I64@PURE_QUANTA.CONN3_210HP1030BR1(CHIPS)':
 C_PATH='@s9s_mb_2u_lib.s9s_mb_2u(sch_1):page223_i64@pure_quanta.conn3_210hp1030~
br1(chips)',
 P_PATH='@s9s_mb_2u_lib.s9s_mb_2u(sch_1):page235_i64@pure_quanta.conn3_210hp1030~
br1(chips)',
 PATH='I64',
 DRAWING='@S9S_MB_2U_LIB.S9S_MB_2U(SCH_1):PAGE223',
 PHYS_PAGE='235',
 XY='(-6725,3200)',
 ROT='2',
 VER='1',
 CDS_LIB='pure_quanta',
 CDS_PART_NAME='CONN3_210HP1030BR1-CONN3_210-HB',
 PART_TYPE='THLF',
 MATERIAL='IO',
 VALUE='CONN3_210-HP1-030BR1',
 PRIM_FILE='./archive_libs/logical/conn3_210hp1030br1/chips/chips.prt';

PART_NAME
 JP9 'CONN3_210HP1030BR1-CONN3_210-HA':;

SECTION_NUMBER 1
 '@S9S_MB_2U_LIB.S9S_MB_2U(SCH_1):PAGE175_I263@PURE_QUANTA.CONN3_210HP1030BR1(CHIPS)':
 C_PATH='@s9s_mb_2u_lib.s9s_mb_2u(sch_1):page175_i263@pure_quanta.conn3_210hp103~
0br1(chips)',
 P_PATH='@s9s_mb_2u_lib.s9s_mb_2u(sch_1):page183_i263@pure_quanta.conn3_210hp103~
0br1(chips)',
 PATH='I263',
 DRAWING='@S9S_MB_2U_LIB.S9S_MB_2U(SCH_1):PAGE175',
 PHYS_PAGE='183',
 XY='(-3125,950)',
 ROT='2',
 VER='1',
 CDS_LIB='pure_quanta',
 CDS_PART_NAME='CONN3_210HP1030BR1-CONN3_210-HA',
 PART_TYPE='THLF',
 MATERIAL='EMPTY',
 VALUE='CONN3_210-HP1-030BR1',
 PRIM_FILE='./archive_libs/logical/conn3_210hp1030br1/chips/chips.prt';

PART_NAME
 JP10 'CONN3_210HP1030BR1-CONN3_210-HB':;

SECTION_NUMBER 1
 '@S9S_MB_2U_LIB.S9S_MB_2U(SCH_1):PAGE327_I51@PURE_QUANTA.CONN3_210HP1030BR1(CHIPS)':
 C_PATH='@s9s_mb_2u_lib.s9s_mb_2u(sch_1):page327_i51@pure_quanta.conn3_210hp1030~
br1(chips)',
 P_PATH='@s9s_mb_2u_lib.s9s_mb_2u(sch_1):page305_i51@pure_quanta.conn3_210hp1030~
br1(chips)',
 PATH='I51',
 DRAWING='@S9S_MB_2U_LIB.S9S_MB_2U(SCH_1):PAGE327',
 PHYS_PAGE='305',
 XY='(2475,1750)',
 ROT='2',
 VER='1',
 CDS_LIB='pure_quanta',
 CDS_PART_NAME='CONN3_210HP1030BR1-CONN3_210-HB',
 PART_TYPE='THLF',
 MATERIAL='IO',
 VALUE='CONN3_210-HP1-030BR1',
 PRIM_FILE='./archive_libs/logical/conn3_210hp1030br1/chips/chips.prt';

PART_NAME
 JP15 'CONN3_210HP1030BR1-CONN3_210-HB':;

SECTION_NUMBER 1
 '@S9S_MB_2U_LIB.S9S_MB_2U(SCH_1):PAGE312_I187@PURE_QUANTA.CONN3_210HP1030BR1(CHIPS)':
 C_PATH='@s9s_mb_2u_lib.s9s_mb_2u(sch_1):page312_i187@pure_quanta.conn3_210hp103~
0br1(chips)',
 P_PATH='@s9s_mb_2u_lib.s9s_mb_2u(sch_1):page215_i187@pure_quanta.conn3_210hp103~
0br1(chips)',
 PATH='I187',
 DRAWING='@S9S_MB_2U_LIB.S9S_MB_2U(SCH_1):PAGE312',
 PHYS_PAGE='215',
 XY='(-5050,3575)',
 ROT='0',
 VER='1',
 CDS_LIB='pure_quanta',
 CDS_PART_NAME='CONN3_210HP1030BR1-CONN3_210-HB',
 PART_TYPE='THLF',
 MATERIAL='IO',
 VALUE='CONN3_210-HP1-030BR1',
 PRIM_FILE='./archive_libs/logical/conn3_210hp1030br1/chips/chips.prt';

PART_NAME
 JP15_23 'TP_TP_BOM ONLY-NA,TP12_BOM':;

SECTION_NUMBER 1
 '@S9S_MB_2U_LIB.S9S_MB_2U(SCH_1):PAGE290_I71@PURE_QUANTA.TP(CHIPS)':
 C_PATH='@s9s_mb_2u_lib.s9s_mb_2u(sch_1):page290_i71@pure_quanta.tp(chips)',
 P_PATH='@s9s_mb_2u_lib.s9s_mb_2u(sch_1):page312_i71@pure_quanta.tp(chips)',
 PATH='I71',
 DRAWING='@S9S_MB_2U_LIB.S9S_MB_2U(SCH_1):PAGE290',
 QPN='DEJP0020021',
 PHYS_PAGE='312',
 XY='(-1225,-775)',
 ROT='0',
 VER='1',
 PACK_TYPE='TP_BOM ONLY',
 LOCATION='JP15_23',
 CDS_LIB='pure_quanta',
 CDS_PART_NAME='TP_TP_BOM ONLY-NA,TP12_BOM',
 MATERIAL='NA',
 PRIM_FILE='./archive_libs/logical/tp/chips/chips.prt';

PART_NAME
 JP16 'CONN3_210HP1030BR1-CONN3_210-HB':;

SECTION_NUMBER 1
 '@S9S_MB_2U_LIB.S9S_MB_2U(SCH_1):PAGE235_I13@PURE_QUANTA.CONN3_210HP1030BR1(CHIPS)':
 C_PATH='@s9s_mb_2u_lib.s9s_mb_2u(sch_1):page235_i13@pure_quanta.conn3_210hp1030~
br1(chips)',
 P_PATH='@s9s_mb_2u_lib.s9s_mb_2u(sch_1):page248_i13@pure_quanta.conn3_210hp1030~
br1(chips)',
 PATH='I13',
 DRAWING='@S9S_MB_2U_LIB.S9S_MB_2U(SCH_1):PAGE235',
 PHYS_PAGE='248',
 XY='(200,4550)',
 ROT='0',
 VER='1',
 CDS_LIB='pure_quanta',
 CDS_PART_NAME='CONN3_210HP1030BR1-CONN3_210-HB',
 PART_TYPE='THLF',
 MATERIAL='IO',
 VALUE='CONN3_210-HP1-030BR1',
 PRIM_FILE='./archive_libs/logical/conn3_210hp1030br1/chips/chips.prt';

PART_NAME
 JP16_23 'TP_TP_BOM ONLY-NA,TP12_BOM':;

SECTION_NUMBER 1
 '@S9S_MB_2U_LIB.S9S_MB_2U(SCH_1):PAGE290_I72@PURE_QUANTA.TP(CHIPS)':
 C_PATH='@s9s_mb_2u_lib.s9s_mb_2u(sch_1):page290_i72@pure_quanta.tp(chips)',
 P_PATH='@s9s_mb_2u_lib.s9s_mb_2u(sch_1):page312_i72@pure_quanta.tp(chips)',
 PATH='I72',
 DRAWING='@S9S_MB_2U_LIB.S9S_MB_2U(SCH_1):PAGE290',
 QPN='DEJP0020021',
 PHYS_PAGE='312',
 XY='(-1225,-1075)',
 ROT='0',
 VER='1',
 PACK_TYPE='TP_BOM ONLY',
 LOCATION='JP16_23',
 CDS_LIB='pure_quanta',
 CDS_PART_NAME='TP_TP_BOM ONLY-NA,TP12_BOM',
 MATERIAL='NA',
 PRIM_FILE='./archive_libs/logical/tp/chips/chips.prt';

PART_NAME
 JP4003 'CONN3_210HP1030BR1-CONN3_210-HB':;

SECTION_NUMBER 1
 '@S9S_MB_2U_LIB.S9S_MB_2U(SCH_1):PAGE303_I12@PURE_QUANTA.CONN3_210HP1030BR1(CHIPS)':
 C_PATH='@s9s_mb_2u_lib.s9s_mb_2u(sch_1):page303_i12@pure_quanta.conn3_210hp1030~
br1(chips)',
 P_PATH='@s9s_mb_2u_lib.s9s_mb_2u(sch_1):page301_i12@pure_quanta.conn3_210hp1030~
br1(chips)',
 PATH='I12',
 DRAWING='@S9S_MB_2U_LIB.S9S_MB_2U(SCH_1):PAGE303',
 PHYS_PAGE='301',
 XY='(-16550,1800)',
 ROT='0',
 VER='1',
 LOCATION='JP4003',
 CDS_LIB='pure_quanta',
 CDS_PART_NAME='CONN3_210HP1030BR1-CONN3_210-HB',
 PART_TYPE='THLF',
 MATERIAL='IO',
 VALUE='CONN3_210-HP1-030BR1',
 PRIM_FILE='./archive_libs/logical/conn3_210hp1030br1/chips/chips.prt';

PART_NAME
 JP4003_12 'TP_TP_BOM ONLY-NA,TP12_BOM':;

SECTION_NUMBER 1
 '@S9S_MB_2U_LIB.S9S_MB_2U(SCH_1):PAGE290_I70@PURE_QUANTA.TP(CHIPS)':
 C_PATH='@s9s_mb_2u_lib.s9s_mb_2u(sch_1):page290_i70@pure_quanta.tp(chips)',
 P_PATH='@s9s_mb_2u_lib.s9s_mb_2u(sch_1):page312_i70@pure_quanta.tp(chips)',
 PATH='I70',
 DRAWING='@S9S_MB_2U_LIB.S9S_MB_2U(SCH_1):PAGE290',
 QPN='DEJP0020021',
 PHYS_PAGE='312',
 XY='(-1225,-475)',
 ROT='0',
 VER='1',
 PACK_TYPE='TP_BOM ONLY',
 LOCATION='JP4003_12',
 CDS_LIB='pure_quanta',
 CDS_PART_NAME='TP_TP_BOM ONLY-NA,TP12_BOM',
 MATERIAL='NA',
 PRIM_FILE='./archive_libs/logical/tp/chips/chips.prt';

PART_NAME
 L1 'Q_INDUCTOR_SMLF-FCM2012KF-601TA':;

SECTION_NUMBER 1
 '@S9S_MB_2U_LIB.S9S_MB_2U(SCH_1):PAGE199_I20@PURE_QUANTA.Q_INDUCTOR(CHIPS)':
 C_PATH='@s9s_mb_2u_lib.s9s_mb_2u(sch_1):page199_i20@pure_quanta.q_inductor(chip~
s)',
 P_PATH='@s9s_mb_2u_lib.s9s_mb_2u(sch_1):page210_i20@pure_quanta.q_inductor(chip~
s)',
 PATH='I20',
 DRAWING='@S9S_MB_2U_LIB.S9S_MB_2U(SCH_1):PAGE199',
 PHYS_PAGE='210',
 XY='(-12075,7700)',
 ROT='0',
 VER='1',
 PACK_TYPE='SMLF',
 CDS_LIB='pure_quanta',
 CDS_PART_NAME='Q_INDUCTOR_SMLF-FCM2012KF-601TA',
 MATERIAL='IND',
 VALUE='FCM2012KF-601T/0.5A',
 PRIM_FILE='./archive_libs/logical/q_inductor/chips/chips.prt';

PART_NAME
 L2 'Q_INDUCTOR_SMLF-BLM15PX121SN1DA':;

SECTION_NUMBER 1
 '@S9S_MB_2U_LIB.S9S_MB_2U(SCH_1):PAGE181_I164@PURE_QUANTA.Q_INDUCTOR(CHIPS)':
 C_PATH='@s9s_mb_2u_lib.s9s_mb_2u(sch_1):page181_i164@pure_quanta.q_inductor(chi~
ps)',
 P_PATH='@s9s_mb_2u_lib.s9s_mb_2u(sch_1):page189_i164@pure_quanta.q_inductor(chi~
ps)',
 PATH='I164',
 DRAWING='@S9S_MB_2U_LIB.S9S_MB_2U(SCH_1):PAGE181',
 PHYS_PAGE='189',
 XY='(2700,3775)',
 ROT='0',
 VER='1',
 PACK_TYPE='SMLF',
 LOCATION='L2',
 CDS_LIB='pure_quanta',
 CDS_PART_NAME='Q_INDUCTOR_SMLF-BLM15PX121SN1DB',
 MATERIAL='EMPTY',
 VALUE='BLM15PX121SN1D/2A',
 PRIM_FILE='./archive_libs/logical/q_inductor/chips/chips.prt';

PART_NAME
 L3 'Q_INDUCTOR_SMLF-BLM18SG331TN1DA':;

SECTION_NUMBER 1
 '@S9S_MB_2U_LIB.S9S_MB_2U(SCH_1):PAGE195_I170@PURE_QUANTA.Q_INDUCTOR(CHIPS)':
 C_PATH='@s9s_mb_2u_lib.s9s_mb_2u(sch_1):page195_i170@pure_quanta.q_inductor(chi~
ps)',
 P_PATH='@s9s_mb_2u_lib.s9s_mb_2u(sch_1):page206_i170@pure_quanta.q_inductor(chi~
ps)',
 PATH='I170',
 DRAWING='@S9S_MB_2U_LIB.S9S_MB_2U(SCH_1):PAGE195',
 PHYS_PAGE='206',
 XY='(-9100,5250)',
 ROT='0',
 VER='1',
 PACK_TYPE='SMLF',
 CDS_LIB='pure_quanta',
 CDS_PART_NAME='Q_INDUCTOR_SMLF-BLM18SG331TN1DA',
 MATERIAL='IND',
 VALUE='BLM18SG331TN1D/1.5A',
 PRIM_FILE='./archive_libs/logical/q_inductor/chips/chips.prt';

PART_NAME
 L4 'Q_INDUCTOR_SMLF-BLM18SG331TN1DA':;

SECTION_NUMBER 1
 '@S9S_MB_2U_LIB.S9S_MB_2U(SCH_1):PAGE195_I177@PURE_QUANTA.Q_INDUCTOR(CHIPS)':
 C_PATH='@s9s_mb_2u_lib.s9s_mb_2u(sch_1):page195_i177@pure_quanta.q_inductor(chi~
ps)',
 P_PATH='@s9s_mb_2u_lib.s9s_mb_2u(sch_1):page206_i177@pure_quanta.q_inductor(chi~
ps)',
 PATH='I177',
 DRAWING='@S9S_MB_2U_LIB.S9S_MB_2U(SCH_1):PAGE195',
 PHYS_PAGE='206',
 XY='(-9100,4225)',
 ROT='0',
 VER='1',
 PACK_TYPE='SMLF',
 CDS_LIB='pure_quanta',
 CDS_PART_NAME='Q_INDUCTOR_SMLF-BLM18SG331TN1DA',
 MATERIAL='IND',
 VALUE='BLM18SG331TN1D/1.5A',
 PRIM_FILE='./archive_libs/logical/q_inductor/chips/chips.prt';

PART_NAME
 L10 'Q_INDUCTOR_SMLF-BLM18PG121SN1DA':;

SECTION_NUMBER 1
 '@S9S_MB_2U_LIB.S9S_MB_2U(SCH_1):PAGE181_I145@PURE_QUANTA.Q_INDUCTOR(CHIPS)':
 C_PATH='@s9s_mb_2u_lib.s9s_mb_2u(sch_1):page181_i145@pure_quanta.q_inductor(chi~
ps)',
 P_PATH='@s9s_mb_2u_lib.s9s_mb_2u(sch_1):page189_i145@pure_quanta.q_inductor(chi~
ps)',
 PATH='I145',
 DRAWING='@S9S_MB_2U_LIB.S9S_MB_2U(SCH_1):PAGE181',
 PHYS_PAGE='189',
 XY='(2750,1100)',
 ROT='0',
 VER='1',
 PACK_TYPE='SMLF',
 CDS_LIB='pure_quanta',
 CDS_PART_NAME='Q_INDUCTOR_SMLF-BLM18PG121SN1DA',
 MATERIAL='EMPTY',
 VALUE='BLM18PG121SN1D/2000MA',
 PRIM_FILE='./archive_libs/logical/q_inductor/chips/chips.prt';

PART_NAME
 L13 'Q_INDUCTOR_SMLF-FCM2012KF-601TA':;

SECTION_NUMBER 1
 '@S9S_MB_2U_LIB.S9S_MB_2U(SCH_1):PAGE199_I41@PURE_QUANTA.Q_INDUCTOR(CHIPS)':
 C_PATH='@s9s_mb_2u_lib.s9s_mb_2u(sch_1):page199_i41@pure_quanta.q_inductor(chip~
s)',
 P_PATH='@s9s_mb_2u_lib.s9s_mb_2u(sch_1):page210_i41@pure_quanta.q_inductor(chip~
s)',
 PATH='I41',
 DRAWING='@S9S_MB_2U_LIB.S9S_MB_2U(SCH_1):PAGE199',
 PHYS_PAGE='210',
 XY='(-12075,6475)',
 ROT='0',
 VER='1',
 PACK_TYPE='SMLF',
 CDS_LIB='pure_quanta',
 CDS_PART_NAME='Q_INDUCTOR_SMLF-FCM2012KF-601TA',
 MATERIAL='IND',
 VALUE='FCM2012KF-601T/0.5A',
 PRIM_FILE='./archive_libs/logical/q_inductor/chips/chips.prt';

PART_NAME
 L14 'Q_INDUCTOR_SMLF-FCM2012KF-601TA':;

SECTION_NUMBER 1
 '@S9S_MB_2U_LIB.S9S_MB_2U(SCH_1):PAGE199_I60@PURE_QUANTA.Q_INDUCTOR(CHIPS)':
 C_PATH='@s9s_mb_2u_lib.s9s_mb_2u(sch_1):page199_i60@pure_quanta.q_inductor(chip~
s)',
 P_PATH='@s9s_mb_2u_lib.s9s_mb_2u(sch_1):page210_i60@pure_quanta.q_inductor(chip~
s)',
 PATH='I60',
 DRAWING='@S9S_MB_2U_LIB.S9S_MB_2U(SCH_1):PAGE199',
 PHYS_PAGE='210',
 XY='(-12075,5175)',
 ROT='0',
 VER='1',
 PACK_TYPE='SMLF',
 CDS_LIB='pure_quanta',
 CDS_PART_NAME='Q_INDUCTOR_SMLF-FCM2012KF-601TA',
 MATERIAL='IND',
 VALUE='FCM2012KF-601T/0.5A',
 PRIM_FILE='./archive_libs/logical/q_inductor/chips/chips.prt';

PART_NAME
 L15 'Q_INDUCTOR_SMLF-BLM18PG300SN1DA':
 ROOM='ADC1_BOM1';

SECTION_NUMBER 1
 '@S9S_MB_2U_LIB.S9S_MB_2U(SCH_1):PAGE239_I62@PURE_QUANTA.Q_INDUCTOR(CHIPS)':
 C_PATH='@s9s_mb_2u_lib.s9s_mb_2u(sch_1):page239_i62@pure_quanta.q_inductor(chip~
s)',
 P_PATH='@s9s_mb_2u_lib.s9s_mb_2u(sch_1):page250_i62@pure_quanta.q_inductor(chip~
s)',
 PATH='I62',
 DRAWING='@S9S_MB_2U_LIB.S9S_MB_2U(SCH_1):PAGE239',
 PHYS_PAGE='250',
 XY='(7100,4750)',
 ROT='0',
 VER='1',
 PACK_TYPE='SMLF',
 CDS_LIB='pure_quanta',
 CDS_PART_NAME='Q_INDUCTOR_SMLF-BLM18PG300SN1DA',
 MATERIAL='EMPTY',
 ROOM='ADC1_BOM1',
 VALUE='BLM18PG300SN1D ',
 PRIM_FILE='./archive_libs/logical/q_inductor/chips/chips.prt';

PART_NAME
 L16 'Q_INDUCTOR_SMLF-BLM18PG300SN1DB':
 ROOM='ADC1_BOM2';

SECTION_NUMBER 1
 '@S9S_MB_2U_LIB.S9S_MB_2U(SCH_1):PAGE239_I118@PURE_QUANTA.Q_INDUCTOR(CHIPS)':
 C_PATH='@s9s_mb_2u_lib.s9s_mb_2u(sch_1):page239_i118@pure_quanta.q_inductor(chi~
ps)',
 P_PATH='@s9s_mb_2u_lib.s9s_mb_2u(sch_1):page250_i118@pure_quanta.q_inductor(chi~
ps)',
 PATH='I118',
 DRAWING='@S9S_MB_2U_LIB.S9S_MB_2U(SCH_1):PAGE239',
 PHYS_PAGE='250',
 XY='(3550,1925)',
 ROT='0',
 VER='1',
 PACK_TYPE='SMLF',
 CDS_LIB='pure_quanta',
 CDS_PART_NAME='Q_INDUCTOR_SMLF-BLM18PG300SN1DB',
 MATERIAL='IND',
 ROOM='ADC1_BOM2',
 VALUE='BLM18PG300SN1D ',
 PRIM_FILE='./archive_libs/logical/q_inductor/chips/chips.prt';

PART_NAME
 L17 'Q_INDUCTOR_SMLF-FCM2012KF-601TA':;

SECTION_NUMBER 1
 '@S9S_MB_2U_LIB.S9S_MB_2U(SCH_1):PAGE201_I155@PURE_QUANTA.Q_INDUCTOR(CHIPS)':
 C_PATH='@s9s_mb_2u_lib.s9s_mb_2u(sch_1):page201_i155@pure_quanta.q_inductor(chi~
ps)',
 P_PATH='@s9s_mb_2u_lib.s9s_mb_2u(sch_1):page212_i155@pure_quanta.q_inductor(chi~
ps)',
 PATH='I155',
 DRAWING='@S9S_MB_2U_LIB.S9S_MB_2U(SCH_1):PAGE201',
 PHYS_PAGE='212',
 XY='(-3150,5225)',
 ROT='0',
 VER='1',
 PACK_TYPE='SMLF',
 LOCATION='L17',
 CDS_LIB='pure_quanta',
 CDS_PART_NAME='Q_INDUCTOR_SMLF-FCM2012KF-601TA',
 MATERIAL='IND',
 VALUE='FCM2012KF-601T/0.5A',
 PRIM_FILE='./archive_libs/logical/q_inductor/chips/chips.prt';

PART_NAME
 L18 'Q_INDUCTOR_SMLF-BLM15PX121SN1DB':;

SECTION_NUMBER 1
 '@S9S_MB_2U_LIB.S9S_MB_2U(SCH_1):PAGE162_I35@PURE_QUANTA.Q_INDUCTOR(CHIPS)':
 C_PATH='@s9s_mb_2u_lib.s9s_mb_2u(sch_1):page162_i35@pure_quanta.q_inductor(chip~
s)',
 P_PATH='@s9s_mb_2u_lib.s9s_mb_2u(sch_1):page169_i35@pure_quanta.q_inductor(chip~
s)',
 PATH='I35',
 DRAWING='@S9S_MB_2U_LIB.S9S_MB_2U(SCH_1):PAGE162',
 PHYS_PAGE='169',
 XY='(-3300,4650)',
 ROT='0',
 VER='1',
 PACK_TYPE='SMLF',
 CDS_LIB='pure_quanta',
 CDS_PART_NAME='Q_INDUCTOR_SMLF-BLM15PX121SN1DA',
 MATERIAL='IND',
 VALUE='BLM15PX121SN1D/2A',
 PRIM_FILE='./archive_libs/logical/q_inductor/chips/chips.prt';

PART_NAME
 L19 'Q_INDUCTOR_SMLF-FCM2012KF-601TA':;

SECTION_NUMBER 1
 '@S9S_MB_2U_LIB.S9S_MB_2U(SCH_1):PAGE200_I81@PURE_QUANTA.Q_INDUCTOR(CHIPS)':
 C_PATH='@s9s_mb_2u_lib.s9s_mb_2u(sch_1):page200_i81@pure_quanta.q_inductor(chip~
s)',
 P_PATH='@s9s_mb_2u_lib.s9s_mb_2u(sch_1):page211_i81@pure_quanta.q_inductor(chip~
s)',
 PATH='I81',
 DRAWING='@S9S_MB_2U_LIB.S9S_MB_2U(SCH_1):PAGE200',
 PHYS_PAGE='211',
 XY='(4750,8375)',
 ROT='0',
 VER='1',
 PACK_TYPE='SMLF',
 LOCATION='L19',
 CDS_LIB='pure_quanta',
 CDS_PART_NAME='Q_INDUCTOR_SMLF-FCM2012KF-601TA',
 MATERIAL='IND',
 VALUE='FCM2012KF-601T/0.5A',
 PRIM_FILE='./archive_libs/logical/q_inductor/chips/chips.prt';

PART_NAME
 L20 'Q_INDUCTOR_SMLF-FCM2012KF-601TA':;

SECTION_NUMBER 1
 '@S9S_MB_2U_LIB.S9S_MB_2U(SCH_1):PAGE200_I82@PURE_QUANTA.Q_INDUCTOR(CHIPS)':
 C_PATH='@s9s_mb_2u_lib.s9s_mb_2u(sch_1):page200_i82@pure_quanta.q_inductor(chip~
s)',
 P_PATH='@s9s_mb_2u_lib.s9s_mb_2u(sch_1):page211_i82@pure_quanta.q_inductor(chip~
s)',
 PATH='I82',
 DRAWING='@S9S_MB_2U_LIB.S9S_MB_2U(SCH_1):PAGE200',
 PHYS_PAGE='211',
 XY='(8075,8050)',
 ROT='0',
 VER='1',
 PACK_TYPE='SMLF',
 LOCATION='L20',
 CDS_LIB='pure_quanta',
 CDS_PART_NAME='Q_INDUCTOR_SMLF-FCM2012KF-601TA',
 MATERIAL='IND',
 VALUE='FCM2012KF-601T/0.5A',
 PRIM_FILE='./archive_libs/logical/q_inductor/chips/chips.prt';

PART_NAME
 ME2 'ME_DUMMY_SYMBOL-PICKUP_SMDC20,A':;

SECTION_NUMBER -1
 '@S9S_MB_2U_LIB.S9S_MB_2U(SCH_1):PAGE290_I10@PURE_QUANTA.ME_DUMMY_SYMBOL(CHIPS)':
 C_PATH='@s9s_mb_2u_lib.s9s_mb_2u(sch_1):page290_i10@pure_quanta.me_dummy_symbol~
(chips)',
 P_PATH='@s9s_mb_2u_lib.s9s_mb_2u(sch_1):page312_i10@pure_quanta.me_dummy_symbol~
(chips)',
 PATH='I10',
 DRAWING='@S9S_MB_2U_LIB.S9S_MB_2U(SCH_1):PAGE290',
 PIN_TEXT_VISIBLE='True',
 PIN_NAMES_ROTATE='True',
 PHYS_PAGE='312',
 XY='(3600,3275)',
 ROT='0',
 VER='1',
 CDS_LIB='pure_quanta',
 CDS_PART_NAME='ME_DUMMY_SYMBOL-PICKUP_SMDC20,A',
 PART_TYPE='MECH',
 MATERIAL='EMPTY',
 VALUE='PICKUP_SMDC20',
 PRIM_FILE='./archive_libs/logical/me_dummy_symbol/chips/chips.prt';

PART_NAME
 ME3 'ME_DUMMY_SYMBOL-PICKUP_SMDC20,A':;

SECTION_NUMBER -1
 '@S9S_MB_2U_LIB.S9S_MB_2U(SCH_1):PAGE290_I11@PURE_QUANTA.ME_DUMMY_SYMBOL(CHIPS)':
 C_PATH='@s9s_mb_2u_lib.s9s_mb_2u(sch_1):page290_i11@pure_quanta.me_dummy_symbol~
(chips)',
 P_PATH='@s9s_mb_2u_lib.s9s_mb_2u(sch_1):page312_i11@pure_quanta.me_dummy_symbol~
(chips)',
 PATH='I11',
 DRAWING='@S9S_MB_2U_LIB.S9S_MB_2U(SCH_1):PAGE290',
 PIN_TEXT_VISIBLE='True',
 PIN_NAMES_ROTATE='True',
 PHYS_PAGE='312',
 XY='(3600,2700)',
 ROT='0',
 VER='1',
 CDS_LIB='pure_quanta',
 CDS_PART_NAME='ME_DUMMY_SYMBOL-PICKUP_SMDC20,A',
 PART_TYPE='MECH',
 MATERIAL='EMPTY',
 VALUE='PICKUP_SMDC20',
 PRIM_FILE='./archive_libs/logical/me_dummy_symbol/chips/chips.prt';

PART_NAME
 ME4 'ME_DUMMY_SYMBOL-PICKUP_SMDC20,A':;

SECTION_NUMBER -1
 '@S9S_MB_2U_LIB.S9S_MB_2U(SCH_1):PAGE290_I9@PURE_QUANTA.ME_DUMMY_SYMBOL(CHIPS)':
 C_PATH='@s9s_mb_2u_lib.s9s_mb_2u(sch_1):page290_i9@pure_quanta.me_dummy_symbol(~
chips)',
 P_PATH='@s9s_mb_2u_lib.s9s_mb_2u(sch_1):page312_i9@pure_quanta.me_dummy_symbol(~
chips)',
 PATH='I9',
 DRAWING='@S9S_MB_2U_LIB.S9S_MB_2U(SCH_1):PAGE290',
 PIN_TEXT_VISIBLE='True',
 PIN_NAMES_ROTATE='True',
 PHYS_PAGE='312',
 XY='(4225,3275)',
 ROT='0',
 VER='1',
 CDS_LIB='pure_quanta',
 CDS_PART_NAME='ME_DUMMY_SYMBOL-PICKUP_SMDC20,A',
 PART_TYPE='MECH',
 MATERIAL='EMPTY',
 VALUE='PICKUP_SMDC20',
 PRIM_FILE='./archive_libs/logical/me_dummy_symbol/chips/chips.prt';

PART_NAME
 ME9 'ME_DUMMY_SYMBOL-PICKUP_SMDC20,A':;

SECTION_NUMBER -1
 '@S9S_MB_2U_LIB.S9S_MB_2U(SCH_1):PAGE290_I18@PURE_QUANTA.ME_DUMMY_SYMBOL(CHIPS)':
 C_PATH='@s9s_mb_2u_lib.s9s_mb_2u(sch_1):page290_i18@pure_quanta.me_dummy_symbol~
(chips)',
 P_PATH='@s9s_mb_2u_lib.s9s_mb_2u(sch_1):page312_i18@pure_quanta.me_dummy_symbol~
(chips)',
 PATH='I18',
 DRAWING='@S9S_MB_2U_LIB.S9S_MB_2U(SCH_1):PAGE290',
 PIN_TEXT_VISIBLE='True',
 PIN_NAMES_ROTATE='True',
 PHYS_PAGE='312',
 XY='(4975,3275)',
 ROT='0',
 VER='1',
 CDS_LIB='pure_quanta',
 CDS_PART_NAME='ME_DUMMY_SYMBOL-PICKUP_SMDC20,A',
 PART_TYPE='MECH',
 MATERIAL='EMPTY',
 VALUE='PICKUP_SMDC20',
 PRIM_FILE='./archive_libs/logical/me_dummy_symbol/chips/chips.prt';

PART_NAME
 ME10 'ME_DUMMY_SYMBOL-PICKUP_SMDC20,A':;

SECTION_NUMBER -1
 '@S9S_MB_2U_LIB.S9S_MB_2U(SCH_1):PAGE290_I19@PURE_QUANTA.ME_DUMMY_SYMBOL(CHIPS)':
 C_PATH='@s9s_mb_2u_lib.s9s_mb_2u(sch_1):page290_i19@pure_quanta.me_dummy_symbol~
(chips)',
 P_PATH='@s9s_mb_2u_lib.s9s_mb_2u(sch_1):page312_i19@pure_quanta.me_dummy_symbol~
(chips)',
 PATH='I19',
 DRAWING='@S9S_MB_2U_LIB.S9S_MB_2U(SCH_1):PAGE290',
 PIN_TEXT_VISIBLE='True',
 PIN_NAMES_ROTATE='True',
 PHYS_PAGE='312',
 XY='(4980,2645)',
 ROT='0',
 VER='1',
 CDS_LIB='pure_quanta',
 CDS_PART_NAME='ME_DUMMY_SYMBOL-PICKUP_SMDC20,A',
 PART_TYPE='MECH',
 MATERIAL='EMPTY',
 VALUE='PICKUP_SMDC20',
 PRIM_FILE='./archive_libs/logical/me_dummy_symbol/chips/chips.prt';

PART_NAME
 ME11 'ME_DUMMY_SYMBOL-PICKUP_SMDC20,A':;

SECTION_NUMBER -1
 '@S9S_MB_2U_LIB.S9S_MB_2U(SCH_1):PAGE290_I14@PURE_QUANTA.ME_DUMMY_SYMBOL(CHIPS)':
 C_PATH='@s9s_mb_2u_lib.s9s_mb_2u(sch_1):page290_i14@pure_quanta.me_dummy_symbol~
(chips)',
 P_PATH='@s9s_mb_2u_lib.s9s_mb_2u(sch_1):page312_i14@pure_quanta.me_dummy_symbol~
(chips)',
 PATH='I14',
 DRAWING='@S9S_MB_2U_LIB.S9S_MB_2U(SCH_1):PAGE290',
 PIN_TEXT_VISIBLE='True',
 PIN_NAMES_ROTATE='True',
 PHYS_PAGE='312',
 XY='(5615,3270)',
 ROT='0',
 VER='1',
 CDS_LIB='pure_quanta',
 CDS_PART_NAME='ME_DUMMY_SYMBOL-PICKUP_SMDC20,A',
 PART_TYPE='MECH',
 MATERIAL='EMPTY',
 VALUE='PICKUP_SMDC20',
 PRIM_FILE='./archive_libs/logical/me_dummy_symbol/chips/chips.prt';

PART_NAME
 ME12 'ME_DUMMY_SYMBOL-PICKUP_SMDC20,A':;

SECTION_NUMBER -1
 '@S9S_MB_2U_LIB.S9S_MB_2U(SCH_1):PAGE290_I15@PURE_QUANTA.ME_DUMMY_SYMBOL(CHIPS)':
 C_PATH='@s9s_mb_2u_lib.s9s_mb_2u(sch_1):page290_i15@pure_quanta.me_dummy_symbol~
(chips)',
 P_PATH='@s9s_mb_2u_lib.s9s_mb_2u(sch_1):page312_i15@pure_quanta.me_dummy_symbol~
(chips)',
 PATH='I15',
 DRAWING='@S9S_MB_2U_LIB.S9S_MB_2U(SCH_1):PAGE290',
 PIN_TEXT_VISIBLE='True',
 PIN_NAMES_ROTATE='True',
 PHYS_PAGE='312',
 XY='(5620,2640)',
 ROT='0',
 VER='1',
 CDS_LIB='pure_quanta',
 CDS_PART_NAME='ME_DUMMY_SYMBOL-PICKUP_SMDC20,A',
 PART_TYPE='MECH',
 MATERIAL='EMPTY',
 VALUE='PICKUP_SMDC20',
 PRIM_FILE='./archive_libs/logical/me_dummy_symbol/chips/chips.prt';

PART_NAME
 ME13 'ME_DUMMY_SYMBOL-PICKUP_SMDC20,A':;

SECTION_NUMBER -1
 '@S9S_MB_2U_LIB.S9S_MB_2U(SCH_1):PAGE290_I13@PURE_QUANTA.ME_DUMMY_SYMBOL(CHIPS)':
 C_PATH='@s9s_mb_2u_lib.s9s_mb_2u(sch_1):page290_i13@pure_quanta.me_dummy_symbol~
(chips)',
 P_PATH='@s9s_mb_2u_lib.s9s_mb_2u(sch_1):page312_i13@pure_quanta.me_dummy_symbol~
(chips)',
 PATH='I13',
 DRAWING='@S9S_MB_2U_LIB.S9S_MB_2U(SCH_1):PAGE290',
 PIN_TEXT_VISIBLE='True',
 PIN_NAMES_ROTATE='True',
 PHYS_PAGE='312',
 XY='(3605,1960)',
 ROT='0',
 VER='1',
 CDS_LIB='pure_quanta',
 CDS_PART_NAME='ME_DUMMY_SYMBOL-PICKUP_SMDC20,A',
 PART_TYPE='MECH',
 MATERIAL='EMPTY',
 VALUE='PICKUP_SMDC20',
 PRIM_FILE='./archive_libs/logical/me_dummy_symbol/chips/chips.prt';

PART_NAME
 ME14 'ME_DUMMY_SYMBOL-PICKUP_SMDC20,A':;

SECTION_NUMBER -1
 '@S9S_MB_2U_LIB.S9S_MB_2U(SCH_1):PAGE290_I16@PURE_QUANTA.ME_DUMMY_SYMBOL(CHIPS)':
 C_PATH='@s9s_mb_2u_lib.s9s_mb_2u(sch_1):page290_i16@pure_quanta.me_dummy_symbol~
(chips)',
 P_PATH='@s9s_mb_2u_lib.s9s_mb_2u(sch_1):page312_i16@pure_quanta.me_dummy_symbol~
(chips)',
 PATH='I16',
 DRAWING='@S9S_MB_2U_LIB.S9S_MB_2U(SCH_1):PAGE290',
 PIN_TEXT_VISIBLE='True',
 PIN_NAMES_ROTATE='True',
 PHYS_PAGE='312',
 XY='(3610,1330)',
 ROT='0',
 VER='1',
 CDS_LIB='pure_quanta',
 CDS_PART_NAME='ME_DUMMY_SYMBOL-PICKUP_SMDC20,A',
 PART_TYPE='MECH',
 MATERIAL='EMPTY',
 VALUE='PICKUP_SMDC20',
 PRIM_FILE='./archive_libs/logical/me_dummy_symbol/chips/chips.prt';

PART_NAME
 ME15 'ME_DUMMY_SYMBOL-PICKUP_SMDC20,A':;

SECTION_NUMBER -1
 '@S9S_MB_2U_LIB.S9S_MB_2U(SCH_1):PAGE290_I12@PURE_QUANTA.ME_DUMMY_SYMBOL(CHIPS)':
 C_PATH='@s9s_mb_2u_lib.s9s_mb_2u(sch_1):page290_i12@pure_quanta.me_dummy_symbol~
(chips)',
 P_PATH='@s9s_mb_2u_lib.s9s_mb_2u(sch_1):page312_i12@pure_quanta.me_dummy_symbol~
(chips)',
 PATH='I12',
 DRAWING='@S9S_MB_2U_LIB.S9S_MB_2U(SCH_1):PAGE290',
 PIN_TEXT_VISIBLE='True',
 PIN_NAMES_ROTATE='True',
 PHYS_PAGE='312',
 XY='(4245,1955)',
 ROT='0',
 VER='1',
 CDS_LIB='pure_quanta',
 CDS_PART_NAME='ME_DUMMY_SYMBOL-PICKUP_SMDC20,A',
 PART_TYPE='MECH',
 MATERIAL='EMPTY',
 VALUE='PICKUP_SMDC20',
 PRIM_FILE='./archive_libs/logical/me_dummy_symbol/chips/chips.prt';

PART_NAME
 ME17 'ME_DUMMY_SYMBOL-QUANTA_LOGO_7XA':;

SECTION_NUMBER -1
 '@S9S_MB_2U_LIB.S9S_MB_2U(SCH_1):PAGE290_I62@PURE_QUANTA.ME_DUMMY_SYMBOL(CHIPS)':
 C_PATH='@s9s_mb_2u_lib.s9s_mb_2u(sch_1):page290_i62@pure_quanta.me_dummy_symbol~
(chips)',
 P_PATH='@s9s_mb_2u_lib.s9s_mb_2u(sch_1):page312_i62@pure_quanta.me_dummy_symbol~
(chips)',
 PATH='I62',
 DRAWING='@S9S_MB_2U_LIB.S9S_MB_2U(SCH_1):PAGE290',
 PIN_TEXT_VISIBLE='True',
 PIN_NAMES_ROTATE='True',
 PHYS_PAGE='312',
 XY='(-2775,4475)',
 ROT='0',
 VER='1',
 CDS_LIB='pure_quanta',
 CDS_PART_NAME='ME_DUMMY_SYMBOL-QUANTA_LOGO_7XA',
 PART_TYPE='MECH',
 MATERIAL='EMPTY',
 VALUE='QUANTA_LOGO_7X26',
 PRIM_FILE='./archive_libs/logical/me_dummy_symbol/chips/chips.prt';

PART_NAME
 ME18 'ME_DUMMY_SYMBOL-WEEE,MECH,EMPTA':;

SECTION_NUMBER -1
 '@S9S_MB_2U_LIB.S9S_MB_2U(SCH_1):PAGE290_I63@PURE_QUANTA.ME_DUMMY_SYMBOL(CHIPS)':
 C_PATH='@s9s_mb_2u_lib.s9s_mb_2u(sch_1):page290_i63@pure_quanta.me_dummy_symbol~
(chips)',
 P_PATH='@s9s_mb_2u_lib.s9s_mb_2u(sch_1):page312_i63@pure_quanta.me_dummy_symbol~
(chips)',
 PATH='I63',
 DRAWING='@S9S_MB_2U_LIB.S9S_MB_2U(SCH_1):PAGE290',
 PIN_TEXT_VISIBLE='True',
 PIN_NAMES_ROTATE='True',
 PHYS_PAGE='312',
 XY='(-1475,4475)',
 ROT='0',
 VER='1',
 CDS_LIB='pure_quanta',
 CDS_PART_NAME='ME_DUMMY_SYMBOL-WEEE,MECH,EMPTA',
 PART_TYPE='MECH',
 MATERIAL='EMPTY',
 VALUE='WEEE',
 PRIM_FILE='./archive_libs/logical/me_dummy_symbol/chips/chips.prt';

PART_NAME
 ME20 'ME_DUMMY_SYMBOL-PB-E1_SMALL,MEA':;

SECTION_NUMBER -1
 '@S9S_MB_2U_LIB.S9S_MB_2U(SCH_1):PAGE290_I64@PURE_QUANTA.ME_DUMMY_SYMBOL(CHIPS)':
 C_PATH='@s9s_mb_2u_lib.s9s_mb_2u(sch_1):page290_i64@pure_quanta.me_dummy_symbol~
(chips)',
 P_PATH='@s9s_mb_2u_lib.s9s_mb_2u(sch_1):page312_i64@pure_quanta.me_dummy_symbol~
(chips)',
 PATH='I64',
 DRAWING='@S9S_MB_2U_LIB.S9S_MB_2U(SCH_1):PAGE290',
 PIN_TEXT_VISIBLE='True',
 PIN_NAMES_ROTATE='True',
 PHYS_PAGE='312',
 XY='(-50,4500)',
 ROT='0',
 VER='1',
 CDS_LIB='pure_quanta',
 CDS_PART_NAME='ME_DUMMY_SYMBOL-PB-E1_SMALL,MEA',
 PART_TYPE='MECH',
 MATERIAL='EMPTY',
 VALUE='PB-E1_SMALL',
 PRIM_FILE='./archive_libs/logical/me_dummy_symbol/chips/chips.prt';

PART_NAME
 ME21 'ME_DUMMY_SYMBOL-PCB_VENDOR_LOGA':;

SECTION_NUMBER -1
 '@S9S_MB_2U_LIB.S9S_MB_2U(SCH_1):PAGE290_I65@PURE_QUANTA.ME_DUMMY_SYMBOL(CHIPS)':
 C_PATH='@s9s_mb_2u_lib.s9s_mb_2u(sch_1):page290_i65@pure_quanta.me_dummy_symbol~
(chips)',
 P_PATH='@s9s_mb_2u_lib.s9s_mb_2u(sch_1):page312_i65@pure_quanta.me_dummy_symbol~
(chips)',
 PATH='I65',
 DRAWING='@S9S_MB_2U_LIB.S9S_MB_2U(SCH_1):PAGE290',
 PIN_TEXT_VISIBLE='True',
 PIN_NAMES_ROTATE='True',
 PHYS_PAGE='312',
 XY='(4900,4350)',
 ROT='0',
 VER='1',
 CDS_LIB='pure_quanta',
 CDS_PART_NAME='ME_DUMMY_SYMBOL-PCB_VENDOR_LOGA',
 PART_TYPE='MECH',
 MATERIAL='EMPTY',
 VALUE='PCB_VENDOR_LOGO_15X8',
 PRIM_FILE='./archive_libs/logical/me_dummy_symbol/chips/chips.prt';

PART_NAME
 ME22 'ME_DUMMY_SYMBOL-SNLABEL_27X6,MA':;

SECTION_NUMBER -1
 '@S9S_MB_2U_LIB.S9S_MB_2U(SCH_1):PAGE290_I73@PURE_QUANTA.ME_DUMMY_SYMBOL(CHIPS)':
 C_PATH='@s9s_mb_2u_lib.s9s_mb_2u(sch_1):page290_i73@pure_quanta.me_dummy_symbol~
(chips)',
 P_PATH='@s9s_mb_2u_lib.s9s_mb_2u(sch_1):page312_i73@pure_quanta.me_dummy_symbol~
(chips)',
 PATH='I73',
 DRAWING='@S9S_MB_2U_LIB.S9S_MB_2U(SCH_1):PAGE290',
 PIN_TEXT_VISIBLE='True',
 PIN_NAMES_ROTATE='True',
 PHYS_PAGE='312',
 XY='(3625,4300)',
 ROT='0',
 VER='1',
 LOCATION='ME22',
 CDS_LIB='pure_quanta',
 CDS_PART_NAME='ME_DUMMY_SYMBOL-SNLABEL_27X6,MA',
 PART_TYPE='MECH',
 MATERIAL='EMPTY',
 VALUE='SNLABEL_27X6',
 PRIM_FILE='./archive_libs/logical/me_dummy_symbol/chips/chips.prt';

PART_NAME
 ME27 'ME_DUMMY_SYMBOL-CBS_3X558-8,MEA':;

SECTION_NUMBER -1
 '@S9S_MB_2U_LIB.S9S_MB_2U(SCH_1):PAGE290_I74@PURE_QUANTA.ME_DUMMY_SYMBOL(CHIPS)':
 C_PATH='@s9s_mb_2u_lib.s9s_mb_2u(sch_1):page290_i74@pure_quanta.me_dummy_symbol~
(chips)',
 P_PATH='@s9s_mb_2u_lib.s9s_mb_2u(sch_1):page312_i74@pure_quanta.me_dummy_symbol~
(chips)',
 PATH='I74',
 DRAWING='@S9S_MB_2U_LIB.S9S_MB_2U(SCH_1):PAGE290',
 PIN_TEXT_VISIBLE='True',
 PIN_NAMES_ROTATE='True',
 PHYS_PAGE='312',
 XY='(-2800,1775)',
 ROT='0',
 VER='1',
 CDS_LIB='pure_quanta',
 CDS_PART_NAME='ME_DUMMY_SYMBOL-CBS_3X558-8,MEA',
 PART_TYPE='MECH',
 MATERIAL='EMPTY',
 VALUE='CBS_3X558-8',
 PRIM_FILE='./archive_libs/logical/me_dummy_symbol/chips/chips.prt';

PART_NAME
 ME28 'ME_DUMMY_SYMBOL-EFI BIOS LABELA':;

SECTION_NUMBER -1
 '@S9S_MB_2U_LIB.S9S_MB_2U(SCH_1):PAGE290_I75@PURE_QUANTA.ME_DUMMY_SYMBOL(CHIPS)':
 C_PATH='@s9s_mb_2u_lib.s9s_mb_2u(sch_1):page290_i75@pure_quanta.me_dummy_symbol~
(chips)',
 P_PATH='@s9s_mb_2u_lib.s9s_mb_2u(sch_1):page312_i75@pure_quanta.me_dummy_symbol~
(chips)',
 PATH='I75',
 DRAWING='@S9S_MB_2U_LIB.S9S_MB_2U(SCH_1):PAGE290',
 PIN_TEXT_VISIBLE='True',
 PIN_NAMES_ROTATE='True',
 PHYS_PAGE='312',
 XY='(-225,1800)',
 ROT='0',
 VER='1',
 CDS_LIB='pure_quanta',
 CDS_PART_NAME='ME_DUMMY_SYMBOL-EFI BIOS LABELA',
 PART_TYPE='MECH',
 MATERIAL='EMPTY',
 VALUE='EFI BIOS LABEL',
 PRIM_FILE='./archive_libs/logical/me_dummy_symbol/chips/chips.prt';

PART_NAME
 ME29 'ME_DUMMY_SYMBOL-SNLABEL_15X5,MA':;

SECTION_NUMBER -1
 '@S9S_MB_2U_LIB.S9S_MB_2U(SCH_1):PAGE290_I76@PURE_QUANTA.ME_DUMMY_SYMBOL(CHIPS)':
 C_PATH='@s9s_mb_2u_lib.s9s_mb_2u(sch_1):page290_i76@pure_quanta.me_dummy_symbol~
(chips)',
 P_PATH='@s9s_mb_2u_lib.s9s_mb_2u(sch_1):page312_i76@pure_quanta.me_dummy_symbol~
(chips)',
 PATH='I76',
 DRAWING='@S9S_MB_2U_LIB.S9S_MB_2U(SCH_1):PAGE290',
 PIN_TEXT_VISIBLE='True',
 PIN_NAMES_ROTATE='True',
 PHYS_PAGE='312',
 XY='(4250,4275)',
 ROT='0',
 VER='1',
 CDS_LIB='pure_quanta',
 CDS_PART_NAME='ME_DUMMY_SYMBOL-SNLABEL_15X5,MA',
 PART_TYPE='MECH',
 MATERIAL='EMPTY',
 VALUE='SNLABEL_15X5',
 PRIM_FILE='./archive_libs/logical/me_dummy_symbol/chips/chips.prt';

PART_NAME
 OSC1 'Q_OSC4P_SMLF-50MHZ,OSC,BF65000A':;

SECTION_NUMBER 1
 '@S9S_MB_2U_LIB.S9S_MB_2U(SCH_1):PAGE152_I76@PURE_QUANTA.Q_OSC4P(CHIPS)':
 C_PATH='@s9s_mb_2u_lib.s9s_mb_2u(sch_1):page152_i76@pure_quanta.q_osc4p(chips)',
 P_PATH='@s9s_mb_2u_lib.s9s_mb_2u(sch_1):page155_i76@pure_quanta.q_osc4p(chips)',
 PATH='I76',
 DRAWING='@S9S_MB_2U_LIB.S9S_MB_2U(SCH_1):PAGE152',
 PHYS_PAGE='155',
 XY='(-9450,2300)',
 ROT='0',
 VER='1',
 PACK_TYPE='SMLF',
 LOCATION='OSC1',
 CDS_LIB='pure_quanta',
 CDS_PART_NAME='Q_OSC4P_SMLF-50MHZ,OSC,BF65000A',
 MATERIAL='OSC',
 VALUE='50MHZ',
 PRIM_FILE='./archive_libs/logical/q_osc4p/chips/chips.prt';

PART_NAME
 OSC2 'Q_OSC4P_SMLF-25MHZ,OSC,BF62500A':;

SECTION_NUMBER 1
 '@S9S_MB_2U_LIB.S9S_MB_2U(SCH_1):PAGE313_I127@PURE_QUANTA.Q_OSC4P(CHIPS)':
 C_PATH='@s9s_mb_2u_lib.s9s_mb_2u(sch_1):page313_i127@pure_quanta.q_osc4p(chips)~
',
 P_PATH='@s9s_mb_2u_lib.s9s_mb_2u(sch_1):page214_i127@pure_quanta.q_osc4p(chips)~
',
 PATH='I127',
 DRAWING='@S9S_MB_2U_LIB.S9S_MB_2U(SCH_1):PAGE313',
 PHYS_PAGE='214',
 XY='(-2450,-3100)',
 ROT='0',
 VER='1',
 PACK_TYPE='SMLF',
 CDS_LIB='pure_quanta',
 CDS_PART_NAME='Q_OSC4P_SMLF-25MHZ,OSC,BF62500A',
 MATERIAL='OSC',
 VALUE='25MHZ',
 PRIM_FILE='./archive_libs/logical/q_osc4p/chips/chips.prt';

PART_NAME
 PC1 'Q_CAP_C0805-22UF,4V,20%,X6S,CHA':;

SECTION_NUMBER 1
 '@S9S_MB_2U_LIB.S9S_MB_2U(SCH_1):PAGE265_I29@PURE_QUANTA.Q_CAP(CHIPS)':
 C_PATH='@s9s_mb_2u_lib.s9s_mb_2u(sch_1):page265_i29@pure_quanta.q_cap(chips)',
 P_PATH='@s9s_mb_2u_lib.s9s_mb_2u(sch_1):page279_i29@pure_quanta.q_cap(chips)',
 PATH='I29',
 DRAWING='@S9S_MB_2U_LIB.S9S_MB_2U(SCH_1):PAGE265',
 PHYS_PAGE='279',
 XY='(-2275,1725)',
 ROT='0',
 VER='1',
 PACK_TYPE='C0805',
 LOCATION='PC1',
 CDS_LIB='pure_quanta',
 CDS_PART_NAME='Q_CAP_C0805-22UF,4V,20%,X6S,CHA',
 TOLERANCE='20%',
 MATERIAL='X6S',
 VOLTAGE='4V',
 VALUE='22UF',
 PRIM_FILE='./archive_libs/logical/q_cap/chips/chips.prt';

PART_NAME
 PC2 'Q_CAP_C0805-22UF,4V,20%,X6S,CHA':;

SECTION_NUMBER 1
 '@S9S_MB_2U_LIB.S9S_MB_2U(SCH_1):PAGE283_I30@PURE_QUANTA.Q_CAP(CHIPS)':
 C_PATH='@s9s_mb_2u_lib.s9s_mb_2u(sch_1):page283_i30@pure_quanta.q_cap(chips)',
 P_PATH='@s9s_mb_2u_lib.s9s_mb_2u(sch_1):page297_i30@pure_quanta.q_cap(chips)',
 PATH='I30',
 DRAWING='@S9S_MB_2U_LIB.S9S_MB_2U(SCH_1):PAGE283',
 PHYS_PAGE='297',
 XY='(-2200,3425)',
 ROT='0',
 VER='1',
 PACK_TYPE='C0805',
 LOCATION='PC2',
 CDS_LIB='pure_quanta',
 CDS_PART_NAME='Q_CAP_C0805-22UF,4V,20%,X6S,CHA',
 TOLERANCE='20%',
 MATERIAL='X6S',
 VOLTAGE='4V',
 VALUE='22UF',
 PRIM_FILE='./archive_libs/logical/q_cap/chips/chips.prt';

PART_NAME
 PC3 'Q_CAPP_THLF-270UF,16V,20%,OSCOA':;

SECTION_NUMBER 1
 '@S9S_MB_2U_LIB.S9S_MB_2U(SCH_1):PAGE245_I103@PURE_QUANTA.Q_CAPP(CHIPS)':
 C_PATH='@s9s_mb_2u_lib.s9s_mb_2u(sch_1):page245_i103@pure_quanta.q_capp(chips)',
 P_PATH='@s9s_mb_2u_lib.s9s_mb_2u(sch_1):page259_i103@pure_quanta.q_capp(chips)',
 PATH='I103',
 DRAWING='@S9S_MB_2U_LIB.S9S_MB_2U(SCH_1):PAGE245',
 PHYS_PAGE='259',
 XY='(-3975,850)',
 ROT='0',
 VER='1',
 PACK_TYPE='THLF',
 LOCATION='PC3',
 CDS_LIB='pure_quanta',
 CDS_PART_NAME='Q_CAPP_THLF-270UF,16V,20%,OSCOA',
 TOLERANCE='20%',
 MATERIAL='OSCON',
 VOLTAGE='16V',
 VALUE='270UF',
 PRIM_FILE='./archive_libs/logical/q_capp/chips/chips.prt';

PART_NAME
 PC8 'Q_CAP_C0603-4.7UF,16V,10%,X6S,A':;

SECTION_NUMBER 1
 '@S9S_MB_2U_LIB.S9S_MB_2U(SCH_1):PAGE245_I118@PURE_QUANTA.Q_CAP(CHIPS)':
 C_PATH='@s9s_mb_2u_lib.s9s_mb_2u(sch_1):page245_i118@pure_quanta.q_cap(chips)',
 P_PATH='@s9s_mb_2u_lib.s9s_mb_2u(sch_1):page259_i118@pure_quanta.q_cap(chips)',
 PATH='I118',
 DRAWING='@S9S_MB_2U_LIB.S9S_MB_2U(SCH_1):PAGE245',
 PHYS_PAGE='259',
 XY='(-900,475)',
 ROT='0',
 VER='1',
 PACK_TYPE='C0603',
 LOCATION='PC8',
 CDS_LIB='pure_quanta',
 CDS_PART_NAME='Q_CAP_C0603-4.7UF,16V,10%,X6S,A',
 TOLERANCE='10%',
 MATERIAL='X6S',
 VOLTAGE='16V',
 VALUE='4.7UF',
 PRIM_FILE='./archive_libs/logical/q_cap/chips/chips.prt';

PART_NAME
 PC16 'Q_CAPP_THLF-560UF,2.5V,20%,OSCA':;

SECTION_NUMBER 1
 '@S9S_MB_2U_LIB.S9S_MB_2U(SCH_1):PAGE253_I56@PURE_QUANTA.Q_CAPP(CHIPS)':
 C_PATH='@s9s_mb_2u_lib.s9s_mb_2u(sch_1):page253_i56@pure_quanta.q_capp(chips)',
 P_PATH='@s9s_mb_2u_lib.s9s_mb_2u(sch_1):page267_i56@pure_quanta.q_capp(chips)',
 PATH='I56',
 DRAWING='@S9S_MB_2U_LIB.S9S_MB_2U(SCH_1):PAGE253',
 PHYS_PAGE='267',
 XY='(1950,-525)',
 ROT='0',
 VER='1',
 PACK_TYPE='THLF',
 LOCATION='PC16',
 CDS_LIB='pure_quanta',
 CDS_PART_NAME='Q_CAPP_THLF-560UF,2.5V,20%,OSCA',
 TOLERANCE='20%',
 MATERIAL='OSCON',
 VOLTAGE='2.5V',
 VALUE='560UF',
 PRIM_FILE='./archive_libs/logical/q_capp/chips/chips.prt';

PART_NAME
 PC27 'Q_CAP_0402-3300PF,50V,10%,X7R,A':;

SECTION_NUMBER 1
 '@S9S_MB_2U_LIB.S9S_MB_2U(SCH_1):PAGE268_I25@PURE_QUANTA.Q_CAP(CHIPS)':
 C_PATH='@s9s_mb_2u_lib.s9s_mb_2u(sch_1):page268_i25@pure_quanta.q_cap(chips)',
 P_PATH='@s9s_mb_2u_lib.s9s_mb_2u(sch_1):page282_i25@pure_quanta.q_cap(chips)',
 PATH='I25',
 DRAWING='@S9S_MB_2U_LIB.S9S_MB_2U(SCH_1):PAGE268',
 PHYS_PAGE='282',
 XY='(-5825,8675)',
 ROT='0',
 VER='1',
 PACK_TYPE='0402',
 LOCATION='PC27',
 CDS_LIB='pure_quanta',
 CDS_PART_NAME='Q_CAP_0402-3300PF,50V,10%,X7R,A',
 TOLERANCE='10%',
 MATERIAL='X7R',
 VOLTAGE='50V',
 VALUE='3300PF',
 PRIM_FILE='./archive_libs/logical/q_cap/chips/chips.prt';

PART_NAME
 PC28 'Q_CAP_0402-3300PF,50V,10%,X7R,A':;

SECTION_NUMBER 1
 '@S9S_MB_2U_LIB.S9S_MB_2U(SCH_1):PAGE286_I23@PURE_QUANTA.Q_CAP(CHIPS)':
 C_PATH='@s9s_mb_2u_lib.s9s_mb_2u(sch_1):page286_i23@pure_quanta.q_cap(chips)',
 P_PATH='@s9s_mb_2u_lib.s9s_mb_2u(sch_1):page300_i23@pure_quanta.q_cap(chips)',
 PATH='I23',
 DRAWING='@S9S_MB_2U_LIB.S9S_MB_2U(SCH_1):PAGE286',
 PHYS_PAGE='300',
 XY='(6025,6050)',
 ROT='0',
 VER='1',
 PACK_TYPE='0402',
 LOCATION='PC28',
 CDS_LIB='pure_quanta',
 CDS_PART_NAME='Q_CAP_0402-3300PF,50V,10%,X7R,A',
 TOLERANCE='10%',
 MATERIAL='X7R',
 VOLTAGE='50V',
 VALUE='3300PF',
 PRIM_FILE='./archive_libs/logical/q_cap/chips/chips.prt';

PART_NAME
 PC71 'Q_CAP_C0805-22UF,16V,20%,X6S,CA':;

SECTION_NUMBER 1
 '@S9S_MB_2U_LIB.S9S_MB_2U(SCH_1):PAGE245_I114@PURE_QUANTA.Q_CAP(CHIPS)':
 C_PATH='@s9s_mb_2u_lib.s9s_mb_2u(sch_1):page245_i114@pure_quanta.q_cap(chips)',
 P_PATH='@s9s_mb_2u_lib.s9s_mb_2u(sch_1):page259_i114@pure_quanta.q_cap(chips)',
 PATH='I114',
 DRAWING='@S9S_MB_2U_LIB.S9S_MB_2U(SCH_1):PAGE245',
 PHYS_PAGE='259',
 XY='(-2050,850)',
 ROT='0',
 VER='1',
 PACK_TYPE='C0805',
 LOCATION='PC71',
 CDS_LIB='pure_quanta',
 CDS_PART_NAME='Q_CAP_C0805-22UF,16V,20%,X6S,CA',
 TOLERANCE='20%',
 MATERIAL='X6S',
 VOLTAGE='16V',
 VALUE='22UF',
 PRIM_FILE='./archive_libs/logical/q_cap/chips/chips.prt';

PART_NAME
 PC83 'Q_CAPP_THLF-560UF,2.5V,20%,OSCA':;

SECTION_NUMBER 1
 '@S9S_MB_2U_LIB.S9S_MB_2U(SCH_1):PAGE271_I56@PURE_QUANTA.Q_CAPP(CHIPS)':
 C_PATH='@s9s_mb_2u_lib.s9s_mb_2u(sch_1):page271_i56@pure_quanta.q_capp(chips)',
 P_PATH='@s9s_mb_2u_lib.s9s_mb_2u(sch_1):page285_i56@pure_quanta.q_capp(chips)',
 PATH='I56',
 DRAWING='@S9S_MB_2U_LIB.S9S_MB_2U(SCH_1):PAGE271',
 PHYS_PAGE='285',
 XY='(2025,-50)',
 ROT='0',
 VER='1',
 PACK_TYPE='THLF',
 LOCATION='PC83',
 CDS_LIB='pure_quanta',
 CDS_PART_NAME='Q_CAPP_THLF-560UF,2.5V,20%,OSCA',
 TOLERANCE='20%',
 MATERIAL='OSCON',
 VOLTAGE='2.5V',
 VALUE='560UF',
 PRIM_FILE='./archive_libs/logical/q_capp/chips/chips.prt';

PART_NAME
 PC100 'Q_CAP_0402-470PF,50V,10%,X7R,TA':;

SECTION_NUMBER 1
 '@S9S_MB_2U_LIB.S9S_MB_2U(SCH_1):PAGE252_I116@PURE_QUANTA.Q_CAP(CHIPS)':
 C_PATH='@s9s_mb_2u_lib.s9s_mb_2u(sch_1):page252_i116@pure_quanta.q_cap(chips)',
 P_PATH='@s9s_mb_2u_lib.s9s_mb_2u(sch_1):page266_i116@pure_quanta.q_cap(chips)',
 PATH='I116',
 DRAWING='@S9S_MB_2U_LIB.S9S_MB_2U(SCH_1):PAGE252',
 PHYS_PAGE='266',
 XY='(-125,1450)',
 ROT='0',
 VER='1',
 PACK_TYPE='0402',
 LOCATION='PC100',
 CDS_LIB='pure_quanta',
 CDS_PART_NAME='Q_CAP_0402-470PF,50V,10%,X7R,TA',
 TOLERANCE='10%',
 MATERIAL='X7R',
 VOLTAGE='50V',
 VALUE='470PF',
 PRIM_FILE='./archive_libs/logical/q_cap/chips/chips.prt';

PART_NAME
 PC101 'Q_CAP_0402-470PF,50V,10%,X7R,TA':;

SECTION_NUMBER 1
 '@S9S_MB_2U_LIB.S9S_MB_2U(SCH_1):PAGE270_I92@PURE_QUANTA.Q_CAP(CHIPS)':
 C_PATH='@s9s_mb_2u_lib.s9s_mb_2u(sch_1):page270_i92@pure_quanta.q_cap(chips)',
 P_PATH='@s9s_mb_2u_lib.s9s_mb_2u(sch_1):page284_i92@pure_quanta.q_cap(chips)',
 PATH='I92',
 DRAWING='@S9S_MB_2U_LIB.S9S_MB_2U(SCH_1):PAGE270',
 PHYS_PAGE='284',
 XY='(2875,-2075)',
 ROT='0',
 VER='1',
 PACK_TYPE='0402',
 LOCATION='PC101',
 CDS_LIB='pure_quanta',
 CDS_PART_NAME='Q_CAP_0402-470PF,50V,10%,X7R,TA',
 TOLERANCE='10%',
 MATERIAL='X7R',
 VOLTAGE='50V',
 VALUE='470PF',
 PRIM_FILE='./archive_libs/logical/q_cap/chips/chips.prt';

PART_NAME
 PC113 'Q_CAP_C0402-1UF,25V,10%,X6S,CHA':;

SECTION_NUMBER 1
 '@S9S_MB_2U_LIB.S9S_MB_2U(SCH_1):PAGE248_I2@PURE_QUANTA.Q_CAP(CHIPS)':
 C_PATH='@s9s_mb_2u_lib.s9s_mb_2u(sch_1):page248_i2@pure_quanta.q_cap(chips)',
 P_PATH='@s9s_mb_2u_lib.s9s_mb_2u(sch_1):page262_i2@pure_quanta.q_cap(chips)',
 PATH='I2',
 DRAWING='@S9S_MB_2U_LIB.S9S_MB_2U(SCH_1):PAGE248',
 BOM_COST='VR_PCH',
 PHYS_PAGE='262',
 XY='(-3150,-1425)',
 ROT='0',
 VER='1',
 PACK_TYPE='C0402',
 LOCATION='PC113',
 SEC='1',
 CDS_LIB='pure_quanta',
 CDS_PART_NAME='Q_CAP_C0402-1UF,25V,10%,X6S,CHA',
 SEC_TYPE='C0402',
 TOLERANCE='10%',
 MATERIAL='X6S',
 VOLTAGE='25V',
 VALUE='1UF',
 PRIM_FILE='./archive_libs/logical/q_cap/chips/chips.prt';

PART_NAME
 PC117 'Q_CAPP_SMLF-330UF,2V,35%,SPCAPA':;

SECTION_NUMBER 1
 '@S9S_MB_2U_LIB.S9S_MB_2U(SCH_1):PAGE248_I40@PURE_QUANTA.Q_CAPP(CHIPS)':
 C_PATH='@s9s_mb_2u_lib.s9s_mb_2u(sch_1):page248_i40@pure_quanta.q_capp(chips)',
 P_PATH='@s9s_mb_2u_lib.s9s_mb_2u(sch_1):page262_i40@pure_quanta.q_capp(chips)',
 PATH='I40',
 DRAWING='@S9S_MB_2U_LIB.S9S_MB_2U(SCH_1):PAGE248',
 PHYS_PAGE='262',
 XY='(2875,-2500)',
 ROT='0',
 VER='1',
 PACK_TYPE='SMLF',
 LOCATION='PC117',
 CDS_LIB='pure_quanta',
 CDS_PART_NAME='Q_CAPP_SMLF-330UF,2V,35%,SPCAPA',
 TOLERANCE='35%',
 MATERIAL='SPCAP',
 VOLTAGE='2V',
 VALUE='330UF',
 PRIM_FILE='./archive_libs/logical/q_capp/chips/chips.prt';

PART_NAME
 PC175 'Q_CAP_C0402-2.2UF,10V,10%,X6S,A':;

SECTION_NUMBER 1
 '@S9S_MB_2U_LIB.S9S_MB_2U(SCH_1):PAGE262_I12@PURE_QUANTA.Q_CAP(CHIPS)':
 C_PATH='@s9s_mb_2u_lib.s9s_mb_2u(sch_1):page262_i12@pure_quanta.q_cap(chips)',
 P_PATH='@s9s_mb_2u_lib.s9s_mb_2u(sch_1):page276_i12@pure_quanta.q_cap(chips)',
 PATH='I12',
 DRAWING='@S9S_MB_2U_LIB.S9S_MB_2U(SCH_1):PAGE262',
 PHYS_PAGE='276',
 XY='(-9600,4000)',
 ROT='0',
 VER='1',
 PACK_TYPE='C0402',
 LOCATION='PC175',
 CDS_LIB='pure_quanta',
 CDS_PART_NAME='Q_CAP_C0402-2.2UF,10V,10%,X6S,A',
 TOLERANCE='10%',
 MATERIAL='X6S',
 VOLTAGE='10V',
 VALUE='2.2UF',
 PRIM_FILE='./archive_libs/logical/q_cap/chips/chips.prt';

PART_NAME
 PC176 'Q_CAP_0402-3300PF,50V,10%,X7R,A':;

SECTION_NUMBER 1
 '@S9S_MB_2U_LIB.S9S_MB_2U(SCH_1):PAGE262_I24@PURE_QUANTA.Q_CAP(CHIPS)':
 C_PATH='@s9s_mb_2u_lib.s9s_mb_2u(sch_1):page262_i24@pure_quanta.q_cap(chips)',
 P_PATH='@s9s_mb_2u_lib.s9s_mb_2u(sch_1):page276_i24@pure_quanta.q_cap(chips)',
 PATH='I24',
 DRAWING='@S9S_MB_2U_LIB.S9S_MB_2U(SCH_1):PAGE262',
 PHYS_PAGE='276',
 XY='(-7275,4450)',
 ROT='0',
 VER='1',
 PACK_TYPE='0402',
 LOCATION='PC176',
 CDS_LIB='pure_quanta',
 CDS_PART_NAME='Q_CAP_0402-3300PF,50V,10%,X7R,A',
 TOLERANCE='10%',
 MATERIAL='X7R',
 VOLTAGE='50V',
 VALUE='3300PF',
 PRIM_FILE='./archive_libs/logical/q_cap/chips/chips.prt';

PART_NAME
 PC177 'Q_CAP_C0402-1UF,16V,10%,X6S,CHA':;

SECTION_NUMBER 1
 '@S9S_MB_2U_LIB.S9S_MB_2U(SCH_1):PAGE262_I25@PURE_QUANTA.Q_CAP(CHIPS)':
 C_PATH='@s9s_mb_2u_lib.s9s_mb_2u(sch_1):page262_i25@pure_quanta.q_cap(chips)',
 P_PATH='@s9s_mb_2u_lib.s9s_mb_2u(sch_1):page276_i25@pure_quanta.q_cap(chips)',
 PATH='I25',
 DRAWING='@S9S_MB_2U_LIB.S9S_MB_2U(SCH_1):PAGE262',
 PHYS_PAGE='276',
 XY='(-6875,4450)',
 ROT='0',
 VER='1',
 PACK_TYPE='C0402',
 LOCATION='PC177',
 CDS_LIB='pure_quanta',
 CDS_PART_NAME='Q_CAP_C0402-1UF,16V,10%,X6S,CHA',
 TOLERANCE='10%',
 MATERIAL='X6S',
 VOLTAGE='16V',
 VALUE='1UF',
 PRIM_FILE='./archive_libs/logical/q_cap/chips/chips.prt';

PART_NAME
 PC178 'Q_CAP_C0402-100NF,50V,10%,X7R,A':;

SECTION_NUMBER 1
 '@S9S_MB_2U_LIB.S9S_MB_2U(SCH_1):PAGE262_I20@PURE_QUANTA.Q_CAP(CHIPS)':
 C_PATH='@s9s_mb_2u_lib.s9s_mb_2u(sch_1):page262_i20@pure_quanta.q_cap(chips)',
 P_PATH='@s9s_mb_2u_lib.s9s_mb_2u(sch_1):page276_i20@pure_quanta.q_cap(chips)',
 PATH='I20',
 DRAWING='@S9S_MB_2U_LIB.S9S_MB_2U(SCH_1):PAGE262',
 PHYS_PAGE='276',
 XY='(-5950,3825)',
 ROT='2',
 VER='1',
 PACK_TYPE='C0402',
 LOCATION='PC178',
 CDS_LIB='pure_quanta',
 CDS_PART_NAME='Q_CAP_C0402-100NF,50V,10%,X7R,A',
 TOLERANCE='10%',
 MATERIAL='X7R',
 VOLTAGE='50V',
 VALUE='100NF',
 PRIM_FILE='./archive_libs/logical/q_cap/chips/chips.prt';

PART_NAME
 PC179 'Q_CAP_C0805-22UF,16V,20%,X6S,CA':;

SECTION_NUMBER 1
 '@S9S_MB_2U_LIB.S9S_MB_2U(SCH_1):PAGE262_I26@PURE_QUANTA.Q_CAP(CHIPS)':
 C_PATH='@s9s_mb_2u_lib.s9s_mb_2u(sch_1):page262_i26@pure_quanta.q_cap(chips)',
 P_PATH='@s9s_mb_2u_lib.s9s_mb_2u(sch_1):page276_i26@pure_quanta.q_cap(chips)',
 PATH='I26',
 DRAWING='@S9S_MB_2U_LIB.S9S_MB_2U(SCH_1):PAGE262',
 PHYS_PAGE='276',
 XY='(-6475,4450)',
 ROT='0',
 VER='1',
 PACK_TYPE='C0805',
 LOCATION='PC179',
 CDS_LIB='pure_quanta',
 CDS_PART_NAME='Q_CAP_C0805-22UF,16V,20%,X6S,CA',
 TOLERANCE='20%',
 MATERIAL='X6S',
 VOLTAGE='16V',
 VALUE='22UF',
 PRIM_FILE='./archive_libs/logical/q_cap/chips/chips.prt';

PART_NAME
 PC180 'Q_CAP_C0805-22UF,16V,20%,X6S,CA':;

SECTION_NUMBER 1
 '@S9S_MB_2U_LIB.S9S_MB_2U(SCH_1):PAGE262_I27@PURE_QUANTA.Q_CAP(CHIPS)':
 C_PATH='@s9s_mb_2u_lib.s9s_mb_2u(sch_1):page262_i27@pure_quanta.q_cap(chips)',
 P_PATH='@s9s_mb_2u_lib.s9s_mb_2u(sch_1):page276_i27@pure_quanta.q_cap(chips)',
 PATH='I27',
 DRAWING='@S9S_MB_2U_LIB.S9S_MB_2U(SCH_1):PAGE262',
 PHYS_PAGE='276',
 XY='(-6075,4450)',
 ROT='0',
 VER='1',
 PACK_TYPE='C0805',
 LOCATION='PC180',
 CDS_LIB='pure_quanta',
 CDS_PART_NAME='Q_CAP_C0805-22UF,16V,20%,X6S,CA',
 TOLERANCE='20%',
 MATERIAL='X6S',
 VOLTAGE='16V',
 VALUE='22UF',
 PRIM_FILE='./archive_libs/logical/q_cap/chips/chips.prt';

PART_NAME
 PC181 'Q_CAP_C0402-100NF,50V,10%,X7R,A':;

SECTION_NUMBER 1
 '@S9S_MB_2U_LIB.S9S_MB_2U(SCH_1):PAGE262_I28@PURE_QUANTA.Q_CAP(CHIPS)':
 C_PATH='@s9s_mb_2u_lib.s9s_mb_2u(sch_1):page262_i28@pure_quanta.q_cap(chips)',
 P_PATH='@s9s_mb_2u_lib.s9s_mb_2u(sch_1):page276_i28@pure_quanta.q_cap(chips)',
 PATH='I28',
 DRAWING='@S9S_MB_2U_LIB.S9S_MB_2U(SCH_1):PAGE262',
 PHYS_PAGE='276',
 XY='(-5200,3350)',
 ROT='0',
 VER='1',
 PACK_TYPE='C0402',
 LOCATION='PC181',
 CDS_LIB='pure_quanta',
 CDS_PART_NAME='Q_CAP_C0402-100NF,50V,10%,X7R,A',
 TOLERANCE='10%',
 MATERIAL='X7R',
 VOLTAGE='50V',
 VALUE='100NF',
 PRIM_FILE='./archive_libs/logical/q_cap/chips/chips.prt';

PART_NAME
 PC184 'Q_CAP_C0805-22UF,4V,20%,X6S,CHA':;

SECTION_NUMBER 1
 '@S9S_MB_2U_LIB.S9S_MB_2U(SCH_1):PAGE262_I31@PURE_QUANTA.Q_CAP(CHIPS)':
 C_PATH='@s9s_mb_2u_lib.s9s_mb_2u(sch_1):page262_i31@pure_quanta.q_cap(chips)',
 P_PATH='@s9s_mb_2u_lib.s9s_mb_2u(sch_1):page276_i31@pure_quanta.q_cap(chips)',
 PATH='I31',
 DRAWING='@S9S_MB_2U_LIB.S9S_MB_2U(SCH_1):PAGE262',
 PHYS_PAGE='276',
 XY='(-4800,3350)',
 ROT='0',
 VER='1',
 PACK_TYPE='C0805',
 LOCATION='PC184',
 CDS_LIB='pure_quanta',
 CDS_PART_NAME='Q_CAP_C0805-22UF,4V,20%,X6S,CHA',
 TOLERANCE='20%',
 MATERIAL='X6S',
 VOLTAGE='4V',
 VALUE='22UF',
 PRIM_FILE='./archive_libs/logical/q_cap/chips/chips.prt';

PART_NAME
 PC186 'Q_CAP_C0805-22UF,4V,20%,X6S,CHA':;

SECTION_NUMBER 1
 '@S9S_MB_2U_LIB.S9S_MB_2U(SCH_1):PAGE262_I32@PURE_QUANTA.Q_CAP(CHIPS)':
 C_PATH='@s9s_mb_2u_lib.s9s_mb_2u(sch_1):page262_i32@pure_quanta.q_cap(chips)',
 P_PATH='@s9s_mb_2u_lib.s9s_mb_2u(sch_1):page276_i32@pure_quanta.q_cap(chips)',
 PATH='I32',
 DRAWING='@S9S_MB_2U_LIB.S9S_MB_2U(SCH_1):PAGE262',
 PHYS_PAGE='276',
 XY='(-4375,3350)',
 ROT='0',
 VER='1',
 PACK_TYPE='C0805',
 LOCATION='PC186',
 CDS_LIB='pure_quanta',
 CDS_PART_NAME='Q_CAP_C0805-22UF,4V,20%,X6S,CHA',
 TOLERANCE='20%',
 MATERIAL='X6S',
 VOLTAGE='4V',
 VALUE='22UF',
 PRIM_FILE='./archive_libs/logical/q_cap/chips/chips.prt';

PART_NAME
 PC187 'Q_CAP_C0402-2.2UF,10V,10%,X6S,A':;

SECTION_NUMBER 1
 '@S9S_MB_2U_LIB.S9S_MB_2U(SCH_1):PAGE261_I24@PURE_QUANTA.Q_CAP(CHIPS)':
 C_PATH='@s9s_mb_2u_lib.s9s_mb_2u(sch_1):page261_i24@pure_quanta.q_cap(chips)',
 P_PATH='@s9s_mb_2u_lib.s9s_mb_2u(sch_1):page275_i24@pure_quanta.q_cap(chips)',
 PATH='I24',
 DRAWING='@S9S_MB_2U_LIB.S9S_MB_2U(SCH_1):PAGE261',
 PHYS_PAGE='275',
 XY='(-10400,5225)',
 ROT='0',
 VER='1',
 PACK_TYPE='C0402',
 LOCATION='PC187',
 CDS_LIB='pure_quanta',
 CDS_PART_NAME='Q_CAP_C0402-2.2UF,10V,10%,X6S,A',
 TOLERANCE='10%',
 MATERIAL='X6S',
 VOLTAGE='10V',
 VALUE='2.2UF',
 PRIM_FILE='./archive_libs/logical/q_cap/chips/chips.prt';

PART_NAME
 PC188 'Q_CAP_C0402-2.2UF,10V,10%,X6S,A':;

SECTION_NUMBER 1
 '@S9S_MB_2U_LIB.S9S_MB_2U(SCH_1):PAGE261_I13@PURE_QUANTA.Q_CAP(CHIPS)':
 C_PATH='@s9s_mb_2u_lib.s9s_mb_2u(sch_1):page261_i13@pure_quanta.q_cap(chips)',
 P_PATH='@s9s_mb_2u_lib.s9s_mb_2u(sch_1):page275_i13@pure_quanta.q_cap(chips)',
 PATH='I13',
 DRAWING='@S9S_MB_2U_LIB.S9S_MB_2U(SCH_1):PAGE261',
 PHYS_PAGE='275',
 XY='(-10400,2425)',
 ROT='0',
 VER='1',
 PACK_TYPE='C0402',
 LOCATION='PC188',
 CDS_LIB='pure_quanta',
 CDS_PART_NAME='Q_CAP_C0402-2.2UF,10V,10%,X6S,A',
 TOLERANCE='10%',
 MATERIAL='X6S',
 VOLTAGE='10V',
 VALUE='2.2UF',
 PRIM_FILE='./archive_libs/logical/q_cap/chips/chips.prt';

PART_NAME
 PC189 'Q_CAPP_SMLF-330UF,2.5V,+10/-35A':;

SECTION_NUMBER 1
 '@S9S_MB_2U_LIB.S9S_MB_2U(SCH_1):PAGE271_I62@PURE_QUANTA.Q_CAPP(CHIPS)':
 C_PATH='@s9s_mb_2u_lib.s9s_mb_2u(sch_1):page271_i62@pure_quanta.q_capp(chips)',
 P_PATH='@s9s_mb_2u_lib.s9s_mb_2u(sch_1):page285_i62@pure_quanta.q_capp(chips)',
 PATH='I62',
 DRAWING='@S9S_MB_2U_LIB.S9S_MB_2U(SCH_1):PAGE271',
 PHYS_PAGE='285',
 XY='(3100,-925)',
 ROT='0',
 VER='1',
 PACK_TYPE='SMLF',
 LOCATION='PC189',
 CDS_LIB='pure_quanta',
 CDS_PART_NAME='Q_CAPP_SMLF-330UF,2.5V,+10/-35A',
 TOLERANCE='+10/-35%',
 MATERIAL='EMPTY',
 VOLTAGE='2.5V',
 VALUE='330UF',
 PRIM_FILE='./archive_libs/logical/q_capp/chips/chips.prt';

PART_NAME
 PC189_P0_1 'Q_CAP_0402-3300PF,50V,10%,X7R,A':;

SECTION_NUMBER 1
 '@S9S_MB_2U_LIB.S9S_MB_2U(SCH_1):PAGE261_I45@PURE_QUANTA.Q_CAP(CHIPS)':
 C_PATH='@s9s_mb_2u_lib.s9s_mb_2u(sch_1):page261_i45@pure_quanta.q_cap(chips)',
 P_PATH='@s9s_mb_2u_lib.s9s_mb_2u(sch_1):page275_i45@pure_quanta.q_cap(chips)',
 PATH='I45',
 DRAWING='@S9S_MB_2U_LIB.S9S_MB_2U(SCH_1):PAGE261',
 PHYS_PAGE='275',
 XY='(-8075,5675)',
 ROT='0',
 VER='1',
 PACK_TYPE='0402',
 LOCATION='PC189_P0_1',
 CDS_LIB='pure_quanta',
 CDS_PART_NAME='Q_CAP_0402-3300PF,50V,10%,X7R,A',
 TOLERANCE='10%',
 MATERIAL='X7R',
 VOLTAGE='50V',
 VALUE='3300PF',
 PRIM_FILE='./archive_libs/logical/q_cap/chips/chips.prt';

PART_NAME
 PC190 'Q_CAP_C0402-1UF,25V,10%,X6S,CHA':
 ROOM='NIC1_P3V3_BOM1';

SECTION_NUMBER 1
 '@S9S_MB_2U_LIB.S9S_MB_2U(SCH_1):PAGE131_I91@PURE_QUANTA.Q_CAP(CHIPS)':
 C_PATH='@s9s_mb_2u_lib.s9s_mb_2u(sch_1):page131_i91@pure_quanta.q_cap(chips)',
 P_PATH='@s9s_mb_2u_lib.s9s_mb_2u(sch_1):page162_i91@pure_quanta.q_cap(chips)',
 PATH='I91',
 DRAWING='@S9S_MB_2U_LIB.S9S_MB_2U(SCH_1):PAGE131',
 PHYS_PAGE='162',
 XY='(275,2100)',
 ROT='0',
 VER='1',
 PACK_TYPE='C0402',
 CDS_LIB='pure_quanta',
 CDS_PART_NAME='Q_CAP_C0402-1UF,25V,10%,X6S,CHA',
 TOLERANCE='10%',
 MATERIAL='X6S',
 VOLTAGE='25V',
 ROOM='NIC1_P3V3_BOM1',
 VALUE='1UF',
 PRIM_FILE='./archive_libs/logical/q_cap/chips/chips.prt';

PART_NAME
 PC190_P0_2 'Q_CAP_0402-3300PF,50V,10%,X7R,A':;

SECTION_NUMBER 1
 '@S9S_MB_2U_LIB.S9S_MB_2U(SCH_1):PAGE261_I32@PURE_QUANTA.Q_CAP(CHIPS)':
 C_PATH='@s9s_mb_2u_lib.s9s_mb_2u(sch_1):page261_i32@pure_quanta.q_cap(chips)',
 P_PATH='@s9s_mb_2u_lib.s9s_mb_2u(sch_1):page275_i32@pure_quanta.q_cap(chips)',
 PATH='I32',
 DRAWING='@S9S_MB_2U_LIB.S9S_MB_2U(SCH_1):PAGE261',
 PHYS_PAGE='275',
 XY='(-8075,2875)',
 ROT='0',
 VER='1',
 PACK_TYPE='0402',
 LOCATION='PC190_P0_2',
 CDS_LIB='pure_quanta',
 CDS_PART_NAME='Q_CAP_0402-3300PF,50V,10%,X7R,A',
 TOLERANCE='10%',
 MATERIAL='X7R',
 VOLTAGE='50V',
 VALUE='3300PF',
 PRIM_FILE='./archive_libs/logical/q_cap/chips/chips.prt';

PART_NAME
 PC191_P0_1 'Q_CAP_C0402-1UF,16V,10%,X6S,CHA':;

SECTION_NUMBER 1
 '@S9S_MB_2U_LIB.S9S_MB_2U(SCH_1):PAGE261_I48@PURE_QUANTA.Q_CAP(CHIPS)':
 C_PATH='@s9s_mb_2u_lib.s9s_mb_2u(sch_1):page261_i48@pure_quanta.q_cap(chips)',
 P_PATH='@s9s_mb_2u_lib.s9s_mb_2u(sch_1):page275_i48@pure_quanta.q_cap(chips)',
 PATH='I48',
 DRAWING='@S9S_MB_2U_LIB.S9S_MB_2U(SCH_1):PAGE261',
 PHYS_PAGE='275',
 XY='(-7675,5675)',
 ROT='0',
 VER='1',
 PACK_TYPE='C0402',
 LOCATION='PC191_P0_1',
 CDS_LIB='pure_quanta',
 CDS_PART_NAME='Q_CAP_C0402-1UF,16V,10%,X6S,CHA',
 TOLERANCE='10%',
 MATERIAL='X6S',
 VOLTAGE='16V',
 VALUE='1UF',
 PRIM_FILE='./archive_libs/logical/q_cap/chips/chips.prt';

PART_NAME
 PC192_P0_2 'Q_CAP_C0402-1UF,16V,10%,X6S,CHA':;

SECTION_NUMBER 1
 '@S9S_MB_2U_LIB.S9S_MB_2U(SCH_1):PAGE261_I35@PURE_QUANTA.Q_CAP(CHIPS)':
 C_PATH='@s9s_mb_2u_lib.s9s_mb_2u(sch_1):page261_i35@pure_quanta.q_cap(chips)',
 P_PATH='@s9s_mb_2u_lib.s9s_mb_2u(sch_1):page275_i35@pure_quanta.q_cap(chips)',
 PATH='I35',
 DRAWING='@S9S_MB_2U_LIB.S9S_MB_2U(SCH_1):PAGE261',
 PHYS_PAGE='275',
 XY='(-7675,2875)',
 ROT='0',
 VER='1',
 PACK_TYPE='C0402',
 LOCATION='PC192_P0_2',
 CDS_LIB='pure_quanta',
 CDS_PART_NAME='Q_CAP_C0402-1UF,16V,10%,X6S,CHA',
 TOLERANCE='10%',
 MATERIAL='X6S',
 VOLTAGE='16V',
 VALUE='1UF',
 PRIM_FILE='./archive_libs/logical/q_cap/chips/chips.prt';

PART_NAME
 PC193 'Q_CAP_C0402-100NF,50V,10%,X7R,A':;

SECTION_NUMBER 1
 '@S9S_MB_2U_LIB.S9S_MB_2U(SCH_1):PAGE261_I51@PURE_QUANTA.Q_CAP(CHIPS)':
 C_PATH='@s9s_mb_2u_lib.s9s_mb_2u(sch_1):page261_i51@pure_quanta.q_cap(chips)',
 P_PATH='@s9s_mb_2u_lib.s9s_mb_2u(sch_1):page275_i51@pure_quanta.q_cap(chips)',
 PATH='I51',
 DRAWING='@S9S_MB_2U_LIB.S9S_MB_2U(SCH_1):PAGE261',
 PHYS_PAGE='275',
 XY='(-6700,5050)',
 ROT='2',
 VER='1',
 PACK_TYPE='C0402',
 LOCATION='PC193',
 CDS_LIB='pure_quanta',
 CDS_PART_NAME='Q_CAP_C0402-100NF,50V,10%,X7R,A',
 TOLERANCE='10%',
 MATERIAL='X7R',
 VOLTAGE='50V',
 VALUE='100NF',
 PRIM_FILE='./archive_libs/logical/q_cap/chips/chips.prt';

PART_NAME
 PC194 'Q_CAP_C0402-100NF,50V,10%,X7R,A':;

SECTION_NUMBER 1
 '@S9S_MB_2U_LIB.S9S_MB_2U(SCH_1):PAGE261_I38@PURE_QUANTA.Q_CAP(CHIPS)':
 C_PATH='@s9s_mb_2u_lib.s9s_mb_2u(sch_1):page261_i38@pure_quanta.q_cap(chips)',
 P_PATH='@s9s_mb_2u_lib.s9s_mb_2u(sch_1):page275_i38@pure_quanta.q_cap(chips)',
 PATH='I38',
 DRAWING='@S9S_MB_2U_LIB.S9S_MB_2U(SCH_1):PAGE261',
 PHYS_PAGE='275',
 XY='(-6700,2250)',
 ROT='2',
 VER='1',
 PACK_TYPE='C0402',
 LOCATION='PC194',
 CDS_LIB='pure_quanta',
 CDS_PART_NAME='Q_CAP_C0402-100NF,50V,10%,X7R,A',
 TOLERANCE='10%',
 MATERIAL='X7R',
 VOLTAGE='50V',
 VALUE='100NF',
 PRIM_FILE='./archive_libs/logical/q_cap/chips/chips.prt';

PART_NAME
 PC195_P0_1 'Q_CAP_C0805-22UF,16V,20%,X6S,CA':;

SECTION_NUMBER 1
 '@S9S_MB_2U_LIB.S9S_MB_2U(SCH_1):PAGE261_I49@PURE_QUANTA.Q_CAP(CHIPS)':
 C_PATH='@s9s_mb_2u_lib.s9s_mb_2u(sch_1):page261_i49@pure_quanta.q_cap(chips)',
 P_PATH='@s9s_mb_2u_lib.s9s_mb_2u(sch_1):page275_i49@pure_quanta.q_cap(chips)',
 PATH='I49',
 DRAWING='@S9S_MB_2U_LIB.S9S_MB_2U(SCH_1):PAGE261',
 PHYS_PAGE='275',
 XY='(-7275,5675)',
 ROT='0',
 VER='1',
 PACK_TYPE='C0805',
 LOCATION='PC195_P0_1',
 CDS_LIB='pure_quanta',
 CDS_PART_NAME='Q_CAP_C0805-22UF,16V,20%,X6S,CA',
 TOLERANCE='20%',
 MATERIAL='X6S',
 VOLTAGE='16V',
 VALUE='22UF',
 PRIM_FILE='./archive_libs/logical/q_cap/chips/chips.prt';

PART_NAME
 PC196_P0_2 'Q_CAP_C0805-22UF,16V,20%,X6S,CA':;

SECTION_NUMBER 1
 '@S9S_MB_2U_LIB.S9S_MB_2U(SCH_1):PAGE261_I36@PURE_QUANTA.Q_CAP(CHIPS)':
 C_PATH='@s9s_mb_2u_lib.s9s_mb_2u(sch_1):page261_i36@pure_quanta.q_cap(chips)',
 P_PATH='@s9s_mb_2u_lib.s9s_mb_2u(sch_1):page275_i36@pure_quanta.q_cap(chips)',
 PATH='I36',
 DRAWING='@S9S_MB_2U_LIB.S9S_MB_2U(SCH_1):PAGE261',
 PHYS_PAGE='275',
 XY='(-7275,2875)',
 ROT='0',
 VER='1',
 PACK_TYPE='C0805',
 LOCATION='PC196_P0_2',
 CDS_LIB='pure_quanta',
 CDS_PART_NAME='Q_CAP_C0805-22UF,16V,20%,X6S,CA',
 TOLERANCE='20%',
 MATERIAL='X6S',
 VOLTAGE='16V',
 VALUE='22UF',
 PRIM_FILE='./archive_libs/logical/q_cap/chips/chips.prt';

PART_NAME
 PC197_P0_1 'Q_CAP_C0805-22UF,16V,20%,X6S,CA':;

SECTION_NUMBER 1
 '@S9S_MB_2U_LIB.S9S_MB_2U(SCH_1):PAGE261_I50@PURE_QUANTA.Q_CAP(CHIPS)':
 C_PATH='@s9s_mb_2u_lib.s9s_mb_2u(sch_1):page261_i50@pure_quanta.q_cap(chips)',
 P_PATH='@s9s_mb_2u_lib.s9s_mb_2u(sch_1):page275_i50@pure_quanta.q_cap(chips)',
 PATH='I50',
 DRAWING='@S9S_MB_2U_LIB.S9S_MB_2U(SCH_1):PAGE261',
 PHYS_PAGE='275',
 XY='(-6875,5675)',
 ROT='0',
 VER='1',
 PACK_TYPE='C0805',
 LOCATION='PC197_P0_1',
 CDS_LIB='pure_quanta',
 CDS_PART_NAME='Q_CAP_C0805-22UF,16V,20%,X6S,CA',
 TOLERANCE='20%',
 MATERIAL='X6S',
 VOLTAGE='16V',
 VALUE='22UF',
 PRIM_FILE='./archive_libs/logical/q_cap/chips/chips.prt';

PART_NAME
 PC198_P0_2 'Q_CAP_C0805-22UF,16V,20%,X6S,CA':;

SECTION_NUMBER 1
 '@S9S_MB_2U_LIB.S9S_MB_2U(SCH_1):PAGE261_I37@PURE_QUANTA.Q_CAP(CHIPS)':
 C_PATH='@s9s_mb_2u_lib.s9s_mb_2u(sch_1):page261_i37@pure_quanta.q_cap(chips)',
 P_PATH='@s9s_mb_2u_lib.s9s_mb_2u(sch_1):page275_i37@pure_quanta.q_cap(chips)',
 PATH='I37',
 DRAWING='@S9S_MB_2U_LIB.S9S_MB_2U(SCH_1):PAGE261',
 PHYS_PAGE='275',
 XY='(-6875,2875)',
 ROT='0',
 VER='1',
 PACK_TYPE='C0805',
 LOCATION='PC198_P0_2',
 CDS_LIB='pure_quanta',
 CDS_PART_NAME='Q_CAP_C0805-22UF,16V,20%,X6S,CA',
 TOLERANCE='20%',
 MATERIAL='X6S',
 VOLTAGE='16V',
 VALUE='22UF',
 PRIM_FILE='./archive_libs/logical/q_cap/chips/chips.prt';

PART_NAME
 PC199_P0_1 'Q_CAP_C0402-100NF,50V,10%,X7R,A':;

SECTION_NUMBER 1
 '@S9S_MB_2U_LIB.S9S_MB_2U(SCH_1):PAGE261_I54@PURE_QUANTA.Q_CAP(CHIPS)':
 C_PATH='@s9s_mb_2u_lib.s9s_mb_2u(sch_1):page261_i54@pure_quanta.q_cap(chips)',
 P_PATH='@s9s_mb_2u_lib.s9s_mb_2u(sch_1):page275_i54@pure_quanta.q_cap(chips)',
 PATH='I54',
 DRAWING='@S9S_MB_2U_LIB.S9S_MB_2U(SCH_1):PAGE261',
 PHYS_PAGE='275',
 XY='(-6100,4575)',
 ROT='0',
 VER='1',
 PACK_TYPE='C0402',
 LOCATION='PC199_P0_1',
 CDS_LIB='pure_quanta',
 CDS_PART_NAME='Q_CAP_C0402-100NF,50V,10%,X7R,A',
 TOLERANCE='10%',
 MATERIAL='X7R',
 VOLTAGE='50V',
 VALUE='100NF',
 PRIM_FILE='./archive_libs/logical/q_cap/chips/chips.prt';

PART_NAME
 PC202_P0_1 'Q_CAP_C0805-22UF,4V,20%,X6S,CHA':;

SECTION_NUMBER 1
 '@S9S_MB_2U_LIB.S9S_MB_2U(SCH_1):PAGE261_I56@PURE_QUANTA.Q_CAP(CHIPS)':
 C_PATH='@s9s_mb_2u_lib.s9s_mb_2u(sch_1):page261_i56@pure_quanta.q_cap(chips)',
 P_PATH='@s9s_mb_2u_lib.s9s_mb_2u(sch_1):page275_i56@pure_quanta.q_cap(chips)',
 PATH='I56',
 DRAWING='@S9S_MB_2U_LIB.S9S_MB_2U(SCH_1):PAGE261',
 PHYS_PAGE='275',
 XY='(-5700,4575)',
 ROT='0',
 VER='1',
 PACK_TYPE='C0805',
 LOCATION='PC202_P0_1',
 CDS_LIB='pure_quanta',
 CDS_PART_NAME='Q_CAP_C0805-22UF,4V,20%,X6S,CHA',
 TOLERANCE='20%',
 MATERIAL='X6S',
 VOLTAGE='4V',
 VALUE='22UF',
 PRIM_FILE='./archive_libs/logical/q_cap/chips/chips.prt';

PART_NAME
 PC203_P0_2 'Q_CAP_C0805-22UF,4V,20%,X6S,CHA':;

SECTION_NUMBER 1
 '@S9S_MB_2U_LIB.S9S_MB_2U(SCH_1):PAGE261_I40@PURE_QUANTA.Q_CAP(CHIPS)':
 C_PATH='@s9s_mb_2u_lib.s9s_mb_2u(sch_1):page261_i40@pure_quanta.q_cap(chips)',
 P_PATH='@s9s_mb_2u_lib.s9s_mb_2u(sch_1):page275_i40@pure_quanta.q_cap(chips)',
 PATH='I40',
 DRAWING='@S9S_MB_2U_LIB.S9S_MB_2U(SCH_1):PAGE261',
 PHYS_PAGE='275',
 XY='(-5475,1775)',
 ROT='0',
 VER='1',
 PACK_TYPE='C0805',
 LOCATION='PC203_P0_2',
 CDS_LIB='pure_quanta',
 CDS_PART_NAME='Q_CAP_C0805-22UF,4V,20%,X6S,CHA',
 TOLERANCE='20%',
 MATERIAL='X6S',
 VOLTAGE='4V',
 VALUE='22UF',
 PRIM_FILE='./archive_libs/logical/q_cap/chips/chips.prt';

PART_NAME
 PC204_P0_1 'Q_CAP_C0805-22UF,4V,20%,X6S,CHA':;

SECTION_NUMBER 1
 '@S9S_MB_2U_LIB.S9S_MB_2U(SCH_1):PAGE261_I57@PURE_QUANTA.Q_CAP(CHIPS)':
 C_PATH='@s9s_mb_2u_lib.s9s_mb_2u(sch_1):page261_i57@pure_quanta.q_cap(chips)',
 P_PATH='@s9s_mb_2u_lib.s9s_mb_2u(sch_1):page275_i57@pure_quanta.q_cap(chips)',
 PATH='I57',
 DRAWING='@S9S_MB_2U_LIB.S9S_MB_2U(SCH_1):PAGE261',
 PHYS_PAGE='275',
 XY='(-5275,4575)',
 ROT='0',
 VER='1',
 PACK_TYPE='C0805',
 LOCATION='PC204_P0_1',
 CDS_LIB='pure_quanta',
 CDS_PART_NAME='Q_CAP_C0805-22UF,4V,20%,X6S,CHA',
 TOLERANCE='20%',
 MATERIAL='X6S',
 VOLTAGE='4V',
 VALUE='22UF',
 PRIM_FILE='./archive_libs/logical/q_cap/chips/chips.prt';

PART_NAME
 PC205_P0_2 'Q_CAP_C0805-22UF,4V,20%,X6S,CHA':;

SECTION_NUMBER 1
 '@S9S_MB_2U_LIB.S9S_MB_2U(SCH_1):PAGE261_I41@PURE_QUANTA.Q_CAP(CHIPS)':
 C_PATH='@s9s_mb_2u_lib.s9s_mb_2u(sch_1):page261_i41@pure_quanta.q_cap(chips)',
 P_PATH='@s9s_mb_2u_lib.s9s_mb_2u(sch_1):page275_i41@pure_quanta.q_cap(chips)',
 PATH='I41',
 DRAWING='@S9S_MB_2U_LIB.S9S_MB_2U(SCH_1):PAGE261',
 PHYS_PAGE='275',
 XY='(-5050,1775)',
 ROT='0',
 VER='1',
 PACK_TYPE='C0805',
 LOCATION='PC205_P0_2',
 CDS_LIB='pure_quanta',
 CDS_PART_NAME='Q_CAP_C0805-22UF,4V,20%,X6S,CHA',
 TOLERANCE='20%',
 MATERIAL='X6S',
 VOLTAGE='4V',
 VALUE='22UF',
 PRIM_FILE='./archive_libs/logical/q_cap/chips/chips.prt';

PART_NAME
 PC207 'Q_CAPP_THLF-270UF,16V,20%,OSCOA':;

SECTION_NUMBER 1
 '@S9S_MB_2U_LIB.S9S_MB_2U(SCH_1):PAGE261_I74@PURE_QUANTA.Q_CAPP(CHIPS)':
 C_PATH='@s9s_mb_2u_lib.s9s_mb_2u(sch_1):page261_i74@pure_quanta.q_capp(chips)',
 P_PATH='@s9s_mb_2u_lib.s9s_mb_2u(sch_1):page275_i74@pure_quanta.q_capp(chips)',
 PATH='I74',
 DRAWING='@S9S_MB_2U_LIB.S9S_MB_2U(SCH_1):PAGE261',
 PHYS_PAGE='275',
 XY='(-4275,5900)',
 ROT='0',
 VER='1',
 PACK_TYPE='THLF',
 LOCATION='PC207',
 CDS_LIB='pure_quanta',
 CDS_PART_NAME='Q_CAPP_THLF-270UF,16V,20%,OSCOA',
 TOLERANCE='20%',
 MATERIAL='OSCON',
 VOLTAGE='16V',
 VALUE='270UF',
 PRIM_FILE='./archive_libs/logical/q_capp/chips/chips.prt';

PART_NAME
 PC208 'Q_CAPP_THLF-270UF,16V,20%,OSCOA':;

SECTION_NUMBER 1
 '@S9S_MB_2U_LIB.S9S_MB_2U(SCH_1):PAGE261_I75@PURE_QUANTA.Q_CAPP(CHIPS)':
 C_PATH='@s9s_mb_2u_lib.s9s_mb_2u(sch_1):page261_i75@pure_quanta.q_capp(chips)',
 P_PATH='@s9s_mb_2u_lib.s9s_mb_2u(sch_1):page275_i75@pure_quanta.q_capp(chips)',
 PATH='I75',
 DRAWING='@S9S_MB_2U_LIB.S9S_MB_2U(SCH_1):PAGE261',
 PHYS_PAGE='275',
 XY='(-3875,5900)',
 ROT='0',
 VER='1',
 PACK_TYPE='THLF',
 LOCATION='PC208',
 CDS_LIB='pure_quanta',
 CDS_PART_NAME='Q_CAPP_THLF-270UF,16V,20%,OSCOA',
 TOLERANCE='20%',
 MATERIAL='OSCON',
 VOLTAGE='16V',
 VALUE='270UF',
 PRIM_FILE='./archive_libs/logical/q_capp/chips/chips.prt';

PART_NAME
 PC214 'Q_CAP_0402-0.1UF,25V,10%,EMPTYA':;

SECTION_NUMBER 1
 '@S9S_MB_2U_LIB.S9S_MB_2U(SCH_1):PAGE260_I20@PURE_QUANTA.Q_CAP(CHIPS)':
 C_PATH='@s9s_mb_2u_lib.s9s_mb_2u(sch_1):page260_i20@pure_quanta.q_cap(chips)',
 P_PATH='@s9s_mb_2u_lib.s9s_mb_2u(sch_1):page274_i20@pure_quanta.q_cap(chips)',
 PATH='I20',
 DRAWING='@S9S_MB_2U_LIB.S9S_MB_2U(SCH_1):PAGE260',
 PHYS_PAGE='274',
 XY='(-8500,1925)',
 ROT='0',
 VER='1',
 PACK_TYPE='0402',
 LOCATION='PC214',
 CDS_LIB='pure_quanta',
 CDS_PART_NAME='Q_CAP_0402-0.1UF,25V,10%,EMPTYA',
 TOLERANCE='10%',
 MATERIAL='EMPTY',
 VOLTAGE='25V',
 VALUE='0.1UF',
 PRIM_FILE='./archive_libs/logical/q_cap/chips/chips.prt';

PART_NAME
 PC215 'Q_CAP_0402-3300PF,50V,10%,X7R,A':;

SECTION_NUMBER 1
 '@S9S_MB_2U_LIB.S9S_MB_2U(SCH_1):PAGE260_I50@PURE_QUANTA.Q_CAP(CHIPS)':
 C_PATH='@s9s_mb_2u_lib.s9s_mb_2u(sch_1):page260_i50@pure_quanta.q_cap(chips)',
 P_PATH='@s9s_mb_2u_lib.s9s_mb_2u(sch_1):page274_i50@pure_quanta.q_cap(chips)',
 PATH='I50',
 DRAWING='@S9S_MB_2U_LIB.S9S_MB_2U(SCH_1):PAGE260',
 PHYS_PAGE='274',
 XY='(-8400,5400)',
 ROT='0',
 VER='1',
 PACK_TYPE='0402',
 LOCATION='PC215',
 CDS_LIB='pure_quanta',
 CDS_PART_NAME='Q_CAP_0402-3300PF,50V,10%,X7R,A',
 TOLERANCE='10%',
 MATERIAL='X7R',
 VOLTAGE='50V',
 VALUE='3300PF',
 PRIM_FILE='./archive_libs/logical/q_cap/chips/chips.prt';

PART_NAME
 PC216 'Q_CAP_0402-3300PF,50V,10%,X7R,A':;

SECTION_NUMBER 1
 '@S9S_MB_2U_LIB.S9S_MB_2U(SCH_1):PAGE260_I48@PURE_QUANTA.Q_CAP(CHIPS)':
 C_PATH='@s9s_mb_2u_lib.s9s_mb_2u(sch_1):page260_i48@pure_quanta.q_cap(chips)',
 P_PATH='@s9s_mb_2u_lib.s9s_mb_2u(sch_1):page274_i48@pure_quanta.q_cap(chips)',
 PATH='I48',
 DRAWING='@S9S_MB_2U_LIB.S9S_MB_2U(SCH_1):PAGE260',
 PHYS_PAGE='274',
 XY='(-8400,4300)',
 ROT='0',
 VER='1',
 PACK_TYPE='0402',
 LOCATION='PC216',
 CDS_LIB='pure_quanta',
 CDS_PART_NAME='Q_CAP_0402-3300PF,50V,10%,X7R,A',
 TOLERANCE='10%',
 MATERIAL='X7R',
 VOLTAGE='50V',
 VALUE='3300PF',
 PRIM_FILE='./archive_libs/logical/q_cap/chips/chips.prt';

PART_NAME
 PC221 'Q_CAP_0402-0.1UF,25V,10%,X7R,CA':;

SECTION_NUMBER 1
 '@S9S_MB_2U_LIB.S9S_MB_2U(SCH_1):PAGE260_I63@PURE_QUANTA.Q_CAP(CHIPS)':
 C_PATH='@s9s_mb_2u_lib.s9s_mb_2u(sch_1):page260_i63@pure_quanta.q_cap(chips)',
 P_PATH='@s9s_mb_2u_lib.s9s_mb_2u(sch_1):page274_i63@pure_quanta.q_cap(chips)',
 PATH='I63',
 DRAWING='@S9S_MB_2U_LIB.S9S_MB_2U(SCH_1):PAGE260',
 PHYS_PAGE='274',
 XY='(-7750,1925)',
 ROT='0',
 VER='1',
 PACK_TYPE='0402',
 LOCATION='PC221',
 CDS_LIB='pure_quanta',
 CDS_PART_NAME='Q_CAP_0402-0.1UF,25V,10%,X7R,CA',
 TOLERANCE='10%',
 MATERIAL='X7R',
 VOLTAGE='25V',
 VALUE='0.1UF',
 PRIM_FILE='./archive_libs/logical/q_cap/chips/chips.prt';

PART_NAME
 PC222 'Q_CAP_0402-470PF,50V,10%,X7R,TA':;

SECTION_NUMBER 1
 '@S9S_MB_2U_LIB.S9S_MB_2U(SCH_1):PAGE260_I69@PURE_QUANTA.Q_CAP(CHIPS)':
 C_PATH='@s9s_mb_2u_lib.s9s_mb_2u(sch_1):page260_i69@pure_quanta.q_cap(chips)',
 P_PATH='@s9s_mb_2u_lib.s9s_mb_2u(sch_1):page274_i69@pure_quanta.q_cap(chips)',
 PATH='I69',
 DRAWING='@S9S_MB_2U_LIB.S9S_MB_2U(SCH_1):PAGE260',
 PHYS_PAGE='274',
 XY='(-6000,2200)',
 ROT='0',
 VER='1',
 PACK_TYPE='0402',
 LOCATION='PC222',
 CDS_LIB='pure_quanta',
 CDS_PART_NAME='Q_CAP_0402-470PF,50V,10%,X7R,TA',
 TOLERANCE='10%',
 MATERIAL='X7R',
 VOLTAGE='50V',
 VALUE='470PF',
 PRIM_FILE='./archive_libs/logical/q_cap/chips/chips.prt';

PART_NAME
 PC223 'Q_CAP_C0402-100NF,50V,10%,EMPTA':;

SECTION_NUMBER 1
 '@S9S_MB_2U_LIB.S9S_MB_2U(SCH_1):PAGE260_I98@PURE_QUANTA.Q_CAP(CHIPS)':
 C_PATH='@s9s_mb_2u_lib.s9s_mb_2u(sch_1):page260_i98@pure_quanta.q_cap(chips)',
 P_PATH='@s9s_mb_2u_lib.s9s_mb_2u(sch_1):page274_i98@pure_quanta.q_cap(chips)',
 PATH='I98',
 DRAWING='@S9S_MB_2U_LIB.S9S_MB_2U(SCH_1):PAGE260',
 PHYS_PAGE='274',
 XY='(-5575,7375)',
 ROT='0',
 VER='1',
 PACK_TYPE='C0402',
 LOCATION='PC223',
 CDS_LIB='pure_quanta',
 CDS_PART_NAME='Q_CAP_C0402-100NF,50V,10%,EMPTA',
 TOLERANCE='10%',
 MATERIAL='EMPTY',
 VOLTAGE='50V',
 VALUE='100NF',
 PRIM_FILE='./archive_libs/logical/q_cap/chips/chips.prt';

PART_NAME
 PC224 'Q_CAP_C0402-10UF,6.3V,20%,X6S,B':;

SECTION_NUMBER 1
 '@S9S_MB_2U_LIB.S9S_MB_2U(SCH_1):PAGE260_I92@PURE_QUANTA.Q_CAP(CHIPS)':
 C_PATH='@s9s_mb_2u_lib.s9s_mb_2u(sch_1):page260_i92@pure_quanta.q_cap(chips)',
 P_PATH='@s9s_mb_2u_lib.s9s_mb_2u(sch_1):page274_i92@pure_quanta.q_cap(chips)',
 PATH='I92',
 DRAWING='@S9S_MB_2U_LIB.S9S_MB_2U(SCH_1):PAGE260',
 PHYS_PAGE='274',
 XY='(-5575,6900)',
 ROT='0',
 VER='1',
 PACK_TYPE='C0402',
 LOCATION='PC224',
 CDS_LIB='pure_quanta',
 CDS_PART_NAME='Q_CAP_C0402-10UF,6.3V,20%,X6S,B',
 TOLERANCE='20%',
 MATERIAL='X6S',
 VOLTAGE='6.3V',
 VALUE='10UF',
 PRIM_FILE='./archive_libs/logical/q_cap/chips/chips.prt';

PART_NAME
 PC225 'Q_CAP_C0402-1UF,16V,10%,X6S,CHA':;

SECTION_NUMBER 1
 '@S9S_MB_2U_LIB.S9S_MB_2U(SCH_1):PAGE260_I99@PURE_QUANTA.Q_CAP(CHIPS)':
 C_PATH='@s9s_mb_2u_lib.s9s_mb_2u(sch_1):page260_i99@pure_quanta.q_cap(chips)',
 P_PATH='@s9s_mb_2u_lib.s9s_mb_2u(sch_1):page274_i99@pure_quanta.q_cap(chips)',
 PATH='I99',
 DRAWING='@S9S_MB_2U_LIB.S9S_MB_2U(SCH_1):PAGE260',
 PHYS_PAGE='274',
 XY='(-5175,7375)',
 ROT='0',
 VER='1',
 PACK_TYPE='C0402',
 LOCATION='PC225',
 CDS_LIB='pure_quanta',
 CDS_PART_NAME='Q_CAP_C0402-1UF,16V,10%,X6S,CHA',
 TOLERANCE='10%',
 MATERIAL='X6S',
 VOLTAGE='16V',
 VALUE='1UF',
 PRIM_FILE='./archive_libs/logical/q_cap/chips/chips.prt';

PART_NAME
 PC226 'Q_CAP_C0402-2.2UF,10V,10%,X6S,A':;

SECTION_NUMBER 1
 '@S9S_MB_2U_LIB.S9S_MB_2U(SCH_1):PAGE256_I11@PURE_QUANTA.Q_CAP(CHIPS)':
 C_PATH='@s9s_mb_2u_lib.s9s_mb_2u(sch_1):page256_i11@pure_quanta.q_cap(chips)',
 P_PATH='@s9s_mb_2u_lib.s9s_mb_2u(sch_1):page270_i11@pure_quanta.q_cap(chips)',
 PATH='I11',
 DRAWING='@S9S_MB_2U_LIB.S9S_MB_2U(SCH_1):PAGE256',
 PHYS_PAGE='270',
 XY='(-7150,-4900)',
 ROT='0',
 VER='1',
 PACK_TYPE='C0402',
 LOCATION='PC226',
 CDS_LIB='pure_quanta',
 CDS_PART_NAME='Q_CAP_C0402-2.2UF,10V,10%,X6S,A',
 TOLERANCE='10%',
 MATERIAL='X6S',
 VOLTAGE='10V',
 VALUE='2.2UF',
 PRIM_FILE='./archive_libs/logical/q_cap/chips/chips.prt';

PART_NAME
 PC227 'Q_CAP_C0402-2.2UF,10V,10%,X6S,A':;

SECTION_NUMBER 1
 '@S9S_MB_2U_LIB.S9S_MB_2U(SCH_1):PAGE256_I31@PURE_QUANTA.Q_CAP(CHIPS)':
 C_PATH='@s9s_mb_2u_lib.s9s_mb_2u(sch_1):page256_i31@pure_quanta.q_cap(chips)',
 P_PATH='@s9s_mb_2u_lib.s9s_mb_2u(sch_1):page270_i31@pure_quanta.q_cap(chips)',
 PATH='I31',
 DRAWING='@S9S_MB_2U_LIB.S9S_MB_2U(SCH_1):PAGE256',
 PHYS_PAGE='270',
 XY='(-7125,-2075)',
 ROT='0',
 VER='1',
 PACK_TYPE='C0402',
 LOCATION='PC227',
 CDS_LIB='pure_quanta',
 CDS_PART_NAME='Q_CAP_C0402-2.2UF,10V,10%,X6S,A',
 TOLERANCE='10%',
 MATERIAL='X6S',
 VOLTAGE='10V',
 VALUE='2.2UF',
 PRIM_FILE='./archive_libs/logical/q_cap/chips/chips.prt';

PART_NAME
 PC228_P0_8 'Q_CAP_C0402-2.2UF,10V,10%,X6S,A':;

SECTION_NUMBER 1
 '@S9S_MB_2U_LIB.S9S_MB_2U(SCH_1):PAGE256_I15@PURE_QUANTA.Q_CAP(CHIPS)':
 C_PATH='@s9s_mb_2u_lib.s9s_mb_2u(sch_1):page256_i15@pure_quanta.q_cap(chips)',
 P_PATH='@s9s_mb_2u_lib.s9s_mb_2u(sch_1):page270_i15@pure_quanta.q_cap(chips)',
 PATH='I15',
 DRAWING='@S9S_MB_2U_LIB.S9S_MB_2U(SCH_1):PAGE256',
 PHYS_PAGE='270',
 XY='(-6725,-4400)',
 ROT='0',
 VER='1',
 PACK_TYPE='C0402',
 LOCATION='PC228_P0_8',
 CDS_LIB='pure_quanta',
 CDS_PART_NAME='Q_CAP_C0402-2.2UF,10V,10%,X6S,A',
 TOLERANCE='10%',
 MATERIAL='X6S',
 VOLTAGE='10V',
 VALUE='2.2UF',
 PRIM_FILE='./archive_libs/logical/q_cap/chips/chips.prt';

PART_NAME
 PC229_P0_7 'Q_CAP_C0402-2.2UF,10V,10%,X6S,A':;

SECTION_NUMBER 1
 '@S9S_MB_2U_LIB.S9S_MB_2U(SCH_1):PAGE256_I36@PURE_QUANTA.Q_CAP(CHIPS)':
 C_PATH='@s9s_mb_2u_lib.s9s_mb_2u(sch_1):page256_i36@pure_quanta.q_cap(chips)',
 P_PATH='@s9s_mb_2u_lib.s9s_mb_2u(sch_1):page270_i36@pure_quanta.q_cap(chips)',
 PATH='I36',
 DRAWING='@S9S_MB_2U_LIB.S9S_MB_2U(SCH_1):PAGE256',
 PHYS_PAGE='270',
 XY='(-6700,-1575)',
 ROT='0',
 VER='1',
 PACK_TYPE='C0402',
 LOCATION='PC229_P0_7',
 CDS_LIB='pure_quanta',
 CDS_PART_NAME='Q_CAP_C0402-2.2UF,10V,10%,X6S,A',
 TOLERANCE='10%',
 MATERIAL='X6S',
 VOLTAGE='10V',
 VALUE='2.2UF',
 PRIM_FILE='./archive_libs/logical/q_cap/chips/chips.prt';

PART_NAME
 PC230_P0_8 'Q_CAP_0402-3300PF,50V,10%,X7R,A':;

SECTION_NUMBER 1
 '@S9S_MB_2U_LIB.S9S_MB_2U(SCH_1):PAGE256_I17@PURE_QUANTA.Q_CAP(CHIPS)':
 C_PATH='@s9s_mb_2u_lib.s9s_mb_2u(sch_1):page256_i17@pure_quanta.q_cap(chips)',
 P_PATH='@s9s_mb_2u_lib.s9s_mb_2u(sch_1):page270_i17@pure_quanta.q_cap(chips)',
 PATH='I17',
 DRAWING='@S9S_MB_2U_LIB.S9S_MB_2U(SCH_1):PAGE256',
 PHYS_PAGE='270',
 XY='(-4825,-4500)',
 ROT='0',
 VER='1',
 PACK_TYPE='0402',
 LOCATION='PC230_P0_8',
 CDS_LIB='pure_quanta',
 CDS_PART_NAME='Q_CAP_0402-3300PF,50V,10%,X7R,A',
 TOLERANCE='10%',
 MATERIAL='X7R',
 VOLTAGE='50V',
 VALUE='3300PF',
 PRIM_FILE='./archive_libs/logical/q_cap/chips/chips.prt';

PART_NAME
 PC231_P0_7 'Q_CAP_0402-3300PF,50V,10%,X7R,A':;

SECTION_NUMBER 1
 '@S9S_MB_2U_LIB.S9S_MB_2U(SCH_1):PAGE256_I41@PURE_QUANTA.Q_CAP(CHIPS)':
 C_PATH='@s9s_mb_2u_lib.s9s_mb_2u(sch_1):page256_i41@pure_quanta.q_cap(chips)',
 P_PATH='@s9s_mb_2u_lib.s9s_mb_2u(sch_1):page270_i41@pure_quanta.q_cap(chips)',
 PATH='I41',
 DRAWING='@S9S_MB_2U_LIB.S9S_MB_2U(SCH_1):PAGE256',
 PHYS_PAGE='270',
 XY='(-4800,-1675)',
 ROT='0',
 VER='1',
 PACK_TYPE='0402',
 LOCATION='PC231_P0_7',
 CDS_LIB='pure_quanta',
 CDS_PART_NAME='Q_CAP_0402-3300PF,50V,10%,X7R,A',
 TOLERANCE='10%',
 MATERIAL='X7R',
 VOLTAGE='50V',
 VALUE='3300PF',
 PRIM_FILE='./archive_libs/logical/q_cap/chips/chips.prt';

PART_NAME
 PC232_P0_8 'Q_CAP_C0402-1UF,16V,10%,X6S,CHA':;

SECTION_NUMBER 1
 '@S9S_MB_2U_LIB.S9S_MB_2U(SCH_1):PAGE256_I20@PURE_QUANTA.Q_CAP(CHIPS)':
 C_PATH='@s9s_mb_2u_lib.s9s_mb_2u(sch_1):page256_i20@pure_quanta.q_cap(chips)',
 P_PATH='@s9s_mb_2u_lib.s9s_mb_2u(sch_1):page270_i20@pure_quanta.q_cap(chips)',
 PATH='I20',
 DRAWING='@S9S_MB_2U_LIB.S9S_MB_2U(SCH_1):PAGE256',
 PHYS_PAGE='270',
 XY='(-4425,-4500)',
 ROT='0',
 VER='1',
 PACK_TYPE='C0402',
 LOCATION='PC232_P0_8',
 CDS_LIB='pure_quanta',
 CDS_PART_NAME='Q_CAP_C0402-1UF,16V,10%,X6S,CHA',
 TOLERANCE='10%',
 MATERIAL='X6S',
 VOLTAGE='16V',
 VALUE='1UF',
 PRIM_FILE='./archive_libs/logical/q_cap/chips/chips.prt';

PART_NAME
 PC233_P0_7 'Q_CAP_C0402-1UF,16V,10%,X6S,CHA':;

SECTION_NUMBER 1
 '@S9S_MB_2U_LIB.S9S_MB_2U(SCH_1):PAGE256_I42@PURE_QUANTA.Q_CAP(CHIPS)':
 C_PATH='@s9s_mb_2u_lib.s9s_mb_2u(sch_1):page256_i42@pure_quanta.q_cap(chips)',
 P_PATH='@s9s_mb_2u_lib.s9s_mb_2u(sch_1):page270_i42@pure_quanta.q_cap(chips)',
 PATH='I42',
 DRAWING='@S9S_MB_2U_LIB.S9S_MB_2U(SCH_1):PAGE256',
 PHYS_PAGE='270',
 XY='(-4400,-1675)',
 ROT='0',
 VER='1',
 PACK_TYPE='C0402',
 LOCATION='PC233_P0_7',
 CDS_LIB='pure_quanta',
 CDS_PART_NAME='Q_CAP_C0402-1UF,16V,10%,X6S,CHA',
 TOLERANCE='10%',
 MATERIAL='X6S',
 VOLTAGE='16V',
 VALUE='1UF',
 PRIM_FILE='./archive_libs/logical/q_cap/chips/chips.prt';

PART_NAME
 PC234 'Q_CAP_C0402-100NF,50V,10%,X7R,A':;

SECTION_NUMBER 1
 '@S9S_MB_2U_LIB.S9S_MB_2U(SCH_1):PAGE256_I45@PURE_QUANTA.Q_CAP(CHIPS)':
 C_PATH='@s9s_mb_2u_lib.s9s_mb_2u(sch_1):page256_i45@pure_quanta.q_cap(chips)',
 P_PATH='@s9s_mb_2u_lib.s9s_mb_2u(sch_1):page270_i45@pure_quanta.q_cap(chips)',
 PATH='I45',
 DRAWING='@S9S_MB_2U_LIB.S9S_MB_2U(SCH_1):PAGE256',
 PHYS_PAGE='270',
 XY='(-3650,-5125)',
 ROT='2',
 VER='1',
 PACK_TYPE='C0402',
 LOCATION='PC234',
 CDS_LIB='pure_quanta',
 CDS_PART_NAME='Q_CAP_C0402-100NF,50V,10%,X7R,A',
 TOLERANCE='10%',
 MATERIAL='X7R',
 VOLTAGE='50V',
 VALUE='100NF',
 PRIM_FILE='./archive_libs/logical/q_cap/chips/chips.prt';

PART_NAME
 PC235 'Q_CAP_C0402-100NF,50V,10%,X7R,A':;

SECTION_NUMBER 1
 '@S9S_MB_2U_LIB.S9S_MB_2U(SCH_1):PAGE256_I59@PURE_QUANTA.Q_CAP(CHIPS)':
 C_PATH='@s9s_mb_2u_lib.s9s_mb_2u(sch_1):page256_i59@pure_quanta.q_cap(chips)',
 P_PATH='@s9s_mb_2u_lib.s9s_mb_2u(sch_1):page270_i59@pure_quanta.q_cap(chips)',
 PATH='I59',
 DRAWING='@S9S_MB_2U_LIB.S9S_MB_2U(SCH_1):PAGE256',
 PHYS_PAGE='270',
 XY='(-3625,-2300)',
 ROT='2',
 VER='1',
 PACK_TYPE='C0402',
 LOCATION='PC235',
 CDS_LIB='pure_quanta',
 CDS_PART_NAME='Q_CAP_C0402-100NF,50V,10%,X7R,A',
 TOLERANCE='10%',
 MATERIAL='X7R',
 VOLTAGE='50V',
 VALUE='100NF',
 PRIM_FILE='./archive_libs/logical/q_cap/chips/chips.prt';

PART_NAME
 PC236_P0_8 'Q_CAP_C0805-22UF,16V,20%,X6S,CA':;

SECTION_NUMBER 1
 '@S9S_MB_2U_LIB.S9S_MB_2U(SCH_1):PAGE256_I21@PURE_QUANTA.Q_CAP(CHIPS)':
 C_PATH='@s9s_mb_2u_lib.s9s_mb_2u(sch_1):page256_i21@pure_quanta.q_cap(chips)',
 P_PATH='@s9s_mb_2u_lib.s9s_mb_2u(sch_1):page270_i21@pure_quanta.q_cap(chips)',
 PATH='I21',
 DRAWING='@S9S_MB_2U_LIB.S9S_MB_2U(SCH_1):PAGE256',
 PHYS_PAGE='270',
 XY='(-4025,-4500)',
 ROT='0',
 VER='1',
 PACK_TYPE='C0805',
 LOCATION='PC236_P0_8',
 CDS_LIB='pure_quanta',
 CDS_PART_NAME='Q_CAP_C0805-22UF,16V,20%,X6S,CA',
 TOLERANCE='20%',
 MATERIAL='X6S',
 VOLTAGE='16V',
 VALUE='22UF',
 PRIM_FILE='./archive_libs/logical/q_cap/chips/chips.prt';

PART_NAME
 PC237 'Q_CAP_0402-680PF,50V,10%,X7R,TA':;

SECTION_NUMBER 1
 '@S9S_MB_2U_LIB.S9S_MB_2U(SCH_1):PAGE268_I35@PURE_QUANTA.Q_CAP(CHIPS)':
 C_PATH='@s9s_mb_2u_lib.s9s_mb_2u(sch_1):page268_i35@pure_quanta.q_cap(chips)',
 P_PATH='@s9s_mb_2u_lib.s9s_mb_2u(sch_1):page282_i35@pure_quanta.q_cap(chips)',
 PATH='I35',
 DRAWING='@S9S_MB_2U_LIB.S9S_MB_2U(SCH_1):PAGE268',
 PHYS_PAGE='282',
 XY='(-3425,8650)',
 ROT='0',
 VER='2',
 PACK_TYPE='0402',
 LOCATION='PC237',
 CDS_LIB='pure_quanta',
 CDS_PART_NAME='Q_CAP_0402-680PF,50V,10%,X7R,TA',
 TOLERANCE='10%',
 MATERIAL='X7R',
 VOLTAGE='50V',
 VALUE='680PF',
 PRIM_FILE='./archive_libs/logical/q_cap/chips/chips.prt';

PART_NAME
 PC237_P0_7 'Q_CAP_C0805-22UF,16V,20%,X6S,CA':;

SECTION_NUMBER 1
 '@S9S_MB_2U_LIB.S9S_MB_2U(SCH_1):PAGE256_I43@PURE_QUANTA.Q_CAP(CHIPS)':
 C_PATH='@s9s_mb_2u_lib.s9s_mb_2u(sch_1):page256_i43@pure_quanta.q_cap(chips)',
 P_PATH='@s9s_mb_2u_lib.s9s_mb_2u(sch_1):page270_i43@pure_quanta.q_cap(chips)',
 PATH='I43',
 DRAWING='@S9S_MB_2U_LIB.S9S_MB_2U(SCH_1):PAGE256',
 PHYS_PAGE='270',
 XY='(-4000,-1675)',
 ROT='0',
 VER='1',
 PACK_TYPE='C0805',
 LOCATION='PC237_P0_7',
 CDS_LIB='pure_quanta',
 CDS_PART_NAME='Q_CAP_C0805-22UF,16V,20%,X6S,CA',
 TOLERANCE='20%',
 MATERIAL='X6S',
 VOLTAGE='16V',
 VALUE='22UF',
 PRIM_FILE='./archive_libs/logical/q_cap/chips/chips.prt';

PART_NAME
 PC238 'Q_CAP_0402-680PF,50V,10%,X7R,TA':;

SECTION_NUMBER 1
 '@S9S_MB_2U_LIB.S9S_MB_2U(SCH_1):PAGE286_I33@PURE_QUANTA.Q_CAP(CHIPS)':
 C_PATH='@s9s_mb_2u_lib.s9s_mb_2u(sch_1):page286_i33@pure_quanta.q_cap(chips)',
 P_PATH='@s9s_mb_2u_lib.s9s_mb_2u(sch_1):page300_i33@pure_quanta.q_cap(chips)',
 PATH='I33',
 DRAWING='@S9S_MB_2U_LIB.S9S_MB_2U(SCH_1):PAGE286',
 PHYS_PAGE='300',
 XY='(8075,6025)',
 ROT='0',
 VER='2',
 PACK_TYPE='0402',
 LOCATION='PC238',
 CDS_LIB='pure_quanta',
 CDS_PART_NAME='Q_CAP_0402-680PF,50V,10%,X7R,TA',
 TOLERANCE='10%',
 MATERIAL='X7R',
 VOLTAGE='50V',
 VALUE='680PF',
 PRIM_FILE='./archive_libs/logical/q_cap/chips/chips.prt';

PART_NAME
 PC238_P0_8 'Q_CAP_C0805-22UF,16V,20%,X6S,CA':;

SECTION_NUMBER 1
 '@S9S_MB_2U_LIB.S9S_MB_2U(SCH_1):PAGE256_I47@PURE_QUANTA.Q_CAP(CHIPS)':
 C_PATH='@s9s_mb_2u_lib.s9s_mb_2u(sch_1):page256_i47@pure_quanta.q_cap(chips)',
 P_PATH='@s9s_mb_2u_lib.s9s_mb_2u(sch_1):page270_i47@pure_quanta.q_cap(chips)',
 PATH='I47',
 DRAWING='@S9S_MB_2U_LIB.S9S_MB_2U(SCH_1):PAGE256',
 PHYS_PAGE='270',
 XY='(-3625,-4500)',
 ROT='0',
 VER='1',
 PACK_TYPE='C0805',
 LOCATION='PC238_P0_8',
 CDS_LIB='pure_quanta',
 CDS_PART_NAME='Q_CAP_C0805-22UF,16V,20%,X6S,CA',
 TOLERANCE='20%',
 MATERIAL='X6S',
 VOLTAGE='16V',
 VALUE='22UF',
 PRIM_FILE='./archive_libs/logical/q_cap/chips/chips.prt';

PART_NAME
 PC239_P0_7 'Q_CAP_C0805-22UF,16V,20%,X6S,CA':;

SECTION_NUMBER 1
 '@S9S_MB_2U_LIB.S9S_MB_2U(SCH_1):PAGE256_I63@PURE_QUANTA.Q_CAP(CHIPS)':
 C_PATH='@s9s_mb_2u_lib.s9s_mb_2u(sch_1):page256_i63@pure_quanta.q_cap(chips)',
 P_PATH='@s9s_mb_2u_lib.s9s_mb_2u(sch_1):page270_i63@pure_quanta.q_cap(chips)',
 PATH='I63',
 DRAWING='@S9S_MB_2U_LIB.S9S_MB_2U(SCH_1):PAGE256',
 PHYS_PAGE='270',
 XY='(-3600,-1675)',
 ROT='0',
 VER='1',
 PACK_TYPE='C0805',
 LOCATION='PC239_P0_7',
 CDS_LIB='pure_quanta',
 CDS_PART_NAME='Q_CAP_C0805-22UF,16V,20%,X6S,CA',
 TOLERANCE='20%',
 MATERIAL='X6S',
 VOLTAGE='16V',
 VALUE='22UF',
 PRIM_FILE='./archive_libs/logical/q_cap/chips/chips.prt';

PART_NAME
 PC240_P0_8 'Q_CAP_C0805-22UF,16V,20%,X6S,CA':;

SECTION_NUMBER 1
 '@S9S_MB_2U_LIB.S9S_MB_2U(SCH_1):PAGE256_I48@PURE_QUANTA.Q_CAP(CHIPS)':
 C_PATH='@s9s_mb_2u_lib.s9s_mb_2u(sch_1):page256_i48@pure_quanta.q_cap(chips)',
 P_PATH='@s9s_mb_2u_lib.s9s_mb_2u(sch_1):page270_i48@pure_quanta.q_cap(chips)',
 PATH='I48',
 DRAWING='@S9S_MB_2U_LIB.S9S_MB_2U(SCH_1):PAGE256',
 PHYS_PAGE='270',
 XY='(-3250,-4500)',
 ROT='0',
 VER='1',
 PACK_TYPE='C0805',
 LOCATION='PC240_P0_8',
 CDS_LIB='pure_quanta',
 CDS_PART_NAME='Q_CAP_C0805-22UF,16V,20%,X6S,CA',
 TOLERANCE='20%',
 MATERIAL='X6S',
 VOLTAGE='16V',
 VALUE='22UF',
 PRIM_FILE='./archive_libs/logical/q_cap/chips/chips.prt';

PART_NAME
 PC241_P0_7 'Q_CAP_C0805-22UF,16V,20%,X6S,CA':;

SECTION_NUMBER 1
 '@S9S_MB_2U_LIB.S9S_MB_2U(SCH_1):PAGE256_I64@PURE_QUANTA.Q_CAP(CHIPS)':
 C_PATH='@s9s_mb_2u_lib.s9s_mb_2u(sch_1):page256_i64@pure_quanta.q_cap(chips)',
 P_PATH='@s9s_mb_2u_lib.s9s_mb_2u(sch_1):page270_i64@pure_quanta.q_cap(chips)',
 PATH='I64',
 DRAWING='@S9S_MB_2U_LIB.S9S_MB_2U(SCH_1):PAGE256',
 PHYS_PAGE='270',
 XY='(-3225,-1675)',
 ROT='0',
 VER='1',
 PACK_TYPE='C0805',
 LOCATION='PC241_P0_7',
 CDS_LIB='pure_quanta',
 CDS_PART_NAME='Q_CAP_C0805-22UF,16V,20%,X6S,CA',
 TOLERANCE='20%',
 MATERIAL='X6S',
 VOLTAGE='16V',
 VALUE='22UF',
 PRIM_FILE='./archive_libs/logical/q_cap/chips/chips.prt';

PART_NAME
 PC242_P0_8 'Q_CAP_C0402-1UF,16V,10%,X6S,CHA':;

SECTION_NUMBER 1
 '@S9S_MB_2U_LIB.S9S_MB_2U(SCH_1):PAGE256_I52@PURE_QUANTA.Q_CAP(CHIPS)':
 C_PATH='@s9s_mb_2u_lib.s9s_mb_2u(sch_1):page256_i52@pure_quanta.q_cap(chips)',
 P_PATH='@s9s_mb_2u_lib.s9s_mb_2u(sch_1):page270_i52@pure_quanta.q_cap(chips)',
 PATH='I52',
 DRAWING='@S9S_MB_2U_LIB.S9S_MB_2U(SCH_1):PAGE256',
 PHYS_PAGE='270',
 XY='(-1575,-5600)',
 ROT='0',
 VER='1',
 PACK_TYPE='C0402',
 LOCATION='PC242_P0_8',
 CDS_LIB='pure_quanta',
 CDS_PART_NAME='Q_CAP_C0402-1UF,16V,10%,X6S,CHA',
 TOLERANCE='10%',
 MATERIAL='X6S',
 VOLTAGE='16V',
 VALUE='1UF',
 PRIM_FILE='./archive_libs/logical/q_cap/chips/chips.prt';

PART_NAME
 PC243_P0_7 'Q_CAP_C0402-1UF,16V,10%,X6S,CHA':;

SECTION_NUMBER 1
 '@S9S_MB_2U_LIB.S9S_MB_2U(SCH_1):PAGE256_I62@PURE_QUANTA.Q_CAP(CHIPS)':
 C_PATH='@s9s_mb_2u_lib.s9s_mb_2u(sch_1):page256_i62@pure_quanta.q_cap(chips)',
 P_PATH='@s9s_mb_2u_lib.s9s_mb_2u(sch_1):page270_i62@pure_quanta.q_cap(chips)',
 PATH='I62',
 DRAWING='@S9S_MB_2U_LIB.S9S_MB_2U(SCH_1):PAGE256',
 PHYS_PAGE='270',
 XY='(-1825,-2775)',
 ROT='0',
 VER='1',
 PACK_TYPE='C0402',
 LOCATION='PC243_P0_7',
 CDS_LIB='pure_quanta',
 CDS_PART_NAME='Q_CAP_C0402-1UF,16V,10%,X6S,CHA',
 TOLERANCE='10%',
 MATERIAL='X6S',
 VOLTAGE='16V',
 VALUE='1UF',
 PRIM_FILE='./archive_libs/logical/q_cap/chips/chips.prt';

PART_NAME
 PC244_P0_8 'Q_CAP_C0805-22UF,4V,20%,X6S,CHA':;

SECTION_NUMBER 1
 '@S9S_MB_2U_LIB.S9S_MB_2U(SCH_1):PAGE256_I53@PURE_QUANTA.Q_CAP(CHIPS)':
 C_PATH='@s9s_mb_2u_lib.s9s_mb_2u(sch_1):page256_i53@pure_quanta.q_cap(chips)',
 P_PATH='@s9s_mb_2u_lib.s9s_mb_2u(sch_1):page270_i53@pure_quanta.q_cap(chips)',
 PATH='I53',
 DRAWING='@S9S_MB_2U_LIB.S9S_MB_2U(SCH_1):PAGE256',
 PHYS_PAGE='270',
 XY='(-1150,-5600)',
 ROT='0',
 VER='1',
 PACK_TYPE='C0805',
 LOCATION='PC244_P0_8',
 CDS_LIB='pure_quanta',
 CDS_PART_NAME='Q_CAP_C0805-22UF,4V,20%,X6S,CHA',
 TOLERANCE='20%',
 MATERIAL='X6S',
 VOLTAGE='4V',
 VALUE='22UF',
 PRIM_FILE='./archive_libs/logical/q_cap/chips/chips.prt';

PART_NAME
 PC245_P0_7 'Q_CAP_C0805-22UF,4V,20%,X6S,CHA':;

SECTION_NUMBER 1
 '@S9S_MB_2U_LIB.S9S_MB_2U(SCH_1):PAGE256_I66@PURE_QUANTA.Q_CAP(CHIPS)':
 C_PATH='@s9s_mb_2u_lib.s9s_mb_2u(sch_1):page256_i66@pure_quanta.q_cap(chips)',
 P_PATH='@s9s_mb_2u_lib.s9s_mb_2u(sch_1):page270_i66@pure_quanta.q_cap(chips)',
 PATH='I66',
 DRAWING='@S9S_MB_2U_LIB.S9S_MB_2U(SCH_1):PAGE256',
 PHYS_PAGE='270',
 XY='(-1400,-2775)',
 ROT='0',
 VER='1',
 PACK_TYPE='C0805',
 LOCATION='PC245_P0_7',
 CDS_LIB='pure_quanta',
 CDS_PART_NAME='Q_CAP_C0805-22UF,4V,20%,X6S,CHA',
 TOLERANCE='20%',
 MATERIAL='X6S',
 VOLTAGE='4V',
 VALUE='22UF',
 PRIM_FILE='./archive_libs/logical/q_cap/chips/chips.prt';

PART_NAME
 PC246_P0_8 'Q_CAP_C0805-22UF,4V,20%,X6S,CHA':;

SECTION_NUMBER 1
 '@S9S_MB_2U_LIB.S9S_MB_2U(SCH_1):PAGE256_I54@PURE_QUANTA.Q_CAP(CHIPS)':
 C_PATH='@s9s_mb_2u_lib.s9s_mb_2u(sch_1):page256_i54@pure_quanta.q_cap(chips)',
 P_PATH='@s9s_mb_2u_lib.s9s_mb_2u(sch_1):page270_i54@pure_quanta.q_cap(chips)',
 PATH='I54',
 DRAWING='@S9S_MB_2U_LIB.S9S_MB_2U(SCH_1):PAGE256',
 PHYS_PAGE='270',
 XY='(-725,-5600)',
 ROT='0',
 VER='1',
 PACK_TYPE='C0805',
 LOCATION='PC246_P0_8',
 CDS_LIB='pure_quanta',
 CDS_PART_NAME='Q_CAP_C0805-22UF,4V,20%,X6S,CHA',
 TOLERANCE='20%',
 MATERIAL='X6S',
 VOLTAGE='4V',
 VALUE='22UF',
 PRIM_FILE='./archive_libs/logical/q_cap/chips/chips.prt';

PART_NAME
 PC247_P0_7 'Q_CAP_C0805-22UF,4V,20%,X6S,CHA':;

SECTION_NUMBER 1
 '@S9S_MB_2U_LIB.S9S_MB_2U(SCH_1):PAGE256_I67@PURE_QUANTA.Q_CAP(CHIPS)':
 C_PATH='@s9s_mb_2u_lib.s9s_mb_2u(sch_1):page256_i67@pure_quanta.q_cap(chips)',
 P_PATH='@s9s_mb_2u_lib.s9s_mb_2u(sch_1):page270_i67@pure_quanta.q_cap(chips)',
 PATH='I67',
 DRAWING='@S9S_MB_2U_LIB.S9S_MB_2U(SCH_1):PAGE256',
 PHYS_PAGE='270',
 XY='(-975,-2775)',
 ROT='0',
 VER='1',
 PACK_TYPE='C0805',
 LOCATION='PC247_P0_7',
 CDS_LIB='pure_quanta',
 CDS_PART_NAME='Q_CAP_C0805-22UF,4V,20%,X6S,CHA',
 TOLERANCE='20%',
 MATERIAL='X6S',
 VOLTAGE='4V',
 VALUE='22UF',
 PRIM_FILE='./archive_libs/logical/q_cap/chips/chips.prt';

PART_NAME
 PC248 'Q_CAP_C0402-2.2UF,10V,10%,X6S,A':;

SECTION_NUMBER 1
 '@S9S_MB_2U_LIB.S9S_MB_2U(SCH_1):PAGE255_I13@PURE_QUANTA.Q_CAP(CHIPS)':
 C_PATH='@s9s_mb_2u_lib.s9s_mb_2u(sch_1):page255_i13@pure_quanta.q_cap(chips)',
 P_PATH='@s9s_mb_2u_lib.s9s_mb_2u(sch_1):page269_i13@pure_quanta.q_cap(chips)',
 PATH='I13',
 DRAWING='@S9S_MB_2U_LIB.S9S_MB_2U(SCH_1):PAGE255',
 PHYS_PAGE='269',
 XY='(2075,2400)',
 ROT='0',
 VER='1',
 PACK_TYPE='C0402',
 LOCATION='PC248',
 CDS_LIB='pure_quanta',
 CDS_PART_NAME='Q_CAP_C0402-2.2UF,10V,10%,X6S,A',
 TOLERANCE='10%',
 MATERIAL='X6S',
 VOLTAGE='10V',
 VALUE='2.2UF',
 PRIM_FILE='./archive_libs/logical/q_cap/chips/chips.prt';

PART_NAME
 PC249 'Q_CAP_C0402-2.2UF,10V,10%,X6S,A':;

SECTION_NUMBER 1
 '@S9S_MB_2U_LIB.S9S_MB_2U(SCH_1):PAGE255_I24@PURE_QUANTA.Q_CAP(CHIPS)':
 C_PATH='@s9s_mb_2u_lib.s9s_mb_2u(sch_1):page255_i24@pure_quanta.q_cap(chips)',
 P_PATH='@s9s_mb_2u_lib.s9s_mb_2u(sch_1):page269_i24@pure_quanta.q_cap(chips)',
 PATH='I24',
 DRAWING='@S9S_MB_2U_LIB.S9S_MB_2U(SCH_1):PAGE255',
 PHYS_PAGE='269',
 XY='(2100,5225)',
 ROT='0',
 VER='1',
 PACK_TYPE='C0402',
 LOCATION='PC249',
 CDS_LIB='pure_quanta',
 CDS_PART_NAME='Q_CAP_C0402-2.2UF,10V,10%,X6S,A',
 TOLERANCE='10%',
 MATERIAL='X6S',
 VOLTAGE='10V',
 VALUE='2.2UF',
 PRIM_FILE='./archive_libs/logical/q_cap/chips/chips.prt';

PART_NAME
 PC250_P0_6 'Q_CAP_C0402-2.2UF,10V,10%,X6S,A':;

SECTION_NUMBER 1
 '@S9S_MB_2U_LIB.S9S_MB_2U(SCH_1):PAGE255_I17@PURE_QUANTA.Q_CAP(CHIPS)':
 C_PATH='@s9s_mb_2u_lib.s9s_mb_2u(sch_1):page255_i17@pure_quanta.q_cap(chips)',
 P_PATH='@s9s_mb_2u_lib.s9s_mb_2u(sch_1):page269_i17@pure_quanta.q_cap(chips)',
 PATH='I17',
 DRAWING='@S9S_MB_2U_LIB.S9S_MB_2U(SCH_1):PAGE255',
 PHYS_PAGE='269',
 XY='(2500,2900)',
 ROT='0',
 VER='1',
 PACK_TYPE='C0402',
 LOCATION='PC250_P0_6',
 CDS_LIB='pure_quanta',
 CDS_PART_NAME='Q_CAP_C0402-2.2UF,10V,10%,X6S,A',
 TOLERANCE='10%',
 MATERIAL='X6S',
 VOLTAGE='10V',
 VALUE='2.2UF',
 PRIM_FILE='./archive_libs/logical/q_cap/chips/chips.prt';

PART_NAME
 PC251_P0_5 'Q_CAP_C0402-2.2UF,10V,10%,X6S,A':;

SECTION_NUMBER 1
 '@S9S_MB_2U_LIB.S9S_MB_2U(SCH_1):PAGE255_I29@PURE_QUANTA.Q_CAP(CHIPS)':
 C_PATH='@s9s_mb_2u_lib.s9s_mb_2u(sch_1):page255_i29@pure_quanta.q_cap(chips)',
 P_PATH='@s9s_mb_2u_lib.s9s_mb_2u(sch_1):page269_i29@pure_quanta.q_cap(chips)',
 PATH='I29',
 DRAWING='@S9S_MB_2U_LIB.S9S_MB_2U(SCH_1):PAGE255',
 PHYS_PAGE='269',
 XY='(2525,5725)',
 ROT='0',
 VER='1',
 PACK_TYPE='C0402',
 LOCATION='PC251_P0_5',
 CDS_LIB='pure_quanta',
 CDS_PART_NAME='Q_CAP_C0402-2.2UF,10V,10%,X6S,A',
 TOLERANCE='10%',
 MATERIAL='X6S',
 VOLTAGE='10V',
 VALUE='2.2UF',
 PRIM_FILE='./archive_libs/logical/q_cap/chips/chips.prt';

PART_NAME
 PC252_P0_6 'Q_CAP_0402-3300PF,50V,10%,X7R,A':;

SECTION_NUMBER 1
 '@S9S_MB_2U_LIB.S9S_MB_2U(SCH_1):PAGE255_I34@PURE_QUANTA.Q_CAP(CHIPS)':
 C_PATH='@s9s_mb_2u_lib.s9s_mb_2u(sch_1):page255_i34@pure_quanta.q_cap(chips)',
 P_PATH='@s9s_mb_2u_lib.s9s_mb_2u(sch_1):page269_i34@pure_quanta.q_cap(chips)',
 PATH='I34',
 DRAWING='@S9S_MB_2U_LIB.S9S_MB_2U(SCH_1):PAGE255',
 PHYS_PAGE='269',
 XY='(4400,2800)',
 ROT='0',
 VER='1',
 PACK_TYPE='0402',
 LOCATION='PC252_P0_6',
 CDS_LIB='pure_quanta',
 CDS_PART_NAME='Q_CAP_0402-3300PF,50V,10%,X7R,A',
 TOLERANCE='10%',
 MATERIAL='X7R',
 VOLTAGE='50V',
 VALUE='3300PF',
 PRIM_FILE='./archive_libs/logical/q_cap/chips/chips.prt';

PART_NAME
 PC253_P0_5 'Q_CAP_0402-3300PF,50V,10%,X7R,A':;

SECTION_NUMBER 1
 '@S9S_MB_2U_LIB.S9S_MB_2U(SCH_1):PAGE255_I48@PURE_QUANTA.Q_CAP(CHIPS)':
 C_PATH='@s9s_mb_2u_lib.s9s_mb_2u(sch_1):page255_i48@pure_quanta.q_cap(chips)',
 P_PATH='@s9s_mb_2u_lib.s9s_mb_2u(sch_1):page269_i48@pure_quanta.q_cap(chips)',
 PATH='I48',
 DRAWING='@S9S_MB_2U_LIB.S9S_MB_2U(SCH_1):PAGE255',
 PHYS_PAGE='269',
 XY='(4425,5625)',
 ROT='0',
 VER='1',
 PACK_TYPE='0402',
 LOCATION='PC253_P0_5',
 CDS_LIB='pure_quanta',
 CDS_PART_NAME='Q_CAP_0402-3300PF,50V,10%,X7R,A',
 TOLERANCE='10%',
 MATERIAL='X7R',
 VOLTAGE='50V',
 VALUE='3300PF',
 PRIM_FILE='./archive_libs/logical/q_cap/chips/chips.prt';

PART_NAME
 PC254_P0_6 'Q_CAP_C0402-1UF,16V,10%,X6S,CHA':;

SECTION_NUMBER 1
 '@S9S_MB_2U_LIB.S9S_MB_2U(SCH_1):PAGE255_I37@PURE_QUANTA.Q_CAP(CHIPS)':
 C_PATH='@s9s_mb_2u_lib.s9s_mb_2u(sch_1):page255_i37@pure_quanta.q_cap(chips)',
 P_PATH='@s9s_mb_2u_lib.s9s_mb_2u(sch_1):page269_i37@pure_quanta.q_cap(chips)',
 PATH='I37',
 DRAWING='@S9S_MB_2U_LIB.S9S_MB_2U(SCH_1):PAGE255',
 PHYS_PAGE='269',
 XY='(4800,2800)',
 ROT='0',
 VER='1',
 PACK_TYPE='C0402',
 LOCATION='PC254_P0_6',
 CDS_LIB='pure_quanta',
 CDS_PART_NAME='Q_CAP_C0402-1UF,16V,10%,X6S,CHA',
 TOLERANCE='10%',
 MATERIAL='X6S',
 VOLTAGE='16V',
 VALUE='1UF',
 PRIM_FILE='./archive_libs/logical/q_cap/chips/chips.prt';

PART_NAME
 PC255_P0_5 'Q_CAP_C0402-1UF,16V,10%,X6S,CHA':;

SECTION_NUMBER 1
 '@S9S_MB_2U_LIB.S9S_MB_2U(SCH_1):PAGE255_I52@PURE_QUANTA.Q_CAP(CHIPS)':
 C_PATH='@s9s_mb_2u_lib.s9s_mb_2u(sch_1):page255_i52@pure_quanta.q_cap(chips)',
 P_PATH='@s9s_mb_2u_lib.s9s_mb_2u(sch_1):page269_i52@pure_quanta.q_cap(chips)',
 PATH='I52',
 DRAWING='@S9S_MB_2U_LIB.S9S_MB_2U(SCH_1):PAGE255',
 PHYS_PAGE='269',
 XY='(4825,5625)',
 ROT='0',
 VER='1',
 PACK_TYPE='C0402',
 LOCATION='PC255_P0_5',
 CDS_LIB='pure_quanta',
 CDS_PART_NAME='Q_CAP_C0402-1UF,16V,10%,X6S,CHA',
 TOLERANCE='10%',
 MATERIAL='X6S',
 VOLTAGE='16V',
 VALUE='1UF',
 PRIM_FILE='./archive_libs/logical/q_cap/chips/chips.prt';

PART_NAME
 PC256 'Q_CAP_C0402-100NF,50V,10%,X7R,A':;

SECTION_NUMBER 1
 '@S9S_MB_2U_LIB.S9S_MB_2U(SCH_1):PAGE255_I33@PURE_QUANTA.Q_CAP(CHIPS)':
 C_PATH='@s9s_mb_2u_lib.s9s_mb_2u(sch_1):page255_i33@pure_quanta.q_cap(chips)',
 P_PATH='@s9s_mb_2u_lib.s9s_mb_2u(sch_1):page269_i33@pure_quanta.q_cap(chips)',
 PATH='I33',
 DRAWING='@S9S_MB_2U_LIB.S9S_MB_2U(SCH_1):PAGE255',
 PHYS_PAGE='269',
 XY='(5575,2175)',
 ROT='2',
 VER='1',
 PACK_TYPE='C0402',
 LOCATION='PC256',
 CDS_LIB='pure_quanta',
 CDS_PART_NAME='Q_CAP_C0402-100NF,50V,10%,X7R,A',
 TOLERANCE='10%',
 MATERIAL='X7R',
 VOLTAGE='50V',
 VALUE='100NF',
 PRIM_FILE='./archive_libs/logical/q_cap/chips/chips.prt';

PART_NAME
 PC257 'Q_CAP_C0402-100NF,50V,10%,X7R,A':;

SECTION_NUMBER 1
 '@S9S_MB_2U_LIB.S9S_MB_2U(SCH_1):PAGE255_I51@PURE_QUANTA.Q_CAP(CHIPS)':
 C_PATH='@s9s_mb_2u_lib.s9s_mb_2u(sch_1):page255_i51@pure_quanta.q_cap(chips)',
 P_PATH='@s9s_mb_2u_lib.s9s_mb_2u(sch_1):page269_i51@pure_quanta.q_cap(chips)',
 PATH='I51',
 DRAWING='@S9S_MB_2U_LIB.S9S_MB_2U(SCH_1):PAGE255',
 PHYS_PAGE='269',
 XY='(5600,5000)',
 ROT='2',
 VER='1',
 PACK_TYPE='C0402',
 LOCATION='PC257',
 CDS_LIB='pure_quanta',
 CDS_PART_NAME='Q_CAP_C0402-100NF,50V,10%,X7R,A',
 TOLERANCE='10%',
 MATERIAL='X7R',
 VOLTAGE='50V',
 VALUE='100NF',
 PRIM_FILE='./archive_libs/logical/q_cap/chips/chips.prt';

PART_NAME
 PC258_P0_6 'Q_CAP_C0805-22UF,16V,20%,X6S,CA':;

SECTION_NUMBER 1
 '@S9S_MB_2U_LIB.S9S_MB_2U(SCH_1):PAGE255_I38@PURE_QUANTA.Q_CAP(CHIPS)':
 C_PATH='@s9s_mb_2u_lib.s9s_mb_2u(sch_1):page255_i38@pure_quanta.q_cap(chips)',
 P_PATH='@s9s_mb_2u_lib.s9s_mb_2u(sch_1):page269_i38@pure_quanta.q_cap(chips)',
 PATH='I38',
 DRAWING='@S9S_MB_2U_LIB.S9S_MB_2U(SCH_1):PAGE255',
 PHYS_PAGE='269',
 XY='(5200,2800)',
 ROT='0',
 VER='1',
 PACK_TYPE='C0805',
 LOCATION='PC258_P0_6',
 CDS_LIB='pure_quanta',
 CDS_PART_NAME='Q_CAP_C0805-22UF,16V,20%,X6S,CA',
 TOLERANCE='20%',
 MATERIAL='X6S',
 VOLTAGE='16V',
 VALUE='22UF',
 PRIM_FILE='./archive_libs/logical/q_cap/chips/chips.prt';

PART_NAME
 PC259_P0_5 'Q_CAP_C0805-22UF,16V,20%,X6S,CA':;

SECTION_NUMBER 1
 '@S9S_MB_2U_LIB.S9S_MB_2U(SCH_1):PAGE255_I53@PURE_QUANTA.Q_CAP(CHIPS)':
 C_PATH='@s9s_mb_2u_lib.s9s_mb_2u(sch_1):page255_i53@pure_quanta.q_cap(chips)',
 P_PATH='@s9s_mb_2u_lib.s9s_mb_2u(sch_1):page269_i53@pure_quanta.q_cap(chips)',
 PATH='I53',
 DRAWING='@S9S_MB_2U_LIB.S9S_MB_2U(SCH_1):PAGE255',
 PHYS_PAGE='269',
 XY='(5225,5625)',
 ROT='0',
 VER='1',
 PACK_TYPE='C0805',
 LOCATION='PC259_P0_5',
 CDS_LIB='pure_quanta',
 CDS_PART_NAME='Q_CAP_C0805-22UF,16V,20%,X6S,CA',
 TOLERANCE='20%',
 MATERIAL='X6S',
 VOLTAGE='16V',
 VALUE='22UF',
 PRIM_FILE='./archive_libs/logical/q_cap/chips/chips.prt';

PART_NAME
 PC260_P0_6 'Q_CAP_C0805-22UF,16V,20%,X6S,CA':;

SECTION_NUMBER 1
 '@S9S_MB_2U_LIB.S9S_MB_2U(SCH_1):PAGE255_I39@PURE_QUANTA.Q_CAP(CHIPS)':
 C_PATH='@s9s_mb_2u_lib.s9s_mb_2u(sch_1):page255_i39@pure_quanta.q_cap(chips)',
 P_PATH='@s9s_mb_2u_lib.s9s_mb_2u(sch_1):page269_i39@pure_quanta.q_cap(chips)',
 PATH='I39',
 DRAWING='@S9S_MB_2U_LIB.S9S_MB_2U(SCH_1):PAGE255',
 PHYS_PAGE='269',
 XY='(5600,2800)',
 ROT='0',
 VER='1',
 PACK_TYPE='C0805',
 LOCATION='PC260_P0_6',
 CDS_LIB='pure_quanta',
 CDS_PART_NAME='Q_CAP_C0805-22UF,16V,20%,X6S,CA',
 TOLERANCE='20%',
 MATERIAL='X6S',
 VOLTAGE='16V',
 VALUE='22UF',
 PRIM_FILE='./archive_libs/logical/q_cap/chips/chips.prt';

PART_NAME
 PC261_P0_5 'Q_CAP_C0805-22UF,16V,20%,X6S,CA':;

SECTION_NUMBER 1
 '@S9S_MB_2U_LIB.S9S_MB_2U(SCH_1):PAGE255_I54@PURE_QUANTA.Q_CAP(CHIPS)':
 C_PATH='@s9s_mb_2u_lib.s9s_mb_2u(sch_1):page255_i54@pure_quanta.q_cap(chips)',
 P_PATH='@s9s_mb_2u_lib.s9s_mb_2u(sch_1):page269_i54@pure_quanta.q_cap(chips)',
 PATH='I54',
 DRAWING='@S9S_MB_2U_LIB.S9S_MB_2U(SCH_1):PAGE255',
 PHYS_PAGE='269',
 XY='(5625,5625)',
 ROT='0',
 VER='1',
 PACK_TYPE='C0805',
 LOCATION='PC261_P0_5',
 CDS_LIB='pure_quanta',
 CDS_PART_NAME='Q_CAP_C0805-22UF,16V,20%,X6S,CA',
 TOLERANCE='20%',
 MATERIAL='X6S',
 VOLTAGE='16V',
 VALUE='22UF',
 PRIM_FILE='./archive_libs/logical/q_cap/chips/chips.prt';

PART_NAME
 PC262_P0_6 'Q_CAP_C0805-22UF,16V,20%,X6S,CA':;

SECTION_NUMBER 1
 '@S9S_MB_2U_LIB.S9S_MB_2U(SCH_1):PAGE255_I43@PURE_QUANTA.Q_CAP(CHIPS)':
 C_PATH='@s9s_mb_2u_lib.s9s_mb_2u(sch_1):page255_i43@pure_quanta.q_cap(chips)',
 P_PATH='@s9s_mb_2u_lib.s9s_mb_2u(sch_1):page269_i43@pure_quanta.q_cap(chips)',
 PATH='I43',
 DRAWING='@S9S_MB_2U_LIB.S9S_MB_2U(SCH_1):PAGE255',
 PHYS_PAGE='269',
 XY='(5975,2800)',
 ROT='0',
 VER='1',
 PACK_TYPE='C0805',
 LOCATION='PC262_P0_6',
 CDS_LIB='pure_quanta',
 CDS_PART_NAME='Q_CAP_C0805-22UF,16V,20%,X6S,CA',
 TOLERANCE='20%',
 MATERIAL='X6S',
 VOLTAGE='16V',
 VALUE='22UF',
 PRIM_FILE='./archive_libs/logical/q_cap/chips/chips.prt';

PART_NAME
 PC263_P0_5 'Q_CAP_C0805-22UF,16V,20%,X6S,CA':;

SECTION_NUMBER 1
 '@S9S_MB_2U_LIB.S9S_MB_2U(SCH_1):PAGE255_I56@PURE_QUANTA.Q_CAP(CHIPS)':
 C_PATH='@s9s_mb_2u_lib.s9s_mb_2u(sch_1):page255_i56@pure_quanta.q_cap(chips)',
 P_PATH='@s9s_mb_2u_lib.s9s_mb_2u(sch_1):page269_i56@pure_quanta.q_cap(chips)',
 PATH='I56',
 DRAWING='@S9S_MB_2U_LIB.S9S_MB_2U(SCH_1):PAGE255',
 PHYS_PAGE='269',
 XY='(6000,5625)',
 ROT='0',
 VER='1',
 PACK_TYPE='C0805',
 LOCATION='PC263_P0_5',
 CDS_LIB='pure_quanta',
 CDS_PART_NAME='Q_CAP_C0805-22UF,16V,20%,X6S,CA',
 TOLERANCE='20%',
 MATERIAL='X6S',
 VOLTAGE='16V',
 VALUE='22UF',
 PRIM_FILE='./archive_libs/logical/q_cap/chips/chips.prt';

PART_NAME
 PC266_P0_6 'Q_CAP_C0805-22UF,4V,20%,X6S,CHA':;

SECTION_NUMBER 1
 '@S9S_MB_2U_LIB.S9S_MB_2U(SCH_1):PAGE255_I42@PURE_QUANTA.Q_CAP(CHIPS)':
 C_PATH='@s9s_mb_2u_lib.s9s_mb_2u(sch_1):page255_i42@pure_quanta.q_cap(chips)',
 P_PATH='@s9s_mb_2u_lib.s9s_mb_2u(sch_1):page269_i42@pure_quanta.q_cap(chips)',
 PATH='I42',
 DRAWING='@S9S_MB_2U_LIB.S9S_MB_2U(SCH_1):PAGE255',
 PHYS_PAGE='269',
 XY='(7725,1700)',
 ROT='0',
 VER='1',
 PACK_TYPE='C0805',
 LOCATION='PC266_P0_6',
 CDS_LIB='pure_quanta',
 CDS_PART_NAME='Q_CAP_C0805-22UF,4V,20%,X6S,CHA',
 TOLERANCE='20%',
 MATERIAL='X6S',
 VOLTAGE='4V',
 VALUE='22UF',
 PRIM_FILE='./archive_libs/logical/q_cap/chips/chips.prt';

PART_NAME
 PC267_P0_5 'Q_CAP_C0805-22UF,4V,20%,X6S,CHA':;

SECTION_NUMBER 1
 '@S9S_MB_2U_LIB.S9S_MB_2U(SCH_1):PAGE255_I63@PURE_QUANTA.Q_CAP(CHIPS)':
 C_PATH='@s9s_mb_2u_lib.s9s_mb_2u(sch_1):page255_i63@pure_quanta.q_cap(chips)',
 P_PATH='@s9s_mb_2u_lib.s9s_mb_2u(sch_1):page269_i63@pure_quanta.q_cap(chips)',
 PATH='I63',
 DRAWING='@S9S_MB_2U_LIB.S9S_MB_2U(SCH_1):PAGE255',
 PHYS_PAGE='269',
 XY='(7925,4525)',
 ROT='0',
 VER='1',
 PACK_TYPE='C0805',
 LOCATION='PC267_P0_5',
 CDS_LIB='pure_quanta',
 CDS_PART_NAME='Q_CAP_C0805-22UF,4V,20%,X6S,CHA',
 TOLERANCE='20%',
 MATERIAL='X6S',
 VOLTAGE='4V',
 VALUE='22UF',
 PRIM_FILE='./archive_libs/logical/q_cap/chips/chips.prt';

PART_NAME
 PC268_P0_6 'Q_CAP_C0805-22UF,4V,20%,X6S,CHA':;

SECTION_NUMBER 1
 '@S9S_MB_2U_LIB.S9S_MB_2U(SCH_1):PAGE255_I59@PURE_QUANTA.Q_CAP(CHIPS)':
 C_PATH='@s9s_mb_2u_lib.s9s_mb_2u(sch_1):page255_i59@pure_quanta.q_cap(chips)',
 P_PATH='@s9s_mb_2u_lib.s9s_mb_2u(sch_1):page269_i59@pure_quanta.q_cap(chips)',
 PATH='I59',
 DRAWING='@S9S_MB_2U_LIB.S9S_MB_2U(SCH_1):PAGE255',
 PHYS_PAGE='269',
 XY='(8150,1700)',
 ROT='0',
 VER='1',
 PACK_TYPE='C0805',
 LOCATION='PC268_P0_6',
 CDS_LIB='pure_quanta',
 CDS_PART_NAME='Q_CAP_C0805-22UF,4V,20%,X6S,CHA',
 TOLERANCE='20%',
 MATERIAL='X6S',
 VOLTAGE='4V',
 VALUE='22UF',
 PRIM_FILE='./archive_libs/logical/q_cap/chips/chips.prt';

PART_NAME
 PC269_P0_5 'Q_CAP_C0805-22UF,4V,20%,X6S,CHA':;

SECTION_NUMBER 1
 '@S9S_MB_2U_LIB.S9S_MB_2U(SCH_1):PAGE255_I64@PURE_QUANTA.Q_CAP(CHIPS)':
 C_PATH='@s9s_mb_2u_lib.s9s_mb_2u(sch_1):page255_i64@pure_quanta.q_cap(chips)',
 P_PATH='@s9s_mb_2u_lib.s9s_mb_2u(sch_1):page269_i64@pure_quanta.q_cap(chips)',
 PATH='I64',
 DRAWING='@S9S_MB_2U_LIB.S9S_MB_2U(SCH_1):PAGE255',
 PHYS_PAGE='269',
 XY='(8350,4525)',
 ROT='0',
 VER='1',
 PACK_TYPE='C0805',
 LOCATION='PC269_P0_5',
 CDS_LIB='pure_quanta',
 CDS_PART_NAME='Q_CAP_C0805-22UF,4V,20%,X6S,CHA',
 TOLERANCE='20%',
 MATERIAL='X6S',
 VOLTAGE='4V',
 VALUE='22UF',
 PRIM_FILE='./archive_libs/logical/q_cap/chips/chips.prt';

PART_NAME
 PC270 'Q_CAP_C0402-2.2UF,10V,10%,X6S,A':;

SECTION_NUMBER 1
 '@S9S_MB_2U_LIB.S9S_MB_2U(SCH_1):PAGE254_I11@PURE_QUANTA.Q_CAP(CHIPS)':
 C_PATH='@s9s_mb_2u_lib.s9s_mb_2u(sch_1):page254_i11@pure_quanta.q_cap(chips)',
 P_PATH='@s9s_mb_2u_lib.s9s_mb_2u(sch_1):page268_i11@pure_quanta.q_cap(chips)',
 PATH='I11',
 DRAWING='@S9S_MB_2U_LIB.S9S_MB_2U(SCH_1):PAGE254',
 PHYS_PAGE='268',
 XY='(3000,2000)',
 ROT='0',
 VER='1',
 PACK_TYPE='C0402',
 LOCATION='PC270',
 CDS_LIB='pure_quanta',
 CDS_PART_NAME='Q_CAP_C0402-2.2UF,10V,10%,X6S,A',
 TOLERANCE='10%',
 MATERIAL='X6S',
 VOLTAGE='10V',
 VALUE='2.2UF',
 PRIM_FILE='./archive_libs/logical/q_cap/chips/chips.prt';

PART_NAME
 PC271 'Q_CAP_C0402-2.2UF,10V,10%,X6S,A':;

SECTION_NUMBER 1
 '@S9S_MB_2U_LIB.S9S_MB_2U(SCH_1):PAGE254_I25@PURE_QUANTA.Q_CAP(CHIPS)':
 C_PATH='@s9s_mb_2u_lib.s9s_mb_2u(sch_1):page254_i25@pure_quanta.q_cap(chips)',
 P_PATH='@s9s_mb_2u_lib.s9s_mb_2u(sch_1):page268_i25@pure_quanta.q_cap(chips)',
 PATH='I25',
 DRAWING='@S9S_MB_2U_LIB.S9S_MB_2U(SCH_1):PAGE254',
 PHYS_PAGE='268',
 XY='(3025,4825)',
 ROT='0',
 VER='1',
 PACK_TYPE='C0402',
 LOCATION='PC271',
 CDS_LIB='pure_quanta',
 CDS_PART_NAME='Q_CAP_C0402-2.2UF,10V,10%,X6S,A',
 TOLERANCE='10%',
 MATERIAL='X6S',
 VOLTAGE='10V',
 VALUE='2.2UF',
 PRIM_FILE='./archive_libs/logical/q_cap/chips/chips.prt';

PART_NAME
 PC272_P0_4 'Q_CAP_C0402-2.2UF,10V,10%,X6S,A':;

SECTION_NUMBER 1
 '@S9S_MB_2U_LIB.S9S_MB_2U(SCH_1):PAGE254_I17@PURE_QUANTA.Q_CAP(CHIPS)':
 C_PATH='@s9s_mb_2u_lib.s9s_mb_2u(sch_1):page254_i17@pure_quanta.q_cap(chips)',
 P_PATH='@s9s_mb_2u_lib.s9s_mb_2u(sch_1):page268_i17@pure_quanta.q_cap(chips)',
 PATH='I17',
 DRAWING='@S9S_MB_2U_LIB.S9S_MB_2U(SCH_1):PAGE254',
 PHYS_PAGE='268',
 XY='(3425,2500)',
 ROT='0',
 VER='1',
 PACK_TYPE='C0402',
 LOCATION='PC272_P0_4',
 CDS_LIB='pure_quanta',
 CDS_PART_NAME='Q_CAP_C0402-2.2UF,10V,10%,X6S,A',
 TOLERANCE='10%',
 MATERIAL='X6S',
 VOLTAGE='10V',
 VALUE='2.2UF',
 PRIM_FILE='./archive_libs/logical/q_cap/chips/chips.prt';

PART_NAME
 PC273_P0_3 'Q_CAP_C0402-2.2UF,10V,10%,X6S,A':;

SECTION_NUMBER 1
 '@S9S_MB_2U_LIB.S9S_MB_2U(SCH_1):PAGE254_I30@PURE_QUANTA.Q_CAP(CHIPS)':
 C_PATH='@s9s_mb_2u_lib.s9s_mb_2u(sch_1):page254_i30@pure_quanta.q_cap(chips)',
 P_PATH='@s9s_mb_2u_lib.s9s_mb_2u(sch_1):page268_i30@pure_quanta.q_cap(chips)',
 PATH='I30',
 DRAWING='@S9S_MB_2U_LIB.S9S_MB_2U(SCH_1):PAGE254',
 PHYS_PAGE='268',
 XY='(3450,5325)',
 ROT='0',
 VER='1',
 PACK_TYPE='C0402',
 LOCATION='PC273_P0_3',
 CDS_LIB='pure_quanta',
 CDS_PART_NAME='Q_CAP_C0402-2.2UF,10V,10%,X6S,A',
 TOLERANCE='10%',
 MATERIAL='X6S',
 VOLTAGE='10V',
 VALUE='2.2UF',
 PRIM_FILE='./archive_libs/logical/q_cap/chips/chips.prt';

PART_NAME
 PC274_P0_4 'Q_CAP_0402-3300PF,50V,10%,X7R,A':;

SECTION_NUMBER 1
 '@S9S_MB_2U_LIB.S9S_MB_2U(SCH_1):PAGE254_I35@PURE_QUANTA.Q_CAP(CHIPS)':
 C_PATH='@s9s_mb_2u_lib.s9s_mb_2u(sch_1):page254_i35@pure_quanta.q_cap(chips)',
 P_PATH='@s9s_mb_2u_lib.s9s_mb_2u(sch_1):page268_i35@pure_quanta.q_cap(chips)',
 PATH='I35',
 DRAWING='@S9S_MB_2U_LIB.S9S_MB_2U(SCH_1):PAGE254',
 PHYS_PAGE='268',
 XY='(5325,2400)',
 ROT='0',
 VER='1',
 PACK_TYPE='0402',
 LOCATION='PC274_P0_4',
 CDS_LIB='pure_quanta',
 CDS_PART_NAME='Q_CAP_0402-3300PF,50V,10%,X7R,A',
 TOLERANCE='10%',
 MATERIAL='X7R',
 VOLTAGE='50V',
 VALUE='3300PF',
 PRIM_FILE='./archive_libs/logical/q_cap/chips/chips.prt';

PART_NAME
 PC275_P0_3 'Q_CAP_0402-3300PF,50V,10%,X7R,A':;

SECTION_NUMBER 1
 '@S9S_MB_2U_LIB.S9S_MB_2U(SCH_1):PAGE254_I48@PURE_QUANTA.Q_CAP(CHIPS)':
 C_PATH='@s9s_mb_2u_lib.s9s_mb_2u(sch_1):page254_i48@pure_quanta.q_cap(chips)',
 P_PATH='@s9s_mb_2u_lib.s9s_mb_2u(sch_1):page268_i48@pure_quanta.q_cap(chips)',
 PATH='I48',
 DRAWING='@S9S_MB_2U_LIB.S9S_MB_2U(SCH_1):PAGE254',
 PHYS_PAGE='268',
 XY='(5350,5225)',
 ROT='0',
 VER='1',
 PACK_TYPE='0402',
 LOCATION='PC275_P0_3',
 CDS_LIB='pure_quanta',
 CDS_PART_NAME='Q_CAP_0402-3300PF,50V,10%,X7R,A',
 TOLERANCE='10%',
 MATERIAL='X7R',
 VOLTAGE='50V',
 VALUE='3300PF',
 PRIM_FILE='./archive_libs/logical/q_cap/chips/chips.prt';

PART_NAME
 PC276_P0_4 'Q_CAP_C0402-1UF,16V,10%,X6S,CHA':;

SECTION_NUMBER 1
 '@S9S_MB_2U_LIB.S9S_MB_2U(SCH_1):PAGE254_I38@PURE_QUANTA.Q_CAP(CHIPS)':
 C_PATH='@s9s_mb_2u_lib.s9s_mb_2u(sch_1):page254_i38@pure_quanta.q_cap(chips)',
 P_PATH='@s9s_mb_2u_lib.s9s_mb_2u(sch_1):page268_i38@pure_quanta.q_cap(chips)',
 PATH='I38',
 DRAWING='@S9S_MB_2U_LIB.S9S_MB_2U(SCH_1):PAGE254',
 PHYS_PAGE='268',
 XY='(5725,2400)',
 ROT='0',
 VER='1',
 PACK_TYPE='C0402',
 LOCATION='PC276_P0_4',
 CDS_LIB='pure_quanta',
 CDS_PART_NAME='Q_CAP_C0402-1UF,16V,10%,X6S,CHA',
 TOLERANCE='10%',
 MATERIAL='X6S',
 VOLTAGE='16V',
 VALUE='1UF',
 PRIM_FILE='./archive_libs/logical/q_cap/chips/chips.prt';

PART_NAME
 PC277_P0_3 'Q_CAP_C0402-1UF,16V,10%,X6S,CHA':;

SECTION_NUMBER 1
 '@S9S_MB_2U_LIB.S9S_MB_2U(SCH_1):PAGE254_I52@PURE_QUANTA.Q_CAP(CHIPS)':
 C_PATH='@s9s_mb_2u_lib.s9s_mb_2u(sch_1):page254_i52@pure_quanta.q_cap(chips)',
 P_PATH='@s9s_mb_2u_lib.s9s_mb_2u(sch_1):page268_i52@pure_quanta.q_cap(chips)',
 PATH='I52',
 DRAWING='@S9S_MB_2U_LIB.S9S_MB_2U(SCH_1):PAGE254',
 PHYS_PAGE='268',
 XY='(5750,5225)',
 ROT='0',
 VER='1',
 PACK_TYPE='C0402',
 LOCATION='PC277_P0_3',
 CDS_LIB='pure_quanta',
 CDS_PART_NAME='Q_CAP_C0402-1UF,16V,10%,X6S,CHA',
 TOLERANCE='10%',
 MATERIAL='X6S',
 VOLTAGE='16V',
 VALUE='1UF',
 PRIM_FILE='./archive_libs/logical/q_cap/chips/chips.prt';

PART_NAME
 PC278 'Q_CAP_C0402-100NF,50V,10%,X7R,A':;

SECTION_NUMBER 1
 '@S9S_MB_2U_LIB.S9S_MB_2U(SCH_1):PAGE254_I34@PURE_QUANTA.Q_CAP(CHIPS)':
 C_PATH='@s9s_mb_2u_lib.s9s_mb_2u(sch_1):page254_i34@pure_quanta.q_cap(chips)',
 P_PATH='@s9s_mb_2u_lib.s9s_mb_2u(sch_1):page268_i34@pure_quanta.q_cap(chips)',
 PATH='I34',
 DRAWING='@S9S_MB_2U_LIB.S9S_MB_2U(SCH_1):PAGE254',
 PHYS_PAGE='268',
 XY='(6500,1775)',
 ROT='2',
 VER='1',
 PACK_TYPE='C0402',
 LOCATION='PC278',
 CDS_LIB='pure_quanta',
 CDS_PART_NAME='Q_CAP_C0402-100NF,50V,10%,X7R,A',
 TOLERANCE='10%',
 MATERIAL='X7R',
 VOLTAGE='50V',
 VALUE='100NF',
 PRIM_FILE='./archive_libs/logical/q_cap/chips/chips.prt';

PART_NAME
 PC279 'Q_CAP_C0402-100NF,50V,10%,X7R,A':;

SECTION_NUMBER 1
 '@S9S_MB_2U_LIB.S9S_MB_2U(SCH_1):PAGE254_I51@PURE_QUANTA.Q_CAP(CHIPS)':
 C_PATH='@s9s_mb_2u_lib.s9s_mb_2u(sch_1):page254_i51@pure_quanta.q_cap(chips)',
 P_PATH='@s9s_mb_2u_lib.s9s_mb_2u(sch_1):page268_i51@pure_quanta.q_cap(chips)',
 PATH='I51',
 DRAWING='@S9S_MB_2U_LIB.S9S_MB_2U(SCH_1):PAGE254',
 PHYS_PAGE='268',
 XY='(6525,4600)',
 ROT='2',
 VER='1',
 PACK_TYPE='C0402',
 LOCATION='PC279',
 CDS_LIB='pure_quanta',
 CDS_PART_NAME='Q_CAP_C0402-100NF,50V,10%,X7R,A',
 TOLERANCE='10%',
 MATERIAL='X7R',
 VOLTAGE='50V',
 VALUE='100NF',
 PRIM_FILE='./archive_libs/logical/q_cap/chips/chips.prt';

PART_NAME
 PC280_P0_4 'Q_CAP_C0805-22UF,16V,20%,X6S,CA':;

SECTION_NUMBER 1
 '@S9S_MB_2U_LIB.S9S_MB_2U(SCH_1):PAGE254_I39@PURE_QUANTA.Q_CAP(CHIPS)':
 C_PATH='@s9s_mb_2u_lib.s9s_mb_2u(sch_1):page254_i39@pure_quanta.q_cap(chips)',
 P_PATH='@s9s_mb_2u_lib.s9s_mb_2u(sch_1):page268_i39@pure_quanta.q_cap(chips)',
 PATH='I39',
 DRAWING='@S9S_MB_2U_LIB.S9S_MB_2U(SCH_1):PAGE254',
 PHYS_PAGE='268',
 XY='(6125,2400)',
 ROT='0',
 VER='1',
 PACK_TYPE='C0805',
 LOCATION='PC280_P0_4',
 CDS_LIB='pure_quanta',
 CDS_PART_NAME='Q_CAP_C0805-22UF,16V,20%,X6S,CA',
 TOLERANCE='20%',
 MATERIAL='X6S',
 VOLTAGE='16V',
 VALUE='22UF',
 PRIM_FILE='./archive_libs/logical/q_cap/chips/chips.prt';

PART_NAME
 PC281_P0_3 'Q_CAP_C0805-22UF,16V,20%,X6S,CA':;

SECTION_NUMBER 1
 '@S9S_MB_2U_LIB.S9S_MB_2U(SCH_1):PAGE254_I53@PURE_QUANTA.Q_CAP(CHIPS)':
 C_PATH='@s9s_mb_2u_lib.s9s_mb_2u(sch_1):page254_i53@pure_quanta.q_cap(chips)',
 P_PATH='@s9s_mb_2u_lib.s9s_mb_2u(sch_1):page268_i53@pure_quanta.q_cap(chips)',
 PATH='I53',
 DRAWING='@S9S_MB_2U_LIB.S9S_MB_2U(SCH_1):PAGE254',
 PHYS_PAGE='268',
 XY='(6150,5225)',
 ROT='0',
 VER='1',
 PACK_TYPE='C0805',
 LOCATION='PC281_P0_3',
 CDS_LIB='pure_quanta',
 CDS_PART_NAME='Q_CAP_C0805-22UF,16V,20%,X6S,CA',
 TOLERANCE='20%',
 MATERIAL='X6S',
 VOLTAGE='16V',
 VALUE='22UF',
 PRIM_FILE='./archive_libs/logical/q_cap/chips/chips.prt';

PART_NAME
 PC282_P0_4 'Q_CAP_C0805-22UF,16V,20%,X6S,CA':;

SECTION_NUMBER 1
 '@S9S_MB_2U_LIB.S9S_MB_2U(SCH_1):PAGE254_I40@PURE_QUANTA.Q_CAP(CHIPS)':
 C_PATH='@s9s_mb_2u_lib.s9s_mb_2u(sch_1):page254_i40@pure_quanta.q_cap(chips)',
 P_PATH='@s9s_mb_2u_lib.s9s_mb_2u(sch_1):page268_i40@pure_quanta.q_cap(chips)',
 PATH='I40',
 DRAWING='@S9S_MB_2U_LIB.S9S_MB_2U(SCH_1):PAGE254',
 PHYS_PAGE='268',
 XY='(6525,2400)',
 ROT='0',
 VER='1',
 PACK_TYPE='C0805',
 LOCATION='PC282_P0_4',
 CDS_LIB='pure_quanta',
 CDS_PART_NAME='Q_CAP_C0805-22UF,16V,20%,X6S,CA',
 TOLERANCE='20%',
 MATERIAL='X6S',
 VOLTAGE='16V',
 VALUE='22UF',
 PRIM_FILE='./archive_libs/logical/q_cap/chips/chips.prt';

PART_NAME
 PC283_P0_3 'Q_CAP_C0805-22UF,16V,20%,X6S,CA':;

SECTION_NUMBER 1
 '@S9S_MB_2U_LIB.S9S_MB_2U(SCH_1):PAGE254_I54@PURE_QUANTA.Q_CAP(CHIPS)':
 C_PATH='@s9s_mb_2u_lib.s9s_mb_2u(sch_1):page254_i54@pure_quanta.q_cap(chips)',
 P_PATH='@s9s_mb_2u_lib.s9s_mb_2u(sch_1):page268_i54@pure_quanta.q_cap(chips)',
 PATH='I54',
 DRAWING='@S9S_MB_2U_LIB.S9S_MB_2U(SCH_1):PAGE254',
 PHYS_PAGE='268',
 XY='(6550,5225)',
 ROT='0',
 VER='1',
 PACK_TYPE='C0805',
 LOCATION='PC283_P0_3',
 CDS_LIB='pure_quanta',
 CDS_PART_NAME='Q_CAP_C0805-22UF,16V,20%,X6S,CA',
 TOLERANCE='20%',
 MATERIAL='X6S',
 VOLTAGE='16V',
 VALUE='22UF',
 PRIM_FILE='./archive_libs/logical/q_cap/chips/chips.prt';

PART_NAME
 PC284_P0_4 'Q_CAP_C0805-22UF,16V,20%,X6S,CA':;

SECTION_NUMBER 1
 '@S9S_MB_2U_LIB.S9S_MB_2U(SCH_1):PAGE254_I43@PURE_QUANTA.Q_CAP(CHIPS)':
 C_PATH='@s9s_mb_2u_lib.s9s_mb_2u(sch_1):page254_i43@pure_quanta.q_cap(chips)',
 P_PATH='@s9s_mb_2u_lib.s9s_mb_2u(sch_1):page268_i43@pure_quanta.q_cap(chips)',
 PATH='I43',
 DRAWING='@S9S_MB_2U_LIB.S9S_MB_2U(SCH_1):PAGE254',
 PHYS_PAGE='268',
 XY='(6900,2400)',
 ROT='0',
 VER='1',
 PACK_TYPE='C0805',
 LOCATION='PC284_P0_4',
 CDS_LIB='pure_quanta',
 CDS_PART_NAME='Q_CAP_C0805-22UF,16V,20%,X6S,CA',
 TOLERANCE='20%',
 MATERIAL='X6S',
 VOLTAGE='16V',
 VALUE='22UF',
 PRIM_FILE='./archive_libs/logical/q_cap/chips/chips.prt';

PART_NAME
 PC285_P0_3 'Q_CAP_C0805-22UF,16V,20%,X6S,CA':;

SECTION_NUMBER 1
 '@S9S_MB_2U_LIB.S9S_MB_2U(SCH_1):PAGE254_I56@PURE_QUANTA.Q_CAP(CHIPS)':
 C_PATH='@s9s_mb_2u_lib.s9s_mb_2u(sch_1):page254_i56@pure_quanta.q_cap(chips)',
 P_PATH='@s9s_mb_2u_lib.s9s_mb_2u(sch_1):page268_i56@pure_quanta.q_cap(chips)',
 PATH='I56',
 DRAWING='@S9S_MB_2U_LIB.S9S_MB_2U(SCH_1):PAGE254',
 PHYS_PAGE='268',
 XY='(6925,5225)',
 ROT='0',
 VER='1',
 PACK_TYPE='C0805',
 LOCATION='PC285_P0_3',
 CDS_LIB='pure_quanta',
 CDS_PART_NAME='Q_CAP_C0805-22UF,16V,20%,X6S,CA',
 TOLERANCE='20%',
 MATERIAL='X6S',
 VOLTAGE='16V',
 VALUE='22UF',
 PRIM_FILE='./archive_libs/logical/q_cap/chips/chips.prt';

PART_NAME
 PC288_P0_4 'Q_CAP_C0805-22UF,4V,20%,X6S,CHA':;

SECTION_NUMBER 1
 '@S9S_MB_2U_LIB.S9S_MB_2U(SCH_1):PAGE254_I60@PURE_QUANTA.Q_CAP(CHIPS)':
 C_PATH='@s9s_mb_2u_lib.s9s_mb_2u(sch_1):page254_i60@pure_quanta.q_cap(chips)',
 P_PATH='@s9s_mb_2u_lib.s9s_mb_2u(sch_1):page268_i60@pure_quanta.q_cap(chips)',
 PATH='I60',
 DRAWING='@S9S_MB_2U_LIB.S9S_MB_2U(SCH_1):PAGE254',
 PHYS_PAGE='268',
 XY='(8775,1300)',
 ROT='0',
 VER='1',
 PACK_TYPE='C0805',
 LOCATION='PC288_P0_4',
 CDS_LIB='pure_quanta',
 CDS_PART_NAME='Q_CAP_C0805-22UF,4V,20%,X6S,CHA',
 TOLERANCE='20%',
 MATERIAL='X6S',
 VOLTAGE='4V',
 VALUE='22UF',
 PRIM_FILE='./archive_libs/logical/q_cap/chips/chips.prt';

PART_NAME
 PC289_P0_3 'Q_CAP_C0805-22UF,4V,20%,X6S,CHA':;

SECTION_NUMBER 1
 '@S9S_MB_2U_LIB.S9S_MB_2U(SCH_1):PAGE254_I59@PURE_QUANTA.Q_CAP(CHIPS)':
 C_PATH='@s9s_mb_2u_lib.s9s_mb_2u(sch_1):page254_i59@pure_quanta.q_cap(chips)',
 P_PATH='@s9s_mb_2u_lib.s9s_mb_2u(sch_1):page268_i59@pure_quanta.q_cap(chips)',
 PATH='I59',
 DRAWING='@S9S_MB_2U_LIB.S9S_MB_2U(SCH_1):PAGE254',
 PHYS_PAGE='268',
 XY='(8750,4125)',
 ROT='0',
 VER='1',
 PACK_TYPE='C0805',
 LOCATION='PC289_P0_3',
 CDS_LIB='pure_quanta',
 CDS_PART_NAME='Q_CAP_C0805-22UF,4V,20%,X6S,CHA',
 TOLERANCE='20%',
 MATERIAL='X6S',
 VOLTAGE='4V',
 VALUE='22UF',
 PRIM_FILE='./archive_libs/logical/q_cap/chips/chips.prt';

PART_NAME
 PC290_P0_4 'Q_CAP_C0805-22UF,4V,20%,X6S,CHA':;

SECTION_NUMBER 1
 '@S9S_MB_2U_LIB.S9S_MB_2U(SCH_1):PAGE254_I61@PURE_QUANTA.Q_CAP(CHIPS)':
 C_PATH='@s9s_mb_2u_lib.s9s_mb_2u(sch_1):page254_i61@pure_quanta.q_cap(chips)',
 P_PATH='@s9s_mb_2u_lib.s9s_mb_2u(sch_1):page268_i61@pure_quanta.q_cap(chips)',
 PATH='I61',
 DRAWING='@S9S_MB_2U_LIB.S9S_MB_2U(SCH_1):PAGE254',
 PHYS_PAGE='268',
 XY='(9200,1300)',
 ROT='0',
 VER='1',
 PACK_TYPE='C0805',
 LOCATION='PC290_P0_4',
 CDS_LIB='pure_quanta',
 CDS_PART_NAME='Q_CAP_C0805-22UF,4V,20%,X6S,CHA',
 TOLERANCE='20%',
 MATERIAL='X6S',
 VOLTAGE='4V',
 VALUE='22UF',
 PRIM_FILE='./archive_libs/logical/q_cap/chips/chips.prt';

PART_NAME
 PC291_P0_3 'Q_CAP_C0805-22UF,4V,20%,X6S,CHA':;

SECTION_NUMBER 1
 '@S9S_MB_2U_LIB.S9S_MB_2U(SCH_1):PAGE254_I65@PURE_QUANTA.Q_CAP(CHIPS)':
 C_PATH='@s9s_mb_2u_lib.s9s_mb_2u(sch_1):page254_i65@pure_quanta.q_cap(chips)',
 P_PATH='@s9s_mb_2u_lib.s9s_mb_2u(sch_1):page268_i65@pure_quanta.q_cap(chips)',
 PATH='I65',
 DRAWING='@S9S_MB_2U_LIB.S9S_MB_2U(SCH_1):PAGE254',
 PHYS_PAGE='268',
 XY='(9175,4125)',
 ROT='0',
 VER='1',
 PACK_TYPE='C0805',
 LOCATION='PC291_P0_3',
 CDS_LIB='pure_quanta',
 CDS_PART_NAME='Q_CAP_C0805-22UF,4V,20%,X6S,CHA',
 TOLERANCE='20%',
 MATERIAL='X6S',
 VOLTAGE='4V',
 VALUE='22UF',
 PRIM_FILE='./archive_libs/logical/q_cap/chips/chips.prt';

PART_NAME
 PC292 'Q_CAP_C0402-2.2UF,10V,10%,X6S,A':;

SECTION_NUMBER 1
 '@S9S_MB_2U_LIB.S9S_MB_2U(SCH_1):PAGE253_I9@PURE_QUANTA.Q_CAP(CHIPS)':
 C_PATH='@s9s_mb_2u_lib.s9s_mb_2u(sch_1):page253_i9@pure_quanta.q_cap(chips)',
 P_PATH='@s9s_mb_2u_lib.s9s_mb_2u(sch_1):page267_i9@pure_quanta.q_cap(chips)',
 PATH='I9',
 DRAWING='@S9S_MB_2U_LIB.S9S_MB_2U(SCH_1):PAGE253',
 PHYS_PAGE='267',
 XY='(-3800,-1625)',
 ROT='0',
 VER='1',
 PACK_TYPE='C0402',
 LOCATION='PC292',
 CDS_LIB='pure_quanta',
 CDS_PART_NAME='Q_CAP_C0402-2.2UF,10V,10%,X6S,A',
 TOLERANCE='10%',
 MATERIAL='X6S',
 VOLTAGE='10V',
 VALUE='2.2UF',
 PRIM_FILE='./archive_libs/logical/q_cap/chips/chips.prt';

PART_NAME
 PC293 'Q_CAP_C0402-2.2UF,10V,10%,X6S,A':;

SECTION_NUMBER 1
 '@S9S_MB_2U_LIB.S9S_MB_2U(SCH_1):PAGE253_I36@PURE_QUANTA.Q_CAP(CHIPS)':
 C_PATH='@s9s_mb_2u_lib.s9s_mb_2u(sch_1):page253_i36@pure_quanta.q_cap(chips)',
 P_PATH='@s9s_mb_2u_lib.s9s_mb_2u(sch_1):page267_i36@pure_quanta.q_cap(chips)',
 PATH='I36',
 DRAWING='@S9S_MB_2U_LIB.S9S_MB_2U(SCH_1):PAGE253',
 PHYS_PAGE='267',
 XY='(-3775,1200)',
 ROT='0',
 VER='1',
 PACK_TYPE='C0402',
 LOCATION='PC293',
 CDS_LIB='pure_quanta',
 CDS_PART_NAME='Q_CAP_C0402-2.2UF,10V,10%,X6S,A',
 TOLERANCE='10%',
 MATERIAL='X6S',
 VOLTAGE='10V',
 VALUE='2.2UF',
 PRIM_FILE='./archive_libs/logical/q_cap/chips/chips.prt';

PART_NAME
 PC294_P0_2 'Q_CAP_C0402-2.2UF,10V,10%,X6S,A':;

SECTION_NUMBER 1
 '@S9S_MB_2U_LIB.S9S_MB_2U(SCH_1):PAGE253_I15@PURE_QUANTA.Q_CAP(CHIPS)':
 C_PATH='@s9s_mb_2u_lib.s9s_mb_2u(sch_1):page253_i15@pure_quanta.q_cap(chips)',
 P_PATH='@s9s_mb_2u_lib.s9s_mb_2u(sch_1):page267_i15@pure_quanta.q_cap(chips)',
 PATH='I15',
 DRAWING='@S9S_MB_2U_LIB.S9S_MB_2U(SCH_1):PAGE253',
 PHYS_PAGE='267',
 XY='(-3375,-1125)',
 ROT='0',
 VER='1',
 PACK_TYPE='C0402',
 LOCATION='PC294_P0_2',
 CDS_LIB='pure_quanta',
 CDS_PART_NAME='Q_CAP_C0402-2.2UF,10V,10%,X6S,A',
 TOLERANCE='10%',
 MATERIAL='X6S',
 VOLTAGE='10V',
 VALUE='2.2UF',
 PRIM_FILE='./archive_libs/logical/q_cap/chips/chips.prt';

PART_NAME
 PC295_P0_1 'Q_CAP_C0402-2.2UF,10V,10%,X6S,A':;

SECTION_NUMBER 1
 '@S9S_MB_2U_LIB.S9S_MB_2U(SCH_1):PAGE253_I39@PURE_QUANTA.Q_CAP(CHIPS)':
 C_PATH='@s9s_mb_2u_lib.s9s_mb_2u(sch_1):page253_i39@pure_quanta.q_cap(chips)',
 P_PATH='@s9s_mb_2u_lib.s9s_mb_2u(sch_1):page267_i39@pure_quanta.q_cap(chips)',
 PATH='I39',
 DRAWING='@S9S_MB_2U_LIB.S9S_MB_2U(SCH_1):PAGE253',
 PHYS_PAGE='267',
 XY='(-3350,1700)',
 ROT='0',
 VER='1',
 PACK_TYPE='C0402',
 LOCATION='PC295_P0_1',
 CDS_LIB='pure_quanta',
 CDS_PART_NAME='Q_CAP_C0402-2.2UF,10V,10%,X6S,A',
 TOLERANCE='10%',
 MATERIAL='X6S',
 VOLTAGE='10V',
 VALUE='2.2UF',
 PRIM_FILE='./archive_libs/logical/q_cap/chips/chips.prt';

PART_NAME
 PC296_P0_2 'Q_CAP_0402-3300PF,50V,10%,X7R,A':;

SECTION_NUMBER 1
 '@S9S_MB_2U_LIB.S9S_MB_2U(SCH_1):PAGE253_I19@PURE_QUANTA.Q_CAP(CHIPS)':
 C_PATH='@s9s_mb_2u_lib.s9s_mb_2u(sch_1):page253_i19@pure_quanta.q_cap(chips)',
 P_PATH='@s9s_mb_2u_lib.s9s_mb_2u(sch_1):page267_i19@pure_quanta.q_cap(chips)',
 PATH='I19',
 DRAWING='@S9S_MB_2U_LIB.S9S_MB_2U(SCH_1):PAGE253',
 PHYS_PAGE='267',
 XY='(-1475,-1225)',
 ROT='0',
 VER='1',
 PACK_TYPE='0402',
 LOCATION='PC296_P0_2',
 CDS_LIB='pure_quanta',
 CDS_PART_NAME='Q_CAP_0402-3300PF,50V,10%,X7R,A',
 TOLERANCE='10%',
 MATERIAL='X7R',
 VOLTAGE='50V',
 VALUE='3300PF',
 PRIM_FILE='./archive_libs/logical/q_cap/chips/chips.prt';

PART_NAME
 PC297_P0_1 'Q_CAP_0402-3300PF,50V,10%,X7R,A':;

SECTION_NUMBER 1
 '@S9S_MB_2U_LIB.S9S_MB_2U(SCH_1):PAGE253_I44@PURE_QUANTA.Q_CAP(CHIPS)':
 C_PATH='@s9s_mb_2u_lib.s9s_mb_2u(sch_1):page253_i44@pure_quanta.q_cap(chips)',
 P_PATH='@s9s_mb_2u_lib.s9s_mb_2u(sch_1):page267_i44@pure_quanta.q_cap(chips)',
 PATH='I44',
 DRAWING='@S9S_MB_2U_LIB.S9S_MB_2U(SCH_1):PAGE253',
 PHYS_PAGE='267',
 XY='(-1375,1600)',
 ROT='0',
 VER='1',
 PACK_TYPE='0402',
 LOCATION='PC297_P0_1',
 CDS_LIB='pure_quanta',
 CDS_PART_NAME='Q_CAP_0402-3300PF,50V,10%,X7R,A',
 TOLERANCE='10%',
 MATERIAL='X7R',
 VOLTAGE='50V',
 VALUE='3300PF',
 PRIM_FILE='./archive_libs/logical/q_cap/chips/chips.prt';

PART_NAME
 PC298_P0_2 'Q_CAP_C0402-1UF,16V,10%,X6S,CHA':;

SECTION_NUMBER 1
 '@S9S_MB_2U_LIB.S9S_MB_2U(SCH_1):PAGE253_I22@PURE_QUANTA.Q_CAP(CHIPS)':
 C_PATH='@s9s_mb_2u_lib.s9s_mb_2u(sch_1):page253_i22@pure_quanta.q_cap(chips)',
 P_PATH='@s9s_mb_2u_lib.s9s_mb_2u(sch_1):page267_i22@pure_quanta.q_cap(chips)',
 PATH='I22',
 DRAWING='@S9S_MB_2U_LIB.S9S_MB_2U(SCH_1):PAGE253',
 PHYS_PAGE='267',
 XY='(-1075,-1225)',
 ROT='0',
 VER='1',
 PACK_TYPE='C0402',
 LOCATION='PC298_P0_2',
 CDS_LIB='pure_quanta',
 CDS_PART_NAME='Q_CAP_C0402-1UF,16V,10%,X6S,CHA',
 TOLERANCE='10%',
 MATERIAL='X6S',
 VOLTAGE='16V',
 VALUE='1UF',
 PRIM_FILE='./archive_libs/logical/q_cap/chips/chips.prt';

PART_NAME
 PC299_P0_1 'Q_CAP_C0402-1UF,16V,10%,X6S,CHA':;

SECTION_NUMBER 1
 '@S9S_MB_2U_LIB.S9S_MB_2U(SCH_1):PAGE253_I47@PURE_QUANTA.Q_CAP(CHIPS)':
 C_PATH='@s9s_mb_2u_lib.s9s_mb_2u(sch_1):page253_i47@pure_quanta.q_cap(chips)',
 P_PATH='@s9s_mb_2u_lib.s9s_mb_2u(sch_1):page267_i47@pure_quanta.q_cap(chips)',
 PATH='I47',
 DRAWING='@S9S_MB_2U_LIB.S9S_MB_2U(SCH_1):PAGE253',
 PHYS_PAGE='267',
 XY='(-975,1600)',
 ROT='0',
 VER='1',
 PACK_TYPE='C0402',
 LOCATION='PC299_P0_1',
 CDS_LIB='pure_quanta',
 CDS_PART_NAME='Q_CAP_C0402-1UF,16V,10%,X6S,CHA',
 TOLERANCE='10%',
 MATERIAL='X6S',
 VOLTAGE='16V',
 VALUE='1UF',
 PRIM_FILE='./archive_libs/logical/q_cap/chips/chips.prt';

PART_NAME
 PC300 'Q_CAP_C0402-100NF,50V,10%,X7R,A':;

SECTION_NUMBER 1
 '@S9S_MB_2U_LIB.S9S_MB_2U(SCH_1):PAGE253_I20@PURE_QUANTA.Q_CAP(CHIPS)':
 C_PATH='@s9s_mb_2u_lib.s9s_mb_2u(sch_1):page253_i20@pure_quanta.q_cap(chips)',
 P_PATH='@s9s_mb_2u_lib.s9s_mb_2u(sch_1):page267_i20@pure_quanta.q_cap(chips)',
 PATH='I20',
 DRAWING='@S9S_MB_2U_LIB.S9S_MB_2U(SCH_1):PAGE253',
 PHYS_PAGE='267',
 XY='(-225,-1875)',
 ROT='2',
 VER='1',
 PACK_TYPE='C0402',
 LOCATION='PC300',
 CDS_LIB='pure_quanta',
 CDS_PART_NAME='Q_CAP_C0402-100NF,50V,10%,X7R,A',
 TOLERANCE='10%',
 MATERIAL='X7R',
 VOLTAGE='50V',
 VALUE='100NF',
 PRIM_FILE='./archive_libs/logical/q_cap/chips/chips.prt';

PART_NAME
 PC301 'Q_CAP_C0402-100NF,50V,10%,X7R,A':;

SECTION_NUMBER 1
 '@S9S_MB_2U_LIB.S9S_MB_2U(SCH_1):PAGE253_I48@PURE_QUANTA.Q_CAP(CHIPS)':
 C_PATH='@s9s_mb_2u_lib.s9s_mb_2u(sch_1):page253_i48@pure_quanta.q_cap(chips)',
 P_PATH='@s9s_mb_2u_lib.s9s_mb_2u(sch_1):page267_i48@pure_quanta.q_cap(chips)',
 PATH='I48',
 DRAWING='@S9S_MB_2U_LIB.S9S_MB_2U(SCH_1):PAGE253',
 PHYS_PAGE='267',
 XY='(-275,975)',
 ROT='2',
 VER='1',
 PACK_TYPE='C0402',
 LOCATION='PC301',
 CDS_LIB='pure_quanta',
 CDS_PART_NAME='Q_CAP_C0402-100NF,50V,10%,X7R,A',
 TOLERANCE='10%',
 MATERIAL='X7R',
 VOLTAGE='50V',
 VALUE='100NF',
 PRIM_FILE='./archive_libs/logical/q_cap/chips/chips.prt';

PART_NAME
 PC302_P0_2 'Q_CAP_C0805-22UF,16V,20%,X6S,CA':;

SECTION_NUMBER 1
 '@S9S_MB_2U_LIB.S9S_MB_2U(SCH_1):PAGE253_I23@PURE_QUANTA.Q_CAP(CHIPS)':
 C_PATH='@s9s_mb_2u_lib.s9s_mb_2u(sch_1):page253_i23@pure_quanta.q_cap(chips)',
 P_PATH='@s9s_mb_2u_lib.s9s_mb_2u(sch_1):page267_i23@pure_quanta.q_cap(chips)',
 PATH='I23',
 DRAWING='@S9S_MB_2U_LIB.S9S_MB_2U(SCH_1):PAGE253',
 PHYS_PAGE='267',
 XY='(-675,-1225)',
 ROT='0',
 VER='1',
 PACK_TYPE='C0805',
 LOCATION='PC302_P0_2',
 CDS_LIB='pure_quanta',
 CDS_PART_NAME='Q_CAP_C0805-22UF,16V,20%,X6S,CA',
 TOLERANCE='20%',
 MATERIAL='X6S',
 VOLTAGE='16V',
 VALUE='22UF',
 PRIM_FILE='./archive_libs/logical/q_cap/chips/chips.prt';

PART_NAME
 PC303_P0_1 'Q_CAP_C0805-22UF,16V,20%,X6S,CA':;

SECTION_NUMBER 1
 '@S9S_MB_2U_LIB.S9S_MB_2U(SCH_1):PAGE253_I49@PURE_QUANTA.Q_CAP(CHIPS)':
 C_PATH='@s9s_mb_2u_lib.s9s_mb_2u(sch_1):page253_i49@pure_quanta.q_cap(chips)',
 P_PATH='@s9s_mb_2u_lib.s9s_mb_2u(sch_1):page267_i49@pure_quanta.q_cap(chips)',
 PATH='I49',
 DRAWING='@S9S_MB_2U_LIB.S9S_MB_2U(SCH_1):PAGE253',
 PHYS_PAGE='267',
 XY='(-575,1600)',
 ROT='0',
 VER='1',
 PACK_TYPE='C0805',
 LOCATION='PC303_P0_1',
 CDS_LIB='pure_quanta',
 CDS_PART_NAME='Q_CAP_C0805-22UF,16V,20%,X6S,CA',
 TOLERANCE='20%',
 MATERIAL='X6S',
 VOLTAGE='16V',
 VALUE='22UF',
 PRIM_FILE='./archive_libs/logical/q_cap/chips/chips.prt';

PART_NAME
 PC304_P0_2 'Q_CAP_C0805-22UF,16V,20%,X6S,CA':;

SECTION_NUMBER 1
 '@S9S_MB_2U_LIB.S9S_MB_2U(SCH_1):PAGE253_I24@PURE_QUANTA.Q_CAP(CHIPS)':
 C_PATH='@s9s_mb_2u_lib.s9s_mb_2u(sch_1):page253_i24@pure_quanta.q_cap(chips)',
 P_PATH='@s9s_mb_2u_lib.s9s_mb_2u(sch_1):page267_i24@pure_quanta.q_cap(chips)',
 PATH='I24',
 DRAWING='@S9S_MB_2U_LIB.S9S_MB_2U(SCH_1):PAGE253',
 PHYS_PAGE='267',
 XY='(-275,-1225)',
 ROT='0',
 VER='1',
 PACK_TYPE='C0805',
 LOCATION='PC304_P0_2',
 CDS_LIB='pure_quanta',
 CDS_PART_NAME='Q_CAP_C0805-22UF,16V,20%,X6S,CA',
 TOLERANCE='20%',
 MATERIAL='X6S',
 VOLTAGE='16V',
 VALUE='22UF',
 PRIM_FILE='./archive_libs/logical/q_cap/chips/chips.prt';

PART_NAME
 PC305_P0_1 'Q_CAP_C0805-22UF,16V,20%,X6S,CA':;

SECTION_NUMBER 1
 '@S9S_MB_2U_LIB.S9S_MB_2U(SCH_1):PAGE253_I50@PURE_QUANTA.Q_CAP(CHIPS)':
 C_PATH='@s9s_mb_2u_lib.s9s_mb_2u(sch_1):page253_i50@pure_quanta.q_cap(chips)',
 P_PATH='@s9s_mb_2u_lib.s9s_mb_2u(sch_1):page267_i50@pure_quanta.q_cap(chips)',
 PATH='I50',
 DRAWING='@S9S_MB_2U_LIB.S9S_MB_2U(SCH_1):PAGE253',
 PHYS_PAGE='267',
 XY='(-175,1600)',
 ROT='0',
 VER='1',
 PACK_TYPE='C0805',
 LOCATION='PC305_P0_1',
 CDS_LIB='pure_quanta',
 CDS_PART_NAME='Q_CAP_C0805-22UF,16V,20%,X6S,CA',
 TOLERANCE='20%',
 MATERIAL='X6S',
 VOLTAGE='16V',
 VALUE='22UF',
 PRIM_FILE='./archive_libs/logical/q_cap/chips/chips.prt';

PART_NAME
 PC306_P0_2 'Q_CAP_C0805-22UF,16V,20%,X6S,CA':;

SECTION_NUMBER 1
 '@S9S_MB_2U_LIB.S9S_MB_2U(SCH_1):PAGE253_I54@PURE_QUANTA.Q_CAP(CHIPS)':
 C_PATH='@s9s_mb_2u_lib.s9s_mb_2u(sch_1):page253_i54@pure_quanta.q_cap(chips)',
 P_PATH='@s9s_mb_2u_lib.s9s_mb_2u(sch_1):page267_i54@pure_quanta.q_cap(chips)',
 PATH='I54',
 DRAWING='@S9S_MB_2U_LIB.S9S_MB_2U(SCH_1):PAGE253',
 PHYS_PAGE='267',
 XY='(100,-1225)',
 ROT='0',
 VER='1',
 PACK_TYPE='C0805',
 LOCATION='PC306_P0_2',
 CDS_LIB='pure_quanta',
 CDS_PART_NAME='Q_CAP_C0805-22UF,16V,20%,X6S,CA',
 TOLERANCE='20%',
 MATERIAL='X6S',
 VOLTAGE='16V',
 VALUE='22UF',
 PRIM_FILE='./archive_libs/logical/q_cap/chips/chips.prt';

PART_NAME
 PC307_P0_1 'Q_CAP_C0805-22UF,16V,20%,X6S,CA':;

SECTION_NUMBER 1
 '@S9S_MB_2U_LIB.S9S_MB_2U(SCH_1):PAGE253_I75@PURE_QUANTA.Q_CAP(CHIPS)':
 C_PATH='@s9s_mb_2u_lib.s9s_mb_2u(sch_1):page253_i75@pure_quanta.q_cap(chips)',
 P_PATH='@s9s_mb_2u_lib.s9s_mb_2u(sch_1):page267_i75@pure_quanta.q_cap(chips)',
 PATH='I75',
 DRAWING='@S9S_MB_2U_LIB.S9S_MB_2U(SCH_1):PAGE253',
 PHYS_PAGE='267',
 XY='(200,1600)',
 ROT='0',
 VER='1',
 PACK_TYPE='C0805',
 LOCATION='PC307_P0_1',
 CDS_LIB='pure_quanta',
 CDS_PART_NAME='Q_CAP_C0805-22UF,16V,20%,X6S,CA',
 TOLERANCE='20%',
 MATERIAL='X6S',
 VOLTAGE='16V',
 VALUE='22UF',
 PRIM_FILE='./archive_libs/logical/q_cap/chips/chips.prt';

PART_NAME
 PC308_P0_1 'Q_CAP_C0402-100NF,50V,10%,X7R,A':;

SECTION_NUMBER 1
 '@S9S_MB_2U_LIB.S9S_MB_2U(SCH_1):PAGE253_I83@PURE_QUANTA.Q_CAP(CHIPS)':
 C_PATH='@s9s_mb_2u_lib.s9s_mb_2u(sch_1):page253_i83@pure_quanta.q_cap(chips)',
 P_PATH='@s9s_mb_2u_lib.s9s_mb_2u(sch_1):page267_i83@pure_quanta.q_cap(chips)',
 PATH='I83',
 DRAWING='@S9S_MB_2U_LIB.S9S_MB_2U(SCH_1):PAGE253',
 PHYS_PAGE='267',
 XY='(1975,500)',
 ROT='0',
 VER='1',
 PACK_TYPE='C0402',
 LOCATION='PC308_P0_1',
 CDS_LIB='pure_quanta',
 CDS_PART_NAME='Q_CAP_C0402-100NF,50V,10%,X7R,A',
 TOLERANCE='10%',
 MATERIAL='X7R',
 VOLTAGE='50V',
 VALUE='100NF',
 PRIM_FILE='./archive_libs/logical/q_cap/chips/chips.prt';

PART_NAME
 PC310_P0_1 'Q_CAP_C0402-1UF,16V,10%,X6S,CHA':;

SECTION_NUMBER 1
 '@S9S_MB_2U_LIB.S9S_MB_2U(SCH_1):PAGE253_I84@PURE_QUANTA.Q_CAP(CHIPS)':
 C_PATH='@s9s_mb_2u_lib.s9s_mb_2u(sch_1):page253_i84@pure_quanta.q_cap(chips)',
 P_PATH='@s9s_mb_2u_lib.s9s_mb_2u(sch_1):page267_i84@pure_quanta.q_cap(chips)',
 PATH='I84',
 DRAWING='@S9S_MB_2U_LIB.S9S_MB_2U(SCH_1):PAGE253',
 PHYS_PAGE='267',
 XY='(2375,500)',
 ROT='0',
 VER='1',
 PACK_TYPE='C0402',
 LOCATION='PC310_P0_1',
 CDS_LIB='pure_quanta',
 CDS_PART_NAME='Q_CAP_C0402-1UF,16V,10%,X6S,CHA',
 TOLERANCE='10%',
 MATERIAL='X6S',
 VOLTAGE='16V',
 VALUE='1UF',
 PRIM_FILE='./archive_libs/logical/q_cap/chips/chips.prt';

PART_NAME
 PC311_P0_2 'Q_CAP_C0805-22UF,4V,20%,X6S,CHA':;

SECTION_NUMBER 1
 '@S9S_MB_2U_LIB.S9S_MB_2U(SCH_1):PAGE253_I57@PURE_QUANTA.Q_CAP(CHIPS)':
 C_PATH='@s9s_mb_2u_lib.s9s_mb_2u(sch_1):page253_i57@pure_quanta.q_cap(chips)',
 P_PATH='@s9s_mb_2u_lib.s9s_mb_2u(sch_1):page267_i57@pure_quanta.q_cap(chips)',
 PATH='I57',
 DRAWING='@S9S_MB_2U_LIB.S9S_MB_2U(SCH_1):PAGE253',
 PHYS_PAGE='267',
 XY='(2900,-2450)',
 ROT='0',
 VER='1',
 PACK_TYPE='C0805',
 LOCATION='PC311_P0_2',
 CDS_LIB='pure_quanta',
 CDS_PART_NAME='Q_CAP_C0805-22UF,4V,20%,X6S,CHA',
 TOLERANCE='20%',
 MATERIAL='X6S',
 VOLTAGE='4V',
 VALUE='22UF',
 PRIM_FILE='./archive_libs/logical/q_cap/chips/chips.prt';

PART_NAME
 PC312_P0_1 'Q_CAP_C0805-22UF,4V,20%,X6S,CHA':;

SECTION_NUMBER 1
 '@S9S_MB_2U_LIB.S9S_MB_2U(SCH_1):PAGE253_I85@PURE_QUANTA.Q_CAP(CHIPS)':
 C_PATH='@s9s_mb_2u_lib.s9s_mb_2u(sch_1):page253_i85@pure_quanta.q_cap(chips)',
 P_PATH='@s9s_mb_2u_lib.s9s_mb_2u(sch_1):page267_i85@pure_quanta.q_cap(chips)',
 PATH='I85',
 DRAWING='@S9S_MB_2U_LIB.S9S_MB_2U(SCH_1):PAGE253',
 PHYS_PAGE='267',
 XY='(2800,500)',
 ROT='0',
 VER='1',
 PACK_TYPE='C0805',
 LOCATION='PC312_P0_1',
 CDS_LIB='pure_quanta',
 CDS_PART_NAME='Q_CAP_C0805-22UF,4V,20%,X6S,CHA',
 TOLERANCE='20%',
 MATERIAL='X6S',
 VOLTAGE='4V',
 VALUE='22UF',
 PRIM_FILE='./archive_libs/logical/q_cap/chips/chips.prt';

PART_NAME
 PC313_P0_2 'Q_CAP_C0805-22UF,4V,20%,X6S,CHA':;

SECTION_NUMBER 1
 '@S9S_MB_2U_LIB.S9S_MB_2U(SCH_1):PAGE253_I58@PURE_QUANTA.Q_CAP(CHIPS)':
 C_PATH='@s9s_mb_2u_lib.s9s_mb_2u(sch_1):page253_i58@pure_quanta.q_cap(chips)',
 P_PATH='@s9s_mb_2u_lib.s9s_mb_2u(sch_1):page267_i58@pure_quanta.q_cap(chips)',
 PATH='I58',
 DRAWING='@S9S_MB_2U_LIB.S9S_MB_2U(SCH_1):PAGE253',
 PHYS_PAGE='267',
 XY='(3325,-2450)',
 ROT='0',
 VER='1',
 PACK_TYPE='C0805',
 LOCATION='PC313_P0_2',
 CDS_LIB='pure_quanta',
 CDS_PART_NAME='Q_CAP_C0805-22UF,4V,20%,X6S,CHA',
 TOLERANCE='20%',
 MATERIAL='X6S',
 VOLTAGE='4V',
 VALUE='22UF',
 PRIM_FILE='./archive_libs/logical/q_cap/chips/chips.prt';

PART_NAME
 PC314_P0_1 'Q_CAP_C0805-22UF,4V,20%,X6S,CHA':;

SECTION_NUMBER 1
 '@S9S_MB_2U_LIB.S9S_MB_2U(SCH_1):PAGE253_I86@PURE_QUANTA.Q_CAP(CHIPS)':
 C_PATH='@s9s_mb_2u_lib.s9s_mb_2u(sch_1):page253_i86@pure_quanta.q_cap(chips)',
 P_PATH='@s9s_mb_2u_lib.s9s_mb_2u(sch_1):page267_i86@pure_quanta.q_cap(chips)',
 PATH='I86',
 DRAWING='@S9S_MB_2U_LIB.S9S_MB_2U(SCH_1):PAGE253',
 PHYS_PAGE='267',
 XY='(3225,500)',
 ROT='0',
 VER='1',
 PACK_TYPE='C0805',
 LOCATION='PC314_P0_1',
 CDS_LIB='pure_quanta',
 CDS_PART_NAME='Q_CAP_C0805-22UF,4V,20%,X6S,CHA',
 TOLERANCE='20%',
 MATERIAL='X6S',
 VOLTAGE='4V',
 VALUE='22UF',
 PRIM_FILE='./archive_libs/logical/q_cap/chips/chips.prt';

PART_NAME
 PC315 'Q_CAPP_THLF-270UF,16V,20%,OSCOA':;

SECTION_NUMBER 1
 '@S9S_MB_2U_LIB.S9S_MB_2U(SCH_1):PAGE253_I91@PURE_QUANTA.Q_CAPP(CHIPS)':
 C_PATH='@s9s_mb_2u_lib.s9s_mb_2u(sch_1):page253_i91@pure_quanta.q_capp(chips)',
 P_PATH='@s9s_mb_2u_lib.s9s_mb_2u(sch_1):page267_i91@pure_quanta.q_capp(chips)',
 PATH='I91',
 DRAWING='@S9S_MB_2U_LIB.S9S_MB_2U(SCH_1):PAGE253',
 PHYS_PAGE='267',
 XY='(2350,1825)',
 ROT='0',
 VER='1',
 PACK_TYPE='THLF',
 LOCATION='PC315',
 CDS_LIB='pure_quanta',
 CDS_PART_NAME='Q_CAPP_THLF-270UF,16V,20%,OSCOA',
 TOLERANCE='20%',
 MATERIAL='OSCON',
 VOLTAGE='16V',
 VALUE='270UF',
 PRIM_FILE='./archive_libs/logical/q_capp/chips/chips.prt';

PART_NAME
 PC316 'Q_CAPP_THLF-560UF,2.5V,20%,OSCA':;

SECTION_NUMBER 1
 '@S9S_MB_2U_LIB.S9S_MB_2U(SCH_1):PAGE253_I61@PURE_QUANTA.Q_CAPP(CHIPS)':
 C_PATH='@s9s_mb_2u_lib.s9s_mb_2u(sch_1):page253_i61@pure_quanta.q_capp(chips)',
 P_PATH='@s9s_mb_2u_lib.s9s_mb_2u(sch_1):page267_i61@pure_quanta.q_capp(chips)',
 PATH='I61',
 DRAWING='@S9S_MB_2U_LIB.S9S_MB_2U(SCH_1):PAGE253',
 PHYS_PAGE='267',
 XY='(2425,-550)',
 ROT='0',
 VER='1',
 PACK_TYPE='THLF',
 LOCATION='PC316',
 CDS_LIB='pure_quanta',
 CDS_PART_NAME='Q_CAPP_THLF-560UF,2.5V,20%,OSCA',
 TOLERANCE='20%',
 MATERIAL='OSCON',
 VOLTAGE='2.5V',
 VALUE='560UF',
 PRIM_FILE='./archive_libs/logical/q_capp/chips/chips.prt';

PART_NAME
 PC318 'Q_CAPP_THLF-270UF,16V,20%,OSCOA':;

SECTION_NUMBER 1
 '@S9S_MB_2U_LIB.S9S_MB_2U(SCH_1):PAGE253_I92@PURE_QUANTA.Q_CAPP(CHIPS)':
 C_PATH='@s9s_mb_2u_lib.s9s_mb_2u(sch_1):page253_i92@pure_quanta.q_capp(chips)',
 P_PATH='@s9s_mb_2u_lib.s9s_mb_2u(sch_1):page267_i92@pure_quanta.q_capp(chips)',
 PATH='I92',
 DRAWING='@S9S_MB_2U_LIB.S9S_MB_2U(SCH_1):PAGE253',
 PHYS_PAGE='267',
 XY='(2750,1825)',
 ROT='0',
 VER='1',
 PACK_TYPE='THLF',
 LOCATION='PC318',
 CDS_LIB='pure_quanta',
 CDS_PART_NAME='Q_CAPP_THLF-270UF,16V,20%,OSCOA',
 TOLERANCE='20%',
 MATERIAL='OSCON',
 VOLTAGE='16V',
 VALUE='270UF',
 PRIM_FILE='./archive_libs/logical/q_capp/chips/chips.prt';

PART_NAME
 PC319 'Q_CAPP_THLF-560UF,2.5V,20%,OSCA':;

SECTION_NUMBER 1
 '@S9S_MB_2U_LIB.S9S_MB_2U(SCH_1):PAGE253_I62@PURE_QUANTA.Q_CAPP(CHIPS)':
 C_PATH='@s9s_mb_2u_lib.s9s_mb_2u(sch_1):page253_i62@pure_quanta.q_capp(chips)',
 P_PATH='@s9s_mb_2u_lib.s9s_mb_2u(sch_1):page267_i62@pure_quanta.q_capp(chips)',
 PATH='I62',
 DRAWING='@S9S_MB_2U_LIB.S9S_MB_2U(SCH_1):PAGE253',
 PHYS_PAGE='267',
 XY='(2950,-550)',
 ROT='0',
 VER='1',
 PACK_TYPE='THLF',
 LOCATION='PC319',
 CDS_LIB='pure_quanta',
 CDS_PART_NAME='Q_CAPP_THLF-560UF,2.5V,20%,OSCA',
 TOLERANCE='20%',
 MATERIAL='OSCON',
 VOLTAGE='2.5V',
 VALUE='560UF',
 PRIM_FILE='./archive_libs/logical/q_capp/chips/chips.prt';

PART_NAME
 PC321 'Q_CAPP_THLF-270UF,16V,20%,OSCOA':;

SECTION_NUMBER 1
 '@S9S_MB_2U_LIB.S9S_MB_2U(SCH_1):PAGE253_I93@PURE_QUANTA.Q_CAPP(CHIPS)':
 C_PATH='@s9s_mb_2u_lib.s9s_mb_2u(sch_1):page253_i93@pure_quanta.q_capp(chips)',
 P_PATH='@s9s_mb_2u_lib.s9s_mb_2u(sch_1):page267_i93@pure_quanta.q_capp(chips)',
 PATH='I93',
 DRAWING='@S9S_MB_2U_LIB.S9S_MB_2U(SCH_1):PAGE253',
 PHYS_PAGE='267',
 XY='(3150,1825)',
 ROT='0',
 VER='1',
 PACK_TYPE='THLF',
 LOCATION='PC321',
 CDS_LIB='pure_quanta',
 CDS_PART_NAME='Q_CAPP_THLF-270UF,16V,20%,OSCOA',
 TOLERANCE='20%',
 MATERIAL='OSCON',
 VOLTAGE='16V',
 VALUE='270UF',
 PRIM_FILE='./archive_libs/logical/q_capp/chips/chips.prt';

PART_NAME
 PC322 'Q_CAPP_THLF-560UF,2.5V,20%,OSCA':;

SECTION_NUMBER 1
 '@S9S_MB_2U_LIB.S9S_MB_2U(SCH_1):PAGE253_I67@PURE_QUANTA.Q_CAPP(CHIPS)':
 C_PATH='@s9s_mb_2u_lib.s9s_mb_2u(sch_1):page253_i67@pure_quanta.q_capp(chips)',
 P_PATH='@s9s_mb_2u_lib.s9s_mb_2u(sch_1):page267_i67@pure_quanta.q_capp(chips)',
 PATH='I67',
 DRAWING='@S9S_MB_2U_LIB.S9S_MB_2U(SCH_1):PAGE253',
 PHYS_PAGE='267',
 XY='(3475,-550)',
 ROT='0',
 VER='1',
 PACK_TYPE='THLF',
 LOCATION='PC322',
 CDS_LIB='pure_quanta',
 CDS_PART_NAME='Q_CAPP_THLF-560UF,2.5V,20%,OSCA',
 TOLERANCE='20%',
 MATERIAL='OSCON',
 VOLTAGE='2.5V',
 VALUE='560UF',
 PRIM_FILE='./archive_libs/logical/q_capp/chips/chips.prt';

PART_NAME
 PC323 'Q_CAPP_SMLF-330UF,2.5V,+10/-35A':;

SECTION_NUMBER 1
 '@S9S_MB_2U_LIB.S9S_MB_2U(SCH_1):PAGE253_I64@PURE_QUANTA.Q_CAPP(CHIPS)':
 C_PATH='@s9s_mb_2u_lib.s9s_mb_2u(sch_1):page253_i64@pure_quanta.q_capp(chips)',
 P_PATH='@s9s_mb_2u_lib.s9s_mb_2u(sch_1):page267_i64@pure_quanta.q_capp(chips)',
 PATH='I64',
 DRAWING='@S9S_MB_2U_LIB.S9S_MB_2U(SCH_1):PAGE253',
 PHYS_PAGE='267',
 XY='(3475,-1425)',
 ROT='0',
 VER='1',
 PACK_TYPE='SMLF',
 LOCATION='PC323',
 CDS_LIB='pure_quanta',
 CDS_PART_NAME='Q_CAPP_SMLF-330UF,2.5V,+10/-35A',
 TOLERANCE='+10/-35%',
 MATERIAL='EMPTY',
 VOLTAGE='2.5V',
 VALUE='330UF',
 PRIM_FILE='./archive_libs/logical/q_capp/chips/chips.prt';

PART_NAME
 PC324 'Q_CAPP_THLF-270UF,16V,20%,OSCOA':;

SECTION_NUMBER 1
 '@S9S_MB_2U_LIB.S9S_MB_2U(SCH_1):PAGE253_I94@PURE_QUANTA.Q_CAPP(CHIPS)':
 C_PATH='@s9s_mb_2u_lib.s9s_mb_2u(sch_1):page253_i94@pure_quanta.q_capp(chips)',
 P_PATH='@s9s_mb_2u_lib.s9s_mb_2u(sch_1):page267_i94@pure_quanta.q_capp(chips)',
 PATH='I94',
 DRAWING='@S9S_MB_2U_LIB.S9S_MB_2U(SCH_1):PAGE253',
 PHYS_PAGE='267',
 XY='(3550,1825)',
 ROT='0',
 VER='1',
 PACK_TYPE='THLF',
 LOCATION='PC324',
 CDS_LIB='pure_quanta',
 CDS_PART_NAME='Q_CAPP_THLF-270UF,16V,20%,OSCOA',
 TOLERANCE='20%',
 MATERIAL='OSCON',
 VOLTAGE='16V',
 VALUE='270UF',
 PRIM_FILE='./archive_libs/logical/q_capp/chips/chips.prt';

PART_NAME
 PC325 'Q_CAPP_THLF-560UF,2.5V,20%,OSCA':;

SECTION_NUMBER 1
 '@S9S_MB_2U_LIB.S9S_MB_2U(SCH_1):PAGE253_I70@PURE_QUANTA.Q_CAPP(CHIPS)':
 C_PATH='@s9s_mb_2u_lib.s9s_mb_2u(sch_1):page253_i70@pure_quanta.q_capp(chips)',
 P_PATH='@s9s_mb_2u_lib.s9s_mb_2u(sch_1):page267_i70@pure_quanta.q_capp(chips)',
 PATH='I70',
 DRAWING='@S9S_MB_2U_LIB.S9S_MB_2U(SCH_1):PAGE253',
 PHYS_PAGE='267',
 XY='(3975,-550)',
 ROT='0',
 VER='1',
 PACK_TYPE='THLF',
 LOCATION='PC325',
 CDS_LIB='pure_quanta',
 CDS_PART_NAME='Q_CAPP_THLF-560UF,2.5V,20%,OSCA',
 TOLERANCE='20%',
 MATERIAL='OSCON',
 VOLTAGE='2.5V',
 VALUE='560UF',
 PRIM_FILE='./archive_libs/logical/q_capp/chips/chips.prt';

PART_NAME
 PC326 'Q_CAPP_SMLF-330UF,2.5V,+10/-35A':;

SECTION_NUMBER 1
 '@S9S_MB_2U_LIB.S9S_MB_2U(SCH_1):PAGE253_I66@PURE_QUANTA.Q_CAPP(CHIPS)':
 C_PATH='@s9s_mb_2u_lib.s9s_mb_2u(sch_1):page253_i66@pure_quanta.q_capp(chips)',
 P_PATH='@s9s_mb_2u_lib.s9s_mb_2u(sch_1):page267_i66@pure_quanta.q_capp(chips)',
 PATH='I66',
 DRAWING='@S9S_MB_2U_LIB.S9S_MB_2U(SCH_1):PAGE253',
 PHYS_PAGE='267',
 XY='(3975,-1425)',
 ROT='0',
 VER='1',
 PACK_TYPE='SMLF',
 LOCATION='PC326',
 CDS_LIB='pure_quanta',
 CDS_PART_NAME='Q_CAPP_SMLF-330UF,2.5V,+10/-35A',
 TOLERANCE='+10/-35%',
 MATERIAL='EMPTY',
 VOLTAGE='2.5V',
 VALUE='330UF',
 PRIM_FILE='./archive_libs/logical/q_capp/chips/chips.prt';

PART_NAME
 PC329 'Q_CAP_0402-0.1UF,25V,10%,EMPTYA':;

SECTION_NUMBER 1
 '@S9S_MB_2U_LIB.S9S_MB_2U(SCH_1):PAGE252_I53@PURE_QUANTA.Q_CAP(CHIPS)':
 C_PATH='@s9s_mb_2u_lib.s9s_mb_2u(sch_1):page252_i53@pure_quanta.q_cap(chips)',
 P_PATH='@s9s_mb_2u_lib.s9s_mb_2u(sch_1):page266_i53@pure_quanta.q_cap(chips)',
 PATH='I53',
 DRAWING='@S9S_MB_2U_LIB.S9S_MB_2U(SCH_1):PAGE252',
 PHYS_PAGE='266',
 XY='(-4425,900)',
 ROT='0',
 VER='1',
 PACK_TYPE='0402',
 LOCATION='PC329',
 CDS_LIB='pure_quanta',
 CDS_PART_NAME='Q_CAP_0402-0.1UF,25V,10%,EMPTYA',
 TOLERANCE='10%',
 MATERIAL='EMPTY',
 VOLTAGE='25V',
 VALUE='0.1UF',
 PRIM_FILE='./archive_libs/logical/q_cap/chips/chips.prt';

PART_NAME
 PC330 'Q_CAP_0402-0.1UF,25V,10%,X7R,CA':;

SECTION_NUMBER 1
 '@S9S_MB_2U_LIB.S9S_MB_2U(SCH_1):PAGE252_I61@PURE_QUANTA.Q_CAP(CHIPS)':
 C_PATH='@s9s_mb_2u_lib.s9s_mb_2u(sch_1):page252_i61@pure_quanta.q_cap(chips)',
 P_PATH='@s9s_mb_2u_lib.s9s_mb_2u(sch_1):page266_i61@pure_quanta.q_cap(chips)',
 PATH='I61',
 DRAWING='@S9S_MB_2U_LIB.S9S_MB_2U(SCH_1):PAGE252',
 PHYS_PAGE='266',
 XY='(-3700,900)',
 ROT='0',
 VER='1',
 PACK_TYPE='0402',
 LOCATION='PC330',
 CDS_LIB='pure_quanta',
 CDS_PART_NAME='Q_CAP_0402-0.1UF,25V,10%,X7R,CA',
 TOLERANCE='10%',
 MATERIAL='X7R',
 VOLTAGE='25V',
 VALUE='0.1UF',
 PRIM_FILE='./archive_libs/logical/q_cap/chips/chips.prt';

PART_NAME
 PC331 'Q_CAP_0402-3300PF,50V,10%,X7R,A':;

SECTION_NUMBER 1
 '@S9S_MB_2U_LIB.S9S_MB_2U(SCH_1):PAGE252_I79@PURE_QUANTA.Q_CAP(CHIPS)':
 C_PATH='@s9s_mb_2u_lib.s9s_mb_2u(sch_1):page252_i79@pure_quanta.q_cap(chips)',
 P_PATH='@s9s_mb_2u_lib.s9s_mb_2u(sch_1):page266_i79@pure_quanta.q_cap(chips)',
 PATH='I79',
 DRAWING='@S9S_MB_2U_LIB.S9S_MB_2U(SCH_1):PAGE252',
 PHYS_PAGE='266',
 XY='(-4325,4375)',
 ROT='0',
 VER='1',
 PACK_TYPE='0402',
 LOCATION='PC331',
 CDS_LIB='pure_quanta',
 CDS_PART_NAME='Q_CAP_0402-3300PF,50V,10%,X7R,A',
 TOLERANCE='10%',
 MATERIAL='X7R',
 VOLTAGE='50V',
 VALUE='3300PF',
 PRIM_FILE='./archive_libs/logical/q_cap/chips/chips.prt';

PART_NAME
 PC334 'Q_CAP_0402-0.1UF,25V,10%,EMPTYA':;

SECTION_NUMBER 1
 '@S9S_MB_2U_LIB.S9S_MB_2U(SCH_1):PAGE252_I88@PURE_QUANTA.Q_CAP(CHIPS)':
 C_PATH='@s9s_mb_2u_lib.s9s_mb_2u(sch_1):page252_i88@pure_quanta.q_cap(chips)',
 P_PATH='@s9s_mb_2u_lib.s9s_mb_2u(sch_1):page266_i88@pure_quanta.q_cap(chips)',
 PATH='I88',
 DRAWING='@S9S_MB_2U_LIB.S9S_MB_2U(SCH_1):PAGE252',
 PHYS_PAGE='266',
 XY='(-1450,6350)',
 ROT='0',
 VER='1',
 PACK_TYPE='0402',
 LOCATION='PC334',
 CDS_LIB='pure_quanta',
 CDS_PART_NAME='Q_CAP_0402-0.1UF,25V,10%,EMPTYA',
 TOLERANCE='10%',
 MATERIAL='EMPTY',
 VOLTAGE='25V',
 VALUE='0.1UF',
 PRIM_FILE='./archive_libs/logical/q_cap/chips/chips.prt';

PART_NAME
 PC335 'Q_CAP_C0402-10UF,6.3V,20%,X6S,B':;

SECTION_NUMBER 1
 '@S9S_MB_2U_LIB.S9S_MB_2U(SCH_1):PAGE252_I86@PURE_QUANTA.Q_CAP(CHIPS)':
 C_PATH='@s9s_mb_2u_lib.s9s_mb_2u(sch_1):page252_i86@pure_quanta.q_cap(chips)',
 P_PATH='@s9s_mb_2u_lib.s9s_mb_2u(sch_1):page266_i86@pure_quanta.q_cap(chips)',
 PATH='I86',
 DRAWING='@S9S_MB_2U_LIB.S9S_MB_2U(SCH_1):PAGE252',
 PHYS_PAGE='266',
 XY='(-1500,5875)',
 ROT='0',
 VER='1',
 PACK_TYPE='C0402',
 LOCATION='PC335',
 CDS_LIB='pure_quanta',
 CDS_PART_NAME='Q_CAP_C0402-10UF,6.3V,20%,X6S,B',
 TOLERANCE='20%',
 MATERIAL='X6S',
 VOLTAGE='6.3V',
 VALUE='10UF',
 PRIM_FILE='./archive_libs/logical/q_cap/chips/chips.prt';

PART_NAME
 PC336 'Q_CAP_0402-470PF,50V,10%,X7R,TA':;

SECTION_NUMBER 1
 '@S9S_MB_2U_LIB.S9S_MB_2U(SCH_1):PAGE252_I70@PURE_QUANTA.Q_CAP(CHIPS)':
 C_PATH='@s9s_mb_2u_lib.s9s_mb_2u(sch_1):page252_i70@pure_quanta.q_cap(chips)',
 P_PATH='@s9s_mb_2u_lib.s9s_mb_2u(sch_1):page266_i70@pure_quanta.q_cap(chips)',
 PATH='I70',
 DRAWING='@S9S_MB_2U_LIB.S9S_MB_2U(SCH_1):PAGE252',
 PHYS_PAGE='266',
 XY='(-1800,1150)',
 ROT='0',
 VER='1',
 PACK_TYPE='0402',
 LOCATION='PC336',
 CDS_LIB='pure_quanta',
 CDS_PART_NAME='Q_CAP_0402-470PF,50V,10%,X7R,TA',
 TOLERANCE='10%',
 MATERIAL='X7R',
 VOLTAGE='50V',
 VALUE='470PF',
 PRIM_FILE='./archive_libs/logical/q_cap/chips/chips.prt';

PART_NAME
 PC337 'Q_CAP_C0402-1UF,16V,10%,X6S,CHA':;

SECTION_NUMBER 1
 '@S9S_MB_2U_LIB.S9S_MB_2U(SCH_1):PAGE252_I89@PURE_QUANTA.Q_CAP(CHIPS)':
 C_PATH='@s9s_mb_2u_lib.s9s_mb_2u(sch_1):page252_i89@pure_quanta.q_cap(chips)',
 P_PATH='@s9s_mb_2u_lib.s9s_mb_2u(sch_1):page266_i89@pure_quanta.q_cap(chips)',
 PATH='I89',
 DRAWING='@S9S_MB_2U_LIB.S9S_MB_2U(SCH_1):PAGE252',
 PHYS_PAGE='266',
 XY='(-1100,6350)',
 ROT='0',
 VER='1',
 PACK_TYPE='C0402',
 LOCATION='PC337',
 CDS_LIB='pure_quanta',
 CDS_PART_NAME='Q_CAP_C0402-1UF,16V,10%,X6S,CHA',
 TOLERANCE='10%',
 MATERIAL='X6S',
 VOLTAGE='16V',
 VALUE='1UF',
 PRIM_FILE='./archive_libs/logical/q_cap/chips/chips.prt';

PART_NAME
 PC373 'Q_CAP_C0402-2.2UF,10V,10%,X6S,A':;

SECTION_NUMBER 1
 '@S9S_MB_2U_LIB.S9S_MB_2U(SCH_1):PAGE283_I15@PURE_QUANTA.Q_CAP(CHIPS)':
 C_PATH='@s9s_mb_2u_lib.s9s_mb_2u(sch_1):page283_i15@pure_quanta.q_cap(chips)',
 P_PATH='@s9s_mb_2u_lib.s9s_mb_2u(sch_1):page297_i15@pure_quanta.q_cap(chips)',
 PATH='I15',
 DRAWING='@S9S_MB_2U_LIB.S9S_MB_2U(SCH_1):PAGE283',
 PHYS_PAGE='297',
 XY='(-8050,4075)',
 ROT='0',
 VER='1',
 PACK_TYPE='C0402',
 LOCATION='PC373',
 CDS_LIB='pure_quanta',
 CDS_PART_NAME='Q_CAP_C0402-2.2UF,10V,10%,X6S,A',
 TOLERANCE='10%',
 MATERIAL='X6S',
 VOLTAGE='10V',
 VALUE='2.2UF',
 PRIM_FILE='./archive_libs/logical/q_cap/chips/chips.prt';

PART_NAME
 PC374 'Q_CAP_0402-3300PF,50V,10%,X7R,A':;

SECTION_NUMBER 1
 '@S9S_MB_2U_LIB.S9S_MB_2U(SCH_1):PAGE283_I20@PURE_QUANTA.Q_CAP(CHIPS)':
 C_PATH='@s9s_mb_2u_lib.s9s_mb_2u(sch_1):page283_i20@pure_quanta.q_cap(chips)',
 P_PATH='@s9s_mb_2u_lib.s9s_mb_2u(sch_1):page297_i20@pure_quanta.q_cap(chips)',
 PATH='I20',
 DRAWING='@S9S_MB_2U_LIB.S9S_MB_2U(SCH_1):PAGE283',
 PHYS_PAGE='297',
 XY='(-5725,4525)',
 ROT='0',
 VER='1',
 PACK_TYPE='0402',
 LOCATION='PC374',
 CDS_LIB='pure_quanta',
 CDS_PART_NAME='Q_CAP_0402-3300PF,50V,10%,X7R,A',
 TOLERANCE='10%',
 MATERIAL='X7R',
 VOLTAGE='50V',
 VALUE='3300PF',
 PRIM_FILE='./archive_libs/logical/q_cap/chips/chips.prt';

PART_NAME
 PC375 'Q_CAP_C0402-1UF,16V,10%,X6S,CHA':;

SECTION_NUMBER 1
 '@S9S_MB_2U_LIB.S9S_MB_2U(SCH_1):PAGE283_I22@PURE_QUANTA.Q_CAP(CHIPS)':
 C_PATH='@s9s_mb_2u_lib.s9s_mb_2u(sch_1):page283_i22@pure_quanta.q_cap(chips)',
 P_PATH='@s9s_mb_2u_lib.s9s_mb_2u(sch_1):page297_i22@pure_quanta.q_cap(chips)',
 PATH='I22',
 DRAWING='@S9S_MB_2U_LIB.S9S_MB_2U(SCH_1):PAGE283',
 PHYS_PAGE='297',
 XY='(-5325,4525)',
 ROT='0',
 VER='1',
 PACK_TYPE='C0402',
 LOCATION='PC375',
 CDS_LIB='pure_quanta',
 CDS_PART_NAME='Q_CAP_C0402-1UF,16V,10%,X6S,CHA',
 TOLERANCE='10%',
 MATERIAL='X6S',
 VOLTAGE='16V',
 VALUE='1UF',
 PRIM_FILE='./archive_libs/logical/q_cap/chips/chips.prt';

PART_NAME
 PC376 'Q_CAP_C0402-100NF,50V,10%,X7R,A':;

SECTION_NUMBER 1
 '@S9S_MB_2U_LIB.S9S_MB_2U(SCH_1):PAGE283_I13@PURE_QUANTA.Q_CAP(CHIPS)':
 C_PATH='@s9s_mb_2u_lib.s9s_mb_2u(sch_1):page283_i13@pure_quanta.q_cap(chips)',
 P_PATH='@s9s_mb_2u_lib.s9s_mb_2u(sch_1):page297_i13@pure_quanta.q_cap(chips)',
 PATH='I13',
 DRAWING='@S9S_MB_2U_LIB.S9S_MB_2U(SCH_1):PAGE283',
 PHYS_PAGE='297',
 XY='(-4500,3900)',
 ROT='2',
 VER='1',
 PACK_TYPE='C0402',
 LOCATION='PC376',
 CDS_LIB='pure_quanta',
 CDS_PART_NAME='Q_CAP_C0402-100NF,50V,10%,X7R,A',
 TOLERANCE='10%',
 MATERIAL='X7R',
 VOLTAGE='50V',
 VALUE='100NF',
 PRIM_FILE='./archive_libs/logical/q_cap/chips/chips.prt';

PART_NAME
 PC377 'Q_CAP_C0805-22UF,16V,20%,X6S,CA':;

SECTION_NUMBER 1
 '@S9S_MB_2U_LIB.S9S_MB_2U(SCH_1):PAGE283_I23@PURE_QUANTA.Q_CAP(CHIPS)':
 C_PATH='@s9s_mb_2u_lib.s9s_mb_2u(sch_1):page283_i23@pure_quanta.q_cap(chips)',
 P_PATH='@s9s_mb_2u_lib.s9s_mb_2u(sch_1):page297_i23@pure_quanta.q_cap(chips)',
 PATH='I23',
 DRAWING='@S9S_MB_2U_LIB.S9S_MB_2U(SCH_1):PAGE283',
 PHYS_PAGE='297',
 XY='(-4925,4525)',
 ROT='0',
 VER='1',
 PACK_TYPE='C0805',
 LOCATION='PC377',
 CDS_LIB='pure_quanta',
 CDS_PART_NAME='Q_CAP_C0805-22UF,16V,20%,X6S,CA',
 TOLERANCE='20%',
 MATERIAL='X6S',
 VOLTAGE='16V',
 VALUE='22UF',
 PRIM_FILE='./archive_libs/logical/q_cap/chips/chips.prt';

PART_NAME
 PC378 'Q_CAP_C0805-22UF,16V,20%,X6S,CA':;

SECTION_NUMBER 1
 '@S9S_MB_2U_LIB.S9S_MB_2U(SCH_1):PAGE283_I24@PURE_QUANTA.Q_CAP(CHIPS)':
 C_PATH='@s9s_mb_2u_lib.s9s_mb_2u(sch_1):page283_i24@pure_quanta.q_cap(chips)',
 P_PATH='@s9s_mb_2u_lib.s9s_mb_2u(sch_1):page297_i24@pure_quanta.q_cap(chips)',
 PATH='I24',
 DRAWING='@S9S_MB_2U_LIB.S9S_MB_2U(SCH_1):PAGE283',
 PHYS_PAGE='297',
 XY='(-4525,4525)',
 ROT='0',
 VER='1',
 PACK_TYPE='C0805',
 LOCATION='PC378',
 CDS_LIB='pure_quanta',
 CDS_PART_NAME='Q_CAP_C0805-22UF,16V,20%,X6S,CA',
 TOLERANCE='20%',
 MATERIAL='X6S',
 VOLTAGE='16V',
 VALUE='22UF',
 PRIM_FILE='./archive_libs/logical/q_cap/chips/chips.prt';

PART_NAME
 PC379 'Q_CAP_C0402-100NF,50V,10%,X7R,A':;

SECTION_NUMBER 1
 '@S9S_MB_2U_LIB.S9S_MB_2U(SCH_1):PAGE283_I27@PURE_QUANTA.Q_CAP(CHIPS)':
 C_PATH='@s9s_mb_2u_lib.s9s_mb_2u(sch_1):page283_i27@pure_quanta.q_cap(chips)',
 P_PATH='@s9s_mb_2u_lib.s9s_mb_2u(sch_1):page297_i27@pure_quanta.q_cap(chips)',
 PATH='I27',
 DRAWING='@S9S_MB_2U_LIB.S9S_MB_2U(SCH_1):PAGE283',
 PHYS_PAGE='297',
 XY='(-3425,3425)',
 ROT='0',
 VER='1',
 PACK_TYPE='C0402',
 LOCATION='PC379',
 CDS_LIB='pure_quanta',
 CDS_PART_NAME='Q_CAP_C0402-100NF,50V,10%,X7R,A',
 TOLERANCE='10%',
 MATERIAL='X7R',
 VOLTAGE='50V',
 VALUE='100NF',
 PRIM_FILE='./archive_libs/logical/q_cap/chips/chips.prt';

PART_NAME
 PC381 'Q_CAP_C0805-22UF,4V,20%,X6S,CHA':;

SECTION_NUMBER 1
 '@S9S_MB_2U_LIB.S9S_MB_2U(SCH_1):PAGE283_I28@PURE_QUANTA.Q_CAP(CHIPS)':
 C_PATH='@s9s_mb_2u_lib.s9s_mb_2u(sch_1):page283_i28@pure_quanta.q_cap(chips)',
 P_PATH='@s9s_mb_2u_lib.s9s_mb_2u(sch_1):page297_i28@pure_quanta.q_cap(chips)',
 PATH='I28',
 DRAWING='@S9S_MB_2U_LIB.S9S_MB_2U(SCH_1):PAGE283',
 PHYS_PAGE='297',
 XY='(-3025,3425)',
 ROT='0',
 VER='1',
 PACK_TYPE='C0805',
 LOCATION='PC381',
 CDS_LIB='pure_quanta',
 CDS_PART_NAME='Q_CAP_C0805-22UF,4V,20%,X6S,CHA',
 TOLERANCE='20%',
 MATERIAL='X6S',
 VOLTAGE='4V',
 VALUE='22UF',
 PRIM_FILE='./archive_libs/logical/q_cap/chips/chips.prt';

PART_NAME
 PC382 'Q_CAP_C0805-22UF,4V,20%,X6S,CHA':;

SECTION_NUMBER 1
 '@S9S_MB_2U_LIB.S9S_MB_2U(SCH_1):PAGE283_I29@PURE_QUANTA.Q_CAP(CHIPS)':
 C_PATH='@s9s_mb_2u_lib.s9s_mb_2u(sch_1):page283_i29@pure_quanta.q_cap(chips)',
 P_PATH='@s9s_mb_2u_lib.s9s_mb_2u(sch_1):page297_i29@pure_quanta.q_cap(chips)',
 PATH='I29',
 DRAWING='@S9S_MB_2U_LIB.S9S_MB_2U(SCH_1):PAGE283',
 PHYS_PAGE='297',
 XY='(-2625,3425)',
 ROT='0',
 VER='1',
 PACK_TYPE='C0805',
 LOCATION='PC382',
 CDS_LIB='pure_quanta',
 CDS_PART_NAME='Q_CAP_C0805-22UF,4V,20%,X6S,CHA',
 TOLERANCE='20%',
 MATERIAL='X6S',
 VOLTAGE='4V',
 VALUE='22UF',
 PRIM_FILE='./archive_libs/logical/q_cap/chips/chips.prt';

PART_NAME
 PC384 'Q_CAPP_THLF-560UF,2.5V,20%,OSCA':;

SECTION_NUMBER 1
 '@S9S_MB_2U_LIB.S9S_MB_2U(SCH_1):PAGE283_I26@PURE_QUANTA.Q_CAPP(CHIPS)':
 C_PATH='@s9s_mb_2u_lib.s9s_mb_2u(sch_1):page283_i26@pure_quanta.q_capp(chips)',
 P_PATH='@s9s_mb_2u_lib.s9s_mb_2u(sch_1):page297_i26@pure_quanta.q_capp(chips)',
 PATH='I26',
 DRAWING='@S9S_MB_2U_LIB.S9S_MB_2U(SCH_1):PAGE283',
 PHYS_PAGE='297',
 XY='(-2500,1975)',
 ROT='0',
 VER='1',
 PACK_TYPE='THLF',
 LOCATION='PC384',
 CDS_LIB='pure_quanta',
 CDS_PART_NAME='Q_CAPP_THLF-560UF,2.5V,20%,OSCA',
 TOLERANCE='20%',
 MATERIAL='OSCON',
 VOLTAGE='2.5V',
 VALUE='560UF',
 PRIM_FILE='./archive_libs/logical/q_capp/chips/chips.prt';

PART_NAME
 PC385 'Q_CAPP_THLF-560UF,2.5V,20%,OSCA':;

SECTION_NUMBER 1
 '@S9S_MB_2U_LIB.S9S_MB_2U(SCH_1):PAGE283_I32@PURE_QUANTA.Q_CAPP(CHIPS)':
 C_PATH='@s9s_mb_2u_lib.s9s_mb_2u(sch_1):page283_i32@pure_quanta.q_capp(chips)',
 P_PATH='@s9s_mb_2u_lib.s9s_mb_2u(sch_1):page297_i32@pure_quanta.q_capp(chips)',
 PATH='I32',
 DRAWING='@S9S_MB_2U_LIB.S9S_MB_2U(SCH_1):PAGE283',
 PHYS_PAGE='297',
 XY='(-2000,1975)',
 ROT='0',
 VER='1',
 PACK_TYPE='THLF',
 LOCATION='PC385',
 CDS_LIB='pure_quanta',
 CDS_PART_NAME='Q_CAPP_THLF-560UF,2.5V,20%,OSCA',
 TOLERANCE='20%',
 MATERIAL='OSCON',
 VOLTAGE='2.5V',
 VALUE='560UF',
 PRIM_FILE='./archive_libs/logical/q_capp/chips/chips.prt';

PART_NAME
 PC386 'Q_CAP_0402-0.1UF,25V,10%,X7R,CA':;

SECTION_NUMBER 1
 '@S9S_MB_2U_LIB.S9S_MB_2U(SCH_1):PAGE282_I13@PURE_QUANTA.Q_CAP(CHIPS)':
 C_PATH='@s9s_mb_2u_lib.s9s_mb_2u(sch_1):page282_i13@pure_quanta.q_cap(chips)',
 P_PATH='@s9s_mb_2u_lib.s9s_mb_2u(sch_1):page296_i13@pure_quanta.q_cap(chips)',
 PATH='I13',
 DRAWING='@S9S_MB_2U_LIB.S9S_MB_2U(SCH_1):PAGE282',
 PHYS_PAGE='296',
 XY='(-4875,-200)',
 ROT='0',
 VER='1',
 PACK_TYPE='0402',
 LOCATION='PC386',
 CDS_LIB='pure_quanta',
 CDS_PART_NAME='Q_CAP_0402-0.1UF,25V,10%,X7R,CA',
 TOLERANCE='10%',
 MATERIAL='X7R',
 VOLTAGE='25V',
 VALUE='0.1UF',
 PRIM_FILE='./archive_libs/logical/q_cap/chips/chips.prt';

PART_NAME
 PC389 'Q_CAP_0402-3300PF,50V,10%,X7R,A':;

SECTION_NUMBER 1
 '@S9S_MB_2U_LIB.S9S_MB_2U(SCH_1):PAGE282_I22@PURE_QUANTA.Q_CAP(CHIPS)':
 C_PATH='@s9s_mb_2u_lib.s9s_mb_2u(sch_1):page282_i22@pure_quanta.q_cap(chips)',
 P_PATH='@s9s_mb_2u_lib.s9s_mb_2u(sch_1):page296_i22@pure_quanta.q_cap(chips)',
 PATH='I22',
 DRAWING='@S9S_MB_2U_LIB.S9S_MB_2U(SCH_1):PAGE282',
 PHYS_PAGE='296',
 XY='(-4475,3275)',
 ROT='0',
 VER='1',
 PACK_TYPE='0402',
 LOCATION='PC389',
 CDS_LIB='pure_quanta',
 CDS_PART_NAME='Q_CAP_0402-3300PF,50V,10%,X7R,A',
 TOLERANCE='10%',
 MATERIAL='X7R',
 VOLTAGE='50V',
 VALUE='3300PF',
 PRIM_FILE='./archive_libs/logical/q_cap/chips/chips.prt';

PART_NAME
 PC390 'Q_CAP_0402-0.1UF,25V,10%,X7R,CA':;

SECTION_NUMBER 1
 '@S9S_MB_2U_LIB.S9S_MB_2U(SCH_1):PAGE282_I50@PURE_QUANTA.Q_CAP(CHIPS)':
 C_PATH='@s9s_mb_2u_lib.s9s_mb_2u(sch_1):page282_i50@pure_quanta.q_cap(chips)',
 P_PATH='@s9s_mb_2u_lib.s9s_mb_2u(sch_1):page296_i50@pure_quanta.q_cap(chips)',
 PATH='I50',
 DRAWING='@S9S_MB_2U_LIB.S9S_MB_2U(SCH_1):PAGE282',
 PHYS_PAGE='296',
 XY='(-4025,-200)',
 ROT='0',
 VER='1',
 PACK_TYPE='0402',
 LOCATION='PC390',
 CDS_LIB='pure_quanta',
 CDS_PART_NAME='Q_CAP_0402-0.1UF,25V,10%,X7R,CA',
 TOLERANCE='10%',
 MATERIAL='X7R',
 VOLTAGE='25V',
 VALUE='0.1UF',
 PRIM_FILE='./archive_libs/logical/q_cap/chips/chips.prt';

PART_NAME
 PC391 'Q_CAP_C0402-100NF,50V,10%,EMPTA':;

SECTION_NUMBER 1
 '@S9S_MB_2U_LIB.S9S_MB_2U(SCH_1):PAGE282_I69@PURE_QUANTA.Q_CAP(CHIPS)':
 C_PATH='@s9s_mb_2u_lib.s9s_mb_2u(sch_1):page282_i69@pure_quanta.q_cap(chips)',
 P_PATH='@s9s_mb_2u_lib.s9s_mb_2u(sch_1):page296_i69@pure_quanta.q_cap(chips)',
 PATH='I69',
 DRAWING='@S9S_MB_2U_LIB.S9S_MB_2U(SCH_1):PAGE282',
 PHYS_PAGE='296',
 XY='(-1700,5250)',
 ROT='0',
 VER='1',
 PACK_TYPE='C0402',
 LOCATION='PC391',
 CDS_LIB='pure_quanta',
 CDS_PART_NAME='Q_CAP_C0402-100NF,50V,10%,EMPTA',
 TOLERANCE='10%',
 MATERIAL='EMPTY',
 VOLTAGE='50V',
 VALUE='100NF',
 PRIM_FILE='./archive_libs/logical/q_cap/chips/chips.prt';

PART_NAME
 PC392 'Q_CAP_C0402-10UF,6.3V,20%,X6S,B':;

SECTION_NUMBER 1
 '@S9S_MB_2U_LIB.S9S_MB_2U(SCH_1):PAGE282_I68@PURE_QUANTA.Q_CAP(CHIPS)':
 C_PATH='@s9s_mb_2u_lib.s9s_mb_2u(sch_1):page282_i68@pure_quanta.q_cap(chips)',
 P_PATH='@s9s_mb_2u_lib.s9s_mb_2u(sch_1):page296_i68@pure_quanta.q_cap(chips)',
 PATH='I68',
 DRAWING='@S9S_MB_2U_LIB.S9S_MB_2U(SCH_1):PAGE282',
 PHYS_PAGE='296',
 XY='(-1700,4775)',
 ROT='0',
 VER='1',
 PACK_TYPE='C0402',
 LOCATION='PC392',
 CDS_LIB='pure_quanta',
 CDS_PART_NAME='Q_CAP_C0402-10UF,6.3V,20%,X6S,B',
 TOLERANCE='20%',
 MATERIAL='X6S',
 VOLTAGE='6.3V',
 VALUE='10UF',
 PRIM_FILE='./archive_libs/logical/q_cap/chips/chips.prt';

PART_NAME
 PC393 'Q_CAP_0402-470PF,50V,10%,X7R,TA':;

SECTION_NUMBER 1
 '@S9S_MB_2U_LIB.S9S_MB_2U(SCH_1):PAGE282_I57@PURE_QUANTA.Q_CAP(CHIPS)':
 C_PATH='@s9s_mb_2u_lib.s9s_mb_2u(sch_1):page282_i57@pure_quanta.q_cap(chips)',
 P_PATH='@s9s_mb_2u_lib.s9s_mb_2u(sch_1):page296_i57@pure_quanta.q_cap(chips)',
 PATH='I57',
 DRAWING='@S9S_MB_2U_LIB.S9S_MB_2U(SCH_1):PAGE282',
 PHYS_PAGE='296',
 XY='(-1325,50)',
 ROT='0',
 VER='1',
 PACK_TYPE='0402',
 LOCATION='PC393',
 CDS_LIB='pure_quanta',
 CDS_PART_NAME='Q_CAP_0402-470PF,50V,10%,X7R,TA',
 TOLERANCE='10%',
 MATERIAL='X7R',
 VOLTAGE='50V',
 VALUE='470PF',
 PRIM_FILE='./archive_libs/logical/q_cap/chips/chips.prt';

PART_NAME
 PC394 'Q_CAP_C0402-1UF,16V,10%,X6S,CHA':;

SECTION_NUMBER 1
 '@S9S_MB_2U_LIB.S9S_MB_2U(SCH_1):PAGE282_I77@PURE_QUANTA.Q_CAP(CHIPS)':
 C_PATH='@s9s_mb_2u_lib.s9s_mb_2u(sch_1):page282_i77@pure_quanta.q_cap(chips)',
 P_PATH='@s9s_mb_2u_lib.s9s_mb_2u(sch_1):page296_i77@pure_quanta.q_cap(chips)',
 PATH='I77',
 DRAWING='@S9S_MB_2U_LIB.S9S_MB_2U(SCH_1):PAGE282',
 PHYS_PAGE='296',
 XY='(-1300,5250)',
 ROT='0',
 VER='1',
 PACK_TYPE='C0402',
 LOCATION='PC394',
 CDS_LIB='pure_quanta',
 CDS_PART_NAME='Q_CAP_C0402-1UF,16V,10%,X6S,CHA',
 TOLERANCE='10%',
 MATERIAL='X6S',
 VOLTAGE='16V',
 VALUE='1UF',
 PRIM_FILE='./archive_libs/logical/q_cap/chips/chips.prt';

PART_NAME
 PC395 'Q_CAP_C0402-2.2UF,10V,10%,X6S,A':;

SECTION_NUMBER 1
 '@S9S_MB_2U_LIB.S9S_MB_2U(SCH_1):PAGE275_I27@PURE_QUANTA.Q_CAP(CHIPS)':
 C_PATH='@s9s_mb_2u_lib.s9s_mb_2u(sch_1):page275_i27@pure_quanta.q_cap(chips)',
 P_PATH='@s9s_mb_2u_lib.s9s_mb_2u(sch_1):page289_i27@pure_quanta.q_cap(chips)',
 PATH='I27',
 DRAWING='@S9S_MB_2U_LIB.S9S_MB_2U(SCH_1):PAGE275',
 PHYS_PAGE='289',
 XY='(-10250,5125)',
 ROT='0',
 VER='1',
 PACK_TYPE='C0402',
 LOCATION='PC395',
 CDS_LIB='pure_quanta',
 CDS_PART_NAME='Q_CAP_C0402-2.2UF,10V,10%,X6S,A',
 TOLERANCE='10%',
 MATERIAL='X6S',
 VOLTAGE='10V',
 VALUE='2.2UF',
 PRIM_FILE='./archive_libs/logical/q_cap/chips/chips.prt';

PART_NAME
 PC396 'Q_CAP_C0402-2.2UF,10V,10%,X6S,A':;

SECTION_NUMBER 1
 '@S9S_MB_2U_LIB.S9S_MB_2U(SCH_1):PAGE275_I11@PURE_QUANTA.Q_CAP(CHIPS)':
 C_PATH='@s9s_mb_2u_lib.s9s_mb_2u(sch_1):page275_i11@pure_quanta.q_cap(chips)',
 P_PATH='@s9s_mb_2u_lib.s9s_mb_2u(sch_1):page289_i11@pure_quanta.q_cap(chips)',
 PATH='I11',
 DRAWING='@S9S_MB_2U_LIB.S9S_MB_2U(SCH_1):PAGE275',
 PHYS_PAGE='289',
 XY='(-10250,2325)',
 ROT='0',
 VER='1',
 PACK_TYPE='C0402',
 LOCATION='PC396',
 CDS_LIB='pure_quanta',
 CDS_PART_NAME='Q_CAP_C0402-2.2UF,10V,10%,X6S,A',
 TOLERANCE='10%',
 MATERIAL='X6S',
 VOLTAGE='10V',
 VALUE='2.2UF',
 PRIM_FILE='./archive_libs/logical/q_cap/chips/chips.prt';

PART_NAME
 PC397_P1_1 'Q_CAP_0402-3300PF,50V,10%,X7R,A':;

SECTION_NUMBER 1
 '@S9S_MB_2U_LIB.S9S_MB_2U(SCH_1):PAGE275_I49@PURE_QUANTA.Q_CAP(CHIPS)':
 C_PATH='@s9s_mb_2u_lib.s9s_mb_2u(sch_1):page275_i49@pure_quanta.q_cap(chips)',
 P_PATH='@s9s_mb_2u_lib.s9s_mb_2u(sch_1):page289_i49@pure_quanta.q_cap(chips)',
 PATH='I49',
 DRAWING='@S9S_MB_2U_LIB.S9S_MB_2U(SCH_1):PAGE275',
 PHYS_PAGE='289',
 XY='(-7925,5575)',
 ROT='0',
 VER='1',
 PACK_TYPE='0402',
 LOCATION='PC397_P1_1',
 CDS_LIB='pure_quanta',
 CDS_PART_NAME='Q_CAP_0402-3300PF,50V,10%,X7R,A',
 TOLERANCE='10%',
 MATERIAL='X7R',
 VOLTAGE='50V',
 VALUE='3300PF',
 PRIM_FILE='./archive_libs/logical/q_cap/chips/chips.prt';

PART_NAME
 PC398_P1_2 'Q_CAP_0402-3300PF,50V,10%,X7R,A':;

SECTION_NUMBER 1
 '@S9S_MB_2U_LIB.S9S_MB_2U(SCH_1):PAGE275_I37@PURE_QUANTA.Q_CAP(CHIPS)':
 C_PATH='@s9s_mb_2u_lib.s9s_mb_2u(sch_1):page275_i37@pure_quanta.q_cap(chips)',
 P_PATH='@s9s_mb_2u_lib.s9s_mb_2u(sch_1):page289_i37@pure_quanta.q_cap(chips)',
 PATH='I37',
 DRAWING='@S9S_MB_2U_LIB.S9S_MB_2U(SCH_1):PAGE275',
 PHYS_PAGE='289',
 XY='(-7925,2775)',
 ROT='0',
 VER='1',
 PACK_TYPE='0402',
 LOCATION='PC398_P1_2',
 CDS_LIB='pure_quanta',
 CDS_PART_NAME='Q_CAP_0402-3300PF,50V,10%,X7R,A',
 TOLERANCE='10%',
 MATERIAL='X7R',
 VOLTAGE='50V',
 VALUE='3300PF',
 PRIM_FILE='./archive_libs/logical/q_cap/chips/chips.prt';

PART_NAME
 PC399_P1_1 'Q_CAP_C0402-1UF,16V,10%,X6S,CHA':;

SECTION_NUMBER 1
 '@S9S_MB_2U_LIB.S9S_MB_2U(SCH_1):PAGE275_I51@PURE_QUANTA.Q_CAP(CHIPS)':
 C_PATH='@s9s_mb_2u_lib.s9s_mb_2u(sch_1):page275_i51@pure_quanta.q_cap(chips)',
 P_PATH='@s9s_mb_2u_lib.s9s_mb_2u(sch_1):page289_i51@pure_quanta.q_cap(chips)',
 PATH='I51',
 DRAWING='@S9S_MB_2U_LIB.S9S_MB_2U(SCH_1):PAGE275',
 PHYS_PAGE='289',
 XY='(-7525,5575)',
 ROT='0',
 VER='1',
 PACK_TYPE='C0402',
 LOCATION='PC399_P1_1',
 CDS_LIB='pure_quanta',
 CDS_PART_NAME='Q_CAP_C0402-1UF,16V,10%,X6S,CHA',
 TOLERANCE='10%',
 MATERIAL='X6S',
 VOLTAGE='16V',
 VALUE='1UF',
 PRIM_FILE='./archive_libs/logical/q_cap/chips/chips.prt';

PART_NAME
 PC400_P1_2 'Q_CAP_C0402-1UF,16V,10%,X6S,CHA':;

SECTION_NUMBER 1
 '@S9S_MB_2U_LIB.S9S_MB_2U(SCH_1):PAGE275_I39@PURE_QUANTA.Q_CAP(CHIPS)':
 C_PATH='@s9s_mb_2u_lib.s9s_mb_2u(sch_1):page275_i39@pure_quanta.q_cap(chips)',
 P_PATH='@s9s_mb_2u_lib.s9s_mb_2u(sch_1):page289_i39@pure_quanta.q_cap(chips)',
 PATH='I39',
 DRAWING='@S9S_MB_2U_LIB.S9S_MB_2U(SCH_1):PAGE275',
 PHYS_PAGE='289',
 XY='(-7525,2775)',
 ROT='0',
 VER='1',
 PACK_TYPE='C0402',
 LOCATION='PC400_P1_2',
 CDS_LIB='pure_quanta',
 CDS_PART_NAME='Q_CAP_C0402-1UF,16V,10%,X6S,CHA',
 TOLERANCE='10%',
 MATERIAL='X6S',
 VOLTAGE='16V',
 VALUE='1UF',
 PRIM_FILE='./archive_libs/logical/q_cap/chips/chips.prt';

PART_NAME
 PC401 'Q_CAP_C0402-100NF,50V,10%,X7R,A':;

SECTION_NUMBER 1
 '@S9S_MB_2U_LIB.S9S_MB_2U(SCH_1):PAGE275_I54@PURE_QUANTA.Q_CAP(CHIPS)':
 C_PATH='@s9s_mb_2u_lib.s9s_mb_2u(sch_1):page275_i54@pure_quanta.q_cap(chips)',
 P_PATH='@s9s_mb_2u_lib.s9s_mb_2u(sch_1):page289_i54@pure_quanta.q_cap(chips)',
 PATH='I54',
 DRAWING='@S9S_MB_2U_LIB.S9S_MB_2U(SCH_1):PAGE275',
 PHYS_PAGE='289',
 XY='(-6300,4950)',
 ROT='2',
 VER='1',
 PACK_TYPE='C0402',
 LOCATION='PC401',
 CDS_LIB='pure_quanta',
 CDS_PART_NAME='Q_CAP_C0402-100NF,50V,10%,X7R,A',
 TOLERANCE='10%',
 MATERIAL='X7R',
 VOLTAGE='50V',
 VALUE='100NF',
 PRIM_FILE='./archive_libs/logical/q_cap/chips/chips.prt';

PART_NAME
 PC402 'Q_CAP_C0402-100NF,50V,10%,X7R,A':;

SECTION_NUMBER 1
 '@S9S_MB_2U_LIB.S9S_MB_2U(SCH_1):PAGE275_I43@PURE_QUANTA.Q_CAP(CHIPS)':
 C_PATH='@s9s_mb_2u_lib.s9s_mb_2u(sch_1):page275_i43@pure_quanta.q_cap(chips)',
 P_PATH='@s9s_mb_2u_lib.s9s_mb_2u(sch_1):page289_i43@pure_quanta.q_cap(chips)',
 PATH='I43',
 DRAWING='@S9S_MB_2U_LIB.S9S_MB_2U(SCH_1):PAGE275',
 PHYS_PAGE='289',
 XY='(-6300,2150)',
 ROT='2',
 VER='1',
 PACK_TYPE='C0402',
 LOCATION='PC402',
 CDS_LIB='pure_quanta',
 CDS_PART_NAME='Q_CAP_C0402-100NF,50V,10%,X7R,A',
 TOLERANCE='10%',
 MATERIAL='X7R',
 VOLTAGE='50V',
 VALUE='100NF',
 PRIM_FILE='./archive_libs/logical/q_cap/chips/chips.prt';

PART_NAME
 PC403_P1_1 'Q_CAP_C0805-22UF,16V,20%,X6S,CA':;

SECTION_NUMBER 1
 '@S9S_MB_2U_LIB.S9S_MB_2U(SCH_1):PAGE275_I52@PURE_QUANTA.Q_CAP(CHIPS)':
 C_PATH='@s9s_mb_2u_lib.s9s_mb_2u(sch_1):page275_i52@pure_quanta.q_cap(chips)',
 P_PATH='@s9s_mb_2u_lib.s9s_mb_2u(sch_1):page289_i52@pure_quanta.q_cap(chips)',
 PATH='I52',
 DRAWING='@S9S_MB_2U_LIB.S9S_MB_2U(SCH_1):PAGE275',
 PHYS_PAGE='289',
 XY='(-7125,5575)',
 ROT='0',
 VER='1',
 PACK_TYPE='C0805',
 LOCATION='PC403_P1_1',
 CDS_LIB='pure_quanta',
 CDS_PART_NAME='Q_CAP_C0805-22UF,16V,20%,X6S,CA',
 TOLERANCE='20%',
 MATERIAL='X6S',
 VOLTAGE='16V',
 VALUE='22UF',
 PRIM_FILE='./archive_libs/logical/q_cap/chips/chips.prt';

PART_NAME
 PC404_P1_2 'Q_CAP_C0805-22UF,16V,20%,X6S,CA':;

SECTION_NUMBER 1
 '@S9S_MB_2U_LIB.S9S_MB_2U(SCH_1):PAGE275_I40@PURE_QUANTA.Q_CAP(CHIPS)':
 C_PATH='@s9s_mb_2u_lib.s9s_mb_2u(sch_1):page275_i40@pure_quanta.q_cap(chips)',
 P_PATH='@s9s_mb_2u_lib.s9s_mb_2u(sch_1):page289_i40@pure_quanta.q_cap(chips)',
 PATH='I40',
 DRAWING='@S9S_MB_2U_LIB.S9S_MB_2U(SCH_1):PAGE275',
 PHYS_PAGE='289',
 XY='(-7125,2775)',
 ROT='0',
 VER='1',
 PACK_TYPE='C0805',
 LOCATION='PC404_P1_2',
 CDS_LIB='pure_quanta',
 CDS_PART_NAME='Q_CAP_C0805-22UF,16V,20%,X6S,CA',
 TOLERANCE='20%',
 MATERIAL='X6S',
 VOLTAGE='16V',
 VALUE='22UF',
 PRIM_FILE='./archive_libs/logical/q_cap/chips/chips.prt';

PART_NAME
 PC405_P1_1 'Q_CAP_C0805-22UF,16V,20%,X6S,CA':;

SECTION_NUMBER 1
 '@S9S_MB_2U_LIB.S9S_MB_2U(SCH_1):PAGE275_I56@PURE_QUANTA.Q_CAP(CHIPS)':
 C_PATH='@s9s_mb_2u_lib.s9s_mb_2u(sch_1):page275_i56@pure_quanta.q_cap(chips)',
 P_PATH='@s9s_mb_2u_lib.s9s_mb_2u(sch_1):page289_i56@pure_quanta.q_cap(chips)',
 PATH='I56',
 DRAWING='@S9S_MB_2U_LIB.S9S_MB_2U(SCH_1):PAGE275',
 PHYS_PAGE='289',
 XY='(-6725,5575)',
 ROT='0',
 VER='1',
 PACK_TYPE='C0805',
 LOCATION='PC405_P1_1',
 CDS_LIB='pure_quanta',
 CDS_PART_NAME='Q_CAP_C0805-22UF,16V,20%,X6S,CA',
 TOLERANCE='20%',
 MATERIAL='X6S',
 VOLTAGE='16V',
 VALUE='22UF',
 PRIM_FILE='./archive_libs/logical/q_cap/chips/chips.prt';

PART_NAME
 PC406_P1_2 'Q_CAP_C0805-22UF,16V,20%,X6S,CA':;

SECTION_NUMBER 1
 '@S9S_MB_2U_LIB.S9S_MB_2U(SCH_1):PAGE275_I42@PURE_QUANTA.Q_CAP(CHIPS)':
 C_PATH='@s9s_mb_2u_lib.s9s_mb_2u(sch_1):page275_i42@pure_quanta.q_cap(chips)',
 P_PATH='@s9s_mb_2u_lib.s9s_mb_2u(sch_1):page289_i42@pure_quanta.q_cap(chips)',
 PATH='I42',
 DRAWING='@S9S_MB_2U_LIB.S9S_MB_2U(SCH_1):PAGE275',
 PHYS_PAGE='289',
 XY='(-6725,2775)',
 ROT='0',
 VER='1',
 PACK_TYPE='C0805',
 LOCATION='PC406_P1_2',
 CDS_LIB='pure_quanta',
 CDS_PART_NAME='Q_CAP_C0805-22UF,16V,20%,X6S,CA',
 TOLERANCE='20%',
 MATERIAL='X6S',
 VOLTAGE='16V',
 VALUE='22UF',
 PRIM_FILE='./archive_libs/logical/q_cap/chips/chips.prt';

PART_NAME
 PC408_P1_2 'Q_CAP_C0402-1UF,16V,10%,X6S,CHA':;

SECTION_NUMBER 1
 '@S9S_MB_2U_LIB.S9S_MB_2U(SCH_1):PAGE275_I61@PURE_QUANTA.Q_CAP(CHIPS)':
 C_PATH='@s9s_mb_2u_lib.s9s_mb_2u(sch_1):page275_i61@pure_quanta.q_cap(chips)',
 P_PATH='@s9s_mb_2u_lib.s9s_mb_2u(sch_1):page289_i61@pure_quanta.q_cap(chips)',
 PATH='I61',
 DRAWING='@S9S_MB_2U_LIB.S9S_MB_2U(SCH_1):PAGE275',
 PHYS_PAGE='289',
 XY='(-4975,1675)',
 ROT='0',
 VER='1',
 PACK_TYPE='C0402',
 LOCATION='PC408_P1_2',
 CDS_LIB='pure_quanta',
 CDS_PART_NAME='Q_CAP_C0402-1UF,16V,10%,X6S,CHA',
 TOLERANCE='10%',
 MATERIAL='X6S',
 VOLTAGE='16V',
 VALUE='1UF',
 PRIM_FILE='./archive_libs/logical/q_cap/chips/chips.prt';

PART_NAME
 PC410_P1_1 'Q_CAP_C0805-22UF,4V,20%,X6S,CHA':;

SECTION_NUMBER 1
 '@S9S_MB_2U_LIB.S9S_MB_2U(SCH_1):PAGE275_I74@PURE_QUANTA.Q_CAP(CHIPS)':
 C_PATH='@s9s_mb_2u_lib.s9s_mb_2u(sch_1):page275_i74@pure_quanta.q_cap(chips)',
 P_PATH='@s9s_mb_2u_lib.s9s_mb_2u(sch_1):page289_i74@pure_quanta.q_cap(chips)',
 PATH='I74',
 DRAWING='@S9S_MB_2U_LIB.S9S_MB_2U(SCH_1):PAGE275',
 PHYS_PAGE='289',
 XY='(-4550,4475)',
 ROT='0',
 VER='1',
 PACK_TYPE='C0805',
 LOCATION='PC410_P1_1',
 CDS_LIB='pure_quanta',
 CDS_PART_NAME='Q_CAP_C0805-22UF,4V,20%,X6S,CHA',
 TOLERANCE='20%',
 MATERIAL='X6S',
 VOLTAGE='4V',
 VALUE='22UF',
 PRIM_FILE='./archive_libs/logical/q_cap/chips/chips.prt';

PART_NAME
 PC411_P1_2 'Q_CAP_C0805-22UF,4V,20%,X6S,CHA':;

SECTION_NUMBER 1
 '@S9S_MB_2U_LIB.S9S_MB_2U(SCH_1):PAGE275_I62@PURE_QUANTA.Q_CAP(CHIPS)':
 C_PATH='@s9s_mb_2u_lib.s9s_mb_2u(sch_1):page275_i62@pure_quanta.q_cap(chips)',
 P_PATH='@s9s_mb_2u_lib.s9s_mb_2u(sch_1):page289_i62@pure_quanta.q_cap(chips)',
 PATH='I62',
 DRAWING='@S9S_MB_2U_LIB.S9S_MB_2U(SCH_1):PAGE275',
 PHYS_PAGE='289',
 XY='(-4550,1675)',
 ROT='0',
 VER='1',
 PACK_TYPE='C0805',
 LOCATION='PC411_P1_2',
 CDS_LIB='pure_quanta',
 CDS_PART_NAME='Q_CAP_C0805-22UF,4V,20%,X6S,CHA',
 TOLERANCE='20%',
 MATERIAL='X6S',
 VOLTAGE='4V',
 VALUE='22UF',
 PRIM_FILE='./archive_libs/logical/q_cap/chips/chips.prt';

PART_NAME
 PC412_P1_1 'Q_CAP_C0805-22UF,4V,20%,X6S,CHA':;

SECTION_NUMBER 1
 '@S9S_MB_2U_LIB.S9S_MB_2U(SCH_1):PAGE275_I75@PURE_QUANTA.Q_CAP(CHIPS)':
 C_PATH='@s9s_mb_2u_lib.s9s_mb_2u(sch_1):page275_i75@pure_quanta.q_cap(chips)',
 P_PATH='@s9s_mb_2u_lib.s9s_mb_2u(sch_1):page289_i75@pure_quanta.q_cap(chips)',
 PATH='I75',
 DRAWING='@S9S_MB_2U_LIB.S9S_MB_2U(SCH_1):PAGE275',
 PHYS_PAGE='289',
 XY='(-4125,4475)',
 ROT='0',
 VER='1',
 PACK_TYPE='C0805',
 LOCATION='PC412_P1_1',
 CDS_LIB='pure_quanta',
 CDS_PART_NAME='Q_CAP_C0805-22UF,4V,20%,X6S,CHA',
 TOLERANCE='20%',
 MATERIAL='X6S',
 VOLTAGE='4V',
 VALUE='22UF',
 PRIM_FILE='./archive_libs/logical/q_cap/chips/chips.prt';

PART_NAME
 PC413_P1_2 'Q_CAP_C0805-22UF,4V,20%,X6S,CHA':;

SECTION_NUMBER 1
 '@S9S_MB_2U_LIB.S9S_MB_2U(SCH_1):PAGE275_I63@PURE_QUANTA.Q_CAP(CHIPS)':
 C_PATH='@s9s_mb_2u_lib.s9s_mb_2u(sch_1):page275_i63@pure_quanta.q_cap(chips)',
 P_PATH='@s9s_mb_2u_lib.s9s_mb_2u(sch_1):page289_i63@pure_quanta.q_cap(chips)',
 PATH='I63',
 DRAWING='@S9S_MB_2U_LIB.S9S_MB_2U(SCH_1):PAGE275',
 PHYS_PAGE='289',
 XY='(-4125,1675)',
 ROT='0',
 VER='1',
 PACK_TYPE='C0805',
 LOCATION='PC413_P1_2',
 CDS_LIB='pure_quanta',
 CDS_PART_NAME='Q_CAP_C0805-22UF,4V,20%,X6S,CHA',
 TOLERANCE='20%',
 MATERIAL='X6S',
 VOLTAGE='4V',
 VALUE='22UF',
 PRIM_FILE='./archive_libs/logical/q_cap/chips/chips.prt';

PART_NAME
 PC414 'Q_CAPP_THLF-560UF,2.5V,20%,OSCA':;

SECTION_NUMBER 1
 '@S9S_MB_2U_LIB.S9S_MB_2U(SCH_1):PAGE275_I66@PURE_QUANTA.Q_CAPP(CHIPS)':
 C_PATH='@s9s_mb_2u_lib.s9s_mb_2u(sch_1):page275_i66@pure_quanta.q_capp(chips)',
 P_PATH='@s9s_mb_2u_lib.s9s_mb_2u(sch_1):page289_i66@pure_quanta.q_capp(chips)',
 PATH='I66',
 DRAWING='@S9S_MB_2U_LIB.S9S_MB_2U(SCH_1):PAGE275',
 PHYS_PAGE='289',
 XY='(-4825,2800)',
 ROT='0',
 VER='1',
 PACK_TYPE='THLF',
 LOCATION='PC414',
 CDS_LIB='pure_quanta',
 CDS_PART_NAME='Q_CAPP_THLF-560UF,2.5V,20%,OSCA',
 TOLERANCE='20%',
 MATERIAL='OSCON',
 VOLTAGE='2.5V',
 VALUE='560UF',
 PRIM_FILE='./archive_libs/logical/q_capp/chips/chips.prt';

PART_NAME
 PC415 'Q_CAPP_THLF-560UF,2.5V,20%,OSCA':;

SECTION_NUMBER 1
 '@S9S_MB_2U_LIB.S9S_MB_2U(SCH_1):PAGE275_I67@PURE_QUANTA.Q_CAPP(CHIPS)':
 C_PATH='@s9s_mb_2u_lib.s9s_mb_2u(sch_1):page275_i67@pure_quanta.q_capp(chips)',
 P_PATH='@s9s_mb_2u_lib.s9s_mb_2u(sch_1):page289_i67@pure_quanta.q_capp(chips)',
 PATH='I67',
 DRAWING='@S9S_MB_2U_LIB.S9S_MB_2U(SCH_1):PAGE275',
 PHYS_PAGE='289',
 XY='(-4300,2800)',
 ROT='0',
 VER='1',
 PACK_TYPE='THLF',
 LOCATION='PC415',
 CDS_LIB='pure_quanta',
 CDS_PART_NAME='Q_CAPP_THLF-560UF,2.5V,20%,OSCA',
 TOLERANCE='20%',
 MATERIAL='OSCON',
 VOLTAGE='2.5V',
 VALUE='560UF',
 PRIM_FILE='./archive_libs/logical/q_capp/chips/chips.prt';

PART_NAME
 PC416 'Q_CAPP_THLF-560UF,2.5V,20%,OSCA':;

SECTION_NUMBER 1
 '@S9S_MB_2U_LIB.S9S_MB_2U(SCH_1):PAGE275_I68@PURE_QUANTA.Q_CAPP(CHIPS)':
 C_PATH='@s9s_mb_2u_lib.s9s_mb_2u(sch_1):page275_i68@pure_quanta.q_capp(chips)',
 P_PATH='@s9s_mb_2u_lib.s9s_mb_2u(sch_1):page289_i68@pure_quanta.q_capp(chips)',
 PATH='I68',
 DRAWING='@S9S_MB_2U_LIB.S9S_MB_2U(SCH_1):PAGE275',
 PHYS_PAGE='289',
 XY='(-3775,2800)',
 ROT='0',
 VER='1',
 PACK_TYPE='THLF',
 LOCATION='PC416',
 CDS_LIB='pure_quanta',
 CDS_PART_NAME='Q_CAPP_THLF-560UF,2.5V,20%,OSCA',
 TOLERANCE='20%',
 MATERIAL='OSCON',
 VOLTAGE='2.5V',
 VALUE='560UF',
 PRIM_FILE='./archive_libs/logical/q_capp/chips/chips.prt';

PART_NAME
 PC417 'Q_CAPP_THLF-270UF,16V,20%,OSCOA':;

SECTION_NUMBER 1
 '@S9S_MB_2U_LIB.S9S_MB_2U(SCH_1):PAGE275_I87@PURE_QUANTA.Q_CAPP(CHIPS)':
 C_PATH='@s9s_mb_2u_lib.s9s_mb_2u(sch_1):page275_i87@pure_quanta.q_capp(chips)',
 P_PATH='@s9s_mb_2u_lib.s9s_mb_2u(sch_1):page289_i87@pure_quanta.q_capp(chips)',
 PATH='I87',
 DRAWING='@S9S_MB_2U_LIB.S9S_MB_2U(SCH_1):PAGE275',
 PHYS_PAGE='289',
 XY='(-3125,5325)',
 ROT='0',
 VER='1',
 PACK_TYPE='THLF',
 LOCATION='PC417',
 CDS_LIB='pure_quanta',
 CDS_PART_NAME='Q_CAPP_THLF-270UF,16V,20%,OSCOA',
 TOLERANCE='20%',
 MATERIAL='OSCON',
 VOLTAGE='16V',
 VALUE='270UF',
 PRIM_FILE='./archive_libs/logical/q_capp/chips/chips.prt';

PART_NAME
 PC418 'Q_CAPP_SMLF-330UF,2.5V,+10/-35B':;

SECTION_NUMBER 1
 '@S9S_MB_2U_LIB.S9S_MB_2U(SCH_1):PAGE275_I70@PURE_QUANTA.Q_CAPP(CHIPS)':
 C_PATH='@s9s_mb_2u_lib.s9s_mb_2u(sch_1):page275_i70@pure_quanta.q_capp(chips)',
 P_PATH='@s9s_mb_2u_lib.s9s_mb_2u(sch_1):page289_i70@pure_quanta.q_capp(chips)',
 PATH='I70',
 DRAWING='@S9S_MB_2U_LIB.S9S_MB_2U(SCH_1):PAGE275',
 PHYS_PAGE='289',
 XY='(-3275,2800)',
 ROT='0',
 VER='1',
 PACK_TYPE='SMLF',
 LOCATION='PC418',
 CDS_LIB='pure_quanta',
 CDS_PART_NAME='Q_CAPP_SMLF-330UF,2.5V,+10/-35B',
 TOLERANCE='+10/-35%',
 MATERIAL='SPCAP',
 VOLTAGE='2.5V',
 VALUE='330UF',
 PRIM_FILE='./archive_libs/logical/q_capp/chips/chips.prt';

PART_NAME
 PC422 'Q_CAP_0402-3300PF,50V,10%,X7R,A':;

SECTION_NUMBER 1
 '@S9S_MB_2U_LIB.S9S_MB_2U(SCH_1):PAGE270_I38@PURE_QUANTA.Q_CAP(CHIPS)':
 C_PATH='@s9s_mb_2u_lib.s9s_mb_2u(sch_1):page270_i38@pure_quanta.q_cap(chips)',
 P_PATH='@s9s_mb_2u_lib.s9s_mb_2u(sch_1):page284_i38@pure_quanta.q_cap(chips)',
 PATH='I38',
 DRAWING='@S9S_MB_2U_LIB.S9S_MB_2U(SCH_1):PAGE270',
 PHYS_PAGE='284',
 XY='(-1325,-250)',
 ROT='0',
 VER='1',
 PACK_TYPE='0402',
 LOCATION='PC422',
 CDS_LIB='pure_quanta',
 CDS_PART_NAME='Q_CAP_0402-3300PF,50V,10%,X7R,A',
 TOLERANCE='10%',
 MATERIAL='X7R',
 VOLTAGE='50V',
 VALUE='3300PF',
 PRIM_FILE='./archive_libs/logical/q_cap/chips/chips.prt';

PART_NAME
 PC428 'Q_CAP_C0402-2.2UF,10V,10%,X6S,A':;

SECTION_NUMBER 1
 '@S9S_MB_2U_LIB.S9S_MB_2U(SCH_1):PAGE280_I11@PURE_QUANTA.Q_CAP(CHIPS)':
 C_PATH='@s9s_mb_2u_lib.s9s_mb_2u(sch_1):page280_i11@pure_quanta.q_cap(chips)',
 P_PATH='@s9s_mb_2u_lib.s9s_mb_2u(sch_1):page294_i11@pure_quanta.q_cap(chips)',
 PATH='I11',
 DRAWING='@S9S_MB_2U_LIB.S9S_MB_2U(SCH_1):PAGE280',
 PHYS_PAGE='294',
 XY='(-6100,9650)',
 ROT='0',
 VER='1',
 PACK_TYPE='C0402',
 LOCATION='PC428',
 CDS_LIB='pure_quanta',
 CDS_PART_NAME='Q_CAP_C0402-2.2UF,10V,10%,X6S,A',
 TOLERANCE='10%',
 MATERIAL='X6S',
 VOLTAGE='10V',
 VALUE='2.2UF',
 PRIM_FILE='./archive_libs/logical/q_cap/chips/chips.prt';

PART_NAME
 PC429 'Q_CAP_0402-3300PF,50V,10%,X7R,A':;

SECTION_NUMBER 1
 '@S9S_MB_2U_LIB.S9S_MB_2U(SCH_1):PAGE280_I24@PURE_QUANTA.Q_CAP(CHIPS)':
 C_PATH='@s9s_mb_2u_lib.s9s_mb_2u(sch_1):page280_i24@pure_quanta.q_cap(chips)',
 P_PATH='@s9s_mb_2u_lib.s9s_mb_2u(sch_1):page294_i24@pure_quanta.q_cap(chips)',
 PATH='I24',
 DRAWING='@S9S_MB_2U_LIB.S9S_MB_2U(SCH_1):PAGE280',
 PHYS_PAGE='294',
 XY='(-3775,10100)',
 ROT='0',
 VER='1',
 PACK_TYPE='0402',
 LOCATION='PC429',
 CDS_LIB='pure_quanta',
 CDS_PART_NAME='Q_CAP_0402-3300PF,50V,10%,X7R,A',
 TOLERANCE='10%',
 MATERIAL='X7R',
 VOLTAGE='50V',
 VALUE='3300PF',
 PRIM_FILE='./archive_libs/logical/q_cap/chips/chips.prt';

PART_NAME
 PC430 'Q_CAP_C0402-1UF,16V,10%,X6S,CHA':;

SECTION_NUMBER 1
 '@S9S_MB_2U_LIB.S9S_MB_2U(SCH_1):PAGE280_I26@PURE_QUANTA.Q_CAP(CHIPS)':
 C_PATH='@s9s_mb_2u_lib.s9s_mb_2u(sch_1):page280_i26@pure_quanta.q_cap(chips)',
 P_PATH='@s9s_mb_2u_lib.s9s_mb_2u(sch_1):page294_i26@pure_quanta.q_cap(chips)',
 PATH='I26',
 DRAWING='@S9S_MB_2U_LIB.S9S_MB_2U(SCH_1):PAGE280',
 PHYS_PAGE='294',
 XY='(-3325,10100)',
 ROT='0',
 VER='1',
 PACK_TYPE='C0402',
 LOCATION='PC430',
 CDS_LIB='pure_quanta',
 CDS_PART_NAME='Q_CAP_C0402-1UF,16V,10%,X6S,CHA',
 TOLERANCE='10%',
 MATERIAL='X6S',
 VOLTAGE='16V',
 VALUE='1UF',
 PRIM_FILE='./archive_libs/logical/q_cap/chips/chips.prt';

PART_NAME
 PC431 'Q_CAP_C0402-100NF,50V,10%,X7R,A':;

SECTION_NUMBER 1
 '@S9S_MB_2U_LIB.S9S_MB_2U(SCH_1):PAGE280_I22@PURE_QUANTA.Q_CAP(CHIPS)':
 C_PATH='@s9s_mb_2u_lib.s9s_mb_2u(sch_1):page280_i22@pure_quanta.q_cap(chips)',
 P_PATH='@s9s_mb_2u_lib.s9s_mb_2u(sch_1):page294_i22@pure_quanta.q_cap(chips)',
 PATH='I22',
 DRAWING='@S9S_MB_2U_LIB.S9S_MB_2U(SCH_1):PAGE280',
 PHYS_PAGE='294',
 XY='(-2450,9475)',
 ROT='2',
 VER='1',
 PACK_TYPE='C0402',
 LOCATION='PC431',
 CDS_LIB='pure_quanta',
 CDS_PART_NAME='Q_CAP_C0402-100NF,50V,10%,X7R,A',
 TOLERANCE='10%',
 MATERIAL='X7R',
 VOLTAGE='50V',
 VALUE='100NF',
 PRIM_FILE='./archive_libs/logical/q_cap/chips/chips.prt';

PART_NAME
 PC432 'Q_CAP_C0805-22UF,16V,20%,X6S,CA':;

SECTION_NUMBER 1
 '@S9S_MB_2U_LIB.S9S_MB_2U(SCH_1):PAGE280_I27@PURE_QUANTA.Q_CAP(CHIPS)':
 C_PATH='@s9s_mb_2u_lib.s9s_mb_2u(sch_1):page280_i27@pure_quanta.q_cap(chips)',
 P_PATH='@s9s_mb_2u_lib.s9s_mb_2u(sch_1):page294_i27@pure_quanta.q_cap(chips)',
 PATH='I27',
 DRAWING='@S9S_MB_2U_LIB.S9S_MB_2U(SCH_1):PAGE280',
 PHYS_PAGE='294',
 XY='(-2950,10100)',
 ROT='0',
 VER='1',
 PACK_TYPE='C0805',
 LOCATION='PC432',
 CDS_LIB='pure_quanta',
 CDS_PART_NAME='Q_CAP_C0805-22UF,16V,20%,X6S,CA',
 TOLERANCE='20%',
 MATERIAL='X6S',
 VOLTAGE='16V',
 VALUE='22UF',
 PRIM_FILE='./archive_libs/logical/q_cap/chips/chips.prt';

PART_NAME
 PC433 'Q_CAP_C0805-22UF,16V,20%,X6S,CA':;

SECTION_NUMBER 1
 '@S9S_MB_2U_LIB.S9S_MB_2U(SCH_1):PAGE280_I28@PURE_QUANTA.Q_CAP(CHIPS)':
 C_PATH='@s9s_mb_2u_lib.s9s_mb_2u(sch_1):page280_i28@pure_quanta.q_cap(chips)',
 P_PATH='@s9s_mb_2u_lib.s9s_mb_2u(sch_1):page294_i28@pure_quanta.q_cap(chips)',
 PATH='I28',
 DRAWING='@S9S_MB_2U_LIB.S9S_MB_2U(SCH_1):PAGE280',
 PHYS_PAGE='294',
 XY='(-2575,10100)',
 ROT='0',
 VER='1',
 PACK_TYPE='C0805',
 LOCATION='PC433',
 CDS_LIB='pure_quanta',
 CDS_PART_NAME='Q_CAP_C0805-22UF,16V,20%,X6S,CA',
 TOLERANCE='20%',
 MATERIAL='X6S',
 VOLTAGE='16V',
 VALUE='22UF',
 PRIM_FILE='./archive_libs/logical/q_cap/chips/chips.prt';

PART_NAME
 PC434 'Q_CAP_C0402-100NF,50V,10%,X7R,A':;

SECTION_NUMBER 1
 '@S9S_MB_2U_LIB.S9S_MB_2U(SCH_1):PAGE280_I29@PURE_QUANTA.Q_CAP(CHIPS)':
 C_PATH='@s9s_mb_2u_lib.s9s_mb_2u(sch_1):page280_i29@pure_quanta.q_cap(chips)',
 P_PATH='@s9s_mb_2u_lib.s9s_mb_2u(sch_1):page294_i29@pure_quanta.q_cap(chips)',
 PATH='I29',
 DRAWING='@S9S_MB_2U_LIB.S9S_MB_2U(SCH_1):PAGE280',
 PHYS_PAGE='294',
 XY='(-2000,9000)',
 ROT='0',
 VER='1',
 PACK_TYPE='C0402',
 LOCATION='PC434',
 CDS_LIB='pure_quanta',
 CDS_PART_NAME='Q_CAP_C0402-100NF,50V,10%,X7R,A',
 TOLERANCE='10%',
 MATERIAL='X7R',
 VOLTAGE='50V',
 VALUE='100NF',
 PRIM_FILE='./archive_libs/logical/q_cap/chips/chips.prt';

PART_NAME
 PC435 'Q_CAP_C0805-22UF,4V,20%,X6S,CHA':;

SECTION_NUMBER 1
 '@S9S_MB_2U_LIB.S9S_MB_2U(SCH_1):PAGE280_I30@PURE_QUANTA.Q_CAP(CHIPS)':
 C_PATH='@s9s_mb_2u_lib.s9s_mb_2u(sch_1):page280_i30@pure_quanta.q_cap(chips)',
 P_PATH='@s9s_mb_2u_lib.s9s_mb_2u(sch_1):page294_i30@pure_quanta.q_cap(chips)',
 PATH='I30',
 DRAWING='@S9S_MB_2U_LIB.S9S_MB_2U(SCH_1):PAGE280',
 PHYS_PAGE='294',
 XY='(-1600,9000)',
 ROT='0',
 VER='1',
 PACK_TYPE='C0805',
 LOCATION='PC435',
 CDS_LIB='pure_quanta',
 CDS_PART_NAME='Q_CAP_C0805-22UF,4V,20%,X6S,CHA',
 TOLERANCE='20%',
 MATERIAL='X6S',
 VOLTAGE='4V',
 VALUE='22UF',
 PRIM_FILE='./archive_libs/logical/q_cap/chips/chips.prt';

PART_NAME
 PC437 'Q_CAP_C0805-22UF,4V,20%,X6S,CHA':;

SECTION_NUMBER 1
 '@S9S_MB_2U_LIB.S9S_MB_2U(SCH_1):PAGE280_I31@PURE_QUANTA.Q_CAP(CHIPS)':
 C_PATH='@s9s_mb_2u_lib.s9s_mb_2u(sch_1):page280_i31@pure_quanta.q_cap(chips)',
 P_PATH='@s9s_mb_2u_lib.s9s_mb_2u(sch_1):page294_i31@pure_quanta.q_cap(chips)',
 PATH='I31',
 DRAWING='@S9S_MB_2U_LIB.S9S_MB_2U(SCH_1):PAGE280',
 PHYS_PAGE='294',
 XY='(-1175,9000)',
 ROT='0',
 VER='1',
 PACK_TYPE='C0805',
 LOCATION='PC437',
 CDS_LIB='pure_quanta',
 CDS_PART_NAME='Q_CAP_C0805-22UF,4V,20%,X6S,CHA',
 TOLERANCE='20%',
 MATERIAL='X6S',
 VOLTAGE='4V',
 VALUE='22UF',
 PRIM_FILE='./archive_libs/logical/q_cap/chips/chips.prt';

PART_NAME
 PC440 'Q_CAP_C0402-2.2UF,10V,10%,X6S,A':;

SECTION_NUMBER 1
 '@S9S_MB_2U_LIB.S9S_MB_2U(SCH_1):PAGE279_I24@PURE_QUANTA.Q_CAP(CHIPS)':
 C_PATH='@s9s_mb_2u_lib.s9s_mb_2u(sch_1):page279_i24@pure_quanta.q_cap(chips)',
 P_PATH='@s9s_mb_2u_lib.s9s_mb_2u(sch_1):page293_i24@pure_quanta.q_cap(chips)',
 PATH='I24',
 DRAWING='@S9S_MB_2U_LIB.S9S_MB_2U(SCH_1):PAGE279',
 PHYS_PAGE='293',
 XY='(-8500,11675)',
 ROT='0',
 VER='1',
 PACK_TYPE='C0402',
 LOCATION='PC440',
 CDS_LIB='pure_quanta',
 CDS_PART_NAME='Q_CAP_C0402-2.2UF,10V,10%,X6S,A',
 TOLERANCE='10%',
 MATERIAL='X6S',
 VOLTAGE='10V',
 VALUE='2.2UF',
 PRIM_FILE='./archive_libs/logical/q_cap/chips/chips.prt';

PART_NAME
 PC441 'Q_CAP_C0402-2.2UF,10V,10%,X6S,A':;

SECTION_NUMBER 1
 '@S9S_MB_2U_LIB.S9S_MB_2U(SCH_1):PAGE279_I10@PURE_QUANTA.Q_CAP(CHIPS)':
 C_PATH='@s9s_mb_2u_lib.s9s_mb_2u(sch_1):page279_i10@pure_quanta.q_cap(chips)',
 P_PATH='@s9s_mb_2u_lib.s9s_mb_2u(sch_1):page293_i10@pure_quanta.q_cap(chips)',
 PATH='I10',
 DRAWING='@S9S_MB_2U_LIB.S9S_MB_2U(SCH_1):PAGE279',
 PHYS_PAGE='293',
 XY='(-8500,8875)',
 ROT='0',
 VER='1',
 PACK_TYPE='C0402',
 LOCATION='PC441',
 CDS_LIB='pure_quanta',
 CDS_PART_NAME='Q_CAP_C0402-2.2UF,10V,10%,X6S,A',
 TOLERANCE='10%',
 MATERIAL='X6S',
 VOLTAGE='10V',
 VALUE='2.2UF',
 PRIM_FILE='./archive_libs/logical/q_cap/chips/chips.prt';

PART_NAME
 PC442_P1_1 'Q_CAP_0402-3300PF,50V,10%,X7R,A':;

SECTION_NUMBER 1
 '@S9S_MB_2U_LIB.S9S_MB_2U(SCH_1):PAGE279_I40@PURE_QUANTA.Q_CAP(CHIPS)':
 C_PATH='@s9s_mb_2u_lib.s9s_mb_2u(sch_1):page279_i40@pure_quanta.q_cap(chips)',
 P_PATH='@s9s_mb_2u_lib.s9s_mb_2u(sch_1):page293_i40@pure_quanta.q_cap(chips)',
 PATH='I40',
 DRAWING='@S9S_MB_2U_LIB.S9S_MB_2U(SCH_1):PAGE279',
 PHYS_PAGE='293',
 XY='(-6175,12125)',
 ROT='0',
 VER='1',
 PACK_TYPE='0402',
 LOCATION='PC442_P1_1',
 CDS_LIB='pure_quanta',
 CDS_PART_NAME='Q_CAP_0402-3300PF,50V,10%,X7R,A',
 TOLERANCE='10%',
 MATERIAL='X7R',
 VOLTAGE='50V',
 VALUE='3300PF',
 PRIM_FILE='./archive_libs/logical/q_cap/chips/chips.prt';

PART_NAME
 PC443_P1_2 'Q_CAP_0402-3300PF,50V,10%,X7R,A':;

SECTION_NUMBER 1
 '@S9S_MB_2U_LIB.S9S_MB_2U(SCH_1):PAGE279_I36@PURE_QUANTA.Q_CAP(CHIPS)':
 C_PATH='@s9s_mb_2u_lib.s9s_mb_2u(sch_1):page279_i36@pure_quanta.q_cap(chips)',
 P_PATH='@s9s_mb_2u_lib.s9s_mb_2u(sch_1):page293_i36@pure_quanta.q_cap(chips)',
 PATH='I36',
 DRAWING='@S9S_MB_2U_LIB.S9S_MB_2U(SCH_1):PAGE279',
 PHYS_PAGE='293',
 XY='(-6175,9325)',
 ROT='0',
 VER='1',
 PACK_TYPE='0402',
 LOCATION='PC443_P1_2',
 CDS_LIB='pure_quanta',
 CDS_PART_NAME='Q_CAP_0402-3300PF,50V,10%,X7R,A',
 TOLERANCE='10%',
 MATERIAL='X7R',
 VOLTAGE='50V',
 VALUE='3300PF',
 PRIM_FILE='./archive_libs/logical/q_cap/chips/chips.prt';

PART_NAME
 PC444_P1_1 'Q_CAP_C0402-1UF,16V,10%,X6S,CHA':;

SECTION_NUMBER 1
 '@S9S_MB_2U_LIB.S9S_MB_2U(SCH_1):PAGE279_I41@PURE_QUANTA.Q_CAP(CHIPS)':
 C_PATH='@s9s_mb_2u_lib.s9s_mb_2u(sch_1):page279_i41@pure_quanta.q_cap(chips)',
 P_PATH='@s9s_mb_2u_lib.s9s_mb_2u(sch_1):page293_i41@pure_quanta.q_cap(chips)',
 PATH='I41',
 DRAWING='@S9S_MB_2U_LIB.S9S_MB_2U(SCH_1):PAGE279',
 PHYS_PAGE='293',
 XY='(-5775,12125)',
 ROT='0',
 VER='1',
 PACK_TYPE='C0402',
 LOCATION='PC444_P1_1',
 CDS_LIB='pure_quanta',
 CDS_PART_NAME='Q_CAP_C0402-1UF,16V,10%,X6S,CHA',
 TOLERANCE='10%',
 MATERIAL='X6S',
 VOLTAGE='16V',
 VALUE='1UF',
 PRIM_FILE='./archive_libs/logical/q_cap/chips/chips.prt';

PART_NAME
 PC445_P1_2 'Q_CAP_C0402-1UF,16V,10%,X6S,CHA':;

SECTION_NUMBER 1
 '@S9S_MB_2U_LIB.S9S_MB_2U(SCH_1):PAGE279_I37@PURE_QUANTA.Q_CAP(CHIPS)':
 C_PATH='@s9s_mb_2u_lib.s9s_mb_2u(sch_1):page279_i37@pure_quanta.q_cap(chips)',
 P_PATH='@s9s_mb_2u_lib.s9s_mb_2u(sch_1):page293_i37@pure_quanta.q_cap(chips)',
 PATH='I37',
 DRAWING='@S9S_MB_2U_LIB.S9S_MB_2U(SCH_1):PAGE279',
 PHYS_PAGE='293',
 XY='(-5775,9325)',
 ROT='0',
 VER='1',
 PACK_TYPE='C0402',
 LOCATION='PC445_P1_2',
 CDS_LIB='pure_quanta',
 CDS_PART_NAME='Q_CAP_C0402-1UF,16V,10%,X6S,CHA',
 TOLERANCE='10%',
 MATERIAL='X6S',
 VOLTAGE='16V',
 VALUE='1UF',
 PRIM_FILE='./archive_libs/logical/q_cap/chips/chips.prt';

PART_NAME
 PC446 'Q_CAP_C0402-100NF,50V,10%,X7R,A':;

SECTION_NUMBER 1
 '@S9S_MB_2U_LIB.S9S_MB_2U(SCH_1):PAGE279_I52@PURE_QUANTA.Q_CAP(CHIPS)':
 C_PATH='@s9s_mb_2u_lib.s9s_mb_2u(sch_1):page279_i52@pure_quanta.q_cap(chips)',
 P_PATH='@s9s_mb_2u_lib.s9s_mb_2u(sch_1):page293_i52@pure_quanta.q_cap(chips)',
 PATH='I52',
 DRAWING='@S9S_MB_2U_LIB.S9S_MB_2U(SCH_1):PAGE279',
 PHYS_PAGE='293',
 XY='(-4800,11500)',
 ROT='2',
 VER='1',
 PACK_TYPE='C0402',
 LOCATION='PC446',
 CDS_LIB='pure_quanta',
 CDS_PART_NAME='Q_CAP_C0402-100NF,50V,10%,X7R,A',
 TOLERANCE='10%',
 MATERIAL='X7R',
 VOLTAGE='50V',
 VALUE='100NF',
 PRIM_FILE='./archive_libs/logical/q_cap/chips/chips.prt';

PART_NAME
 PC447 'Q_CAP_C0402-100NF,50V,10%,X7R,A':;

SECTION_NUMBER 1
 '@S9S_MB_2U_LIB.S9S_MB_2U(SCH_1):PAGE279_I44@PURE_QUANTA.Q_CAP(CHIPS)':
 C_PATH='@s9s_mb_2u_lib.s9s_mb_2u(sch_1):page279_i44@pure_quanta.q_cap(chips)',
 P_PATH='@s9s_mb_2u_lib.s9s_mb_2u(sch_1):page293_i44@pure_quanta.q_cap(chips)',
 PATH='I44',
 DRAWING='@S9S_MB_2U_LIB.S9S_MB_2U(SCH_1):PAGE279',
 PHYS_PAGE='293',
 XY='(-4800,8700)',
 ROT='2',
 VER='1',
 PACK_TYPE='C0402',
 LOCATION='PC447',
 CDS_LIB='pure_quanta',
 CDS_PART_NAME='Q_CAP_C0402-100NF,50V,10%,X7R,A',
 TOLERANCE='10%',
 MATERIAL='X7R',
 VOLTAGE='50V',
 VALUE='100NF',
 PRIM_FILE='./archive_libs/logical/q_cap/chips/chips.prt';

PART_NAME
 PC448_P1_1 'Q_CAP_C0805-22UF,16V,20%,X6S,CA':;

SECTION_NUMBER 1
 '@S9S_MB_2U_LIB.S9S_MB_2U(SCH_1):PAGE279_I51@PURE_QUANTA.Q_CAP(CHIPS)':
 C_PATH='@s9s_mb_2u_lib.s9s_mb_2u(sch_1):page279_i51@pure_quanta.q_cap(chips)',
 P_PATH='@s9s_mb_2u_lib.s9s_mb_2u(sch_1):page293_i51@pure_quanta.q_cap(chips)',
 PATH='I51',
 DRAWING='@S9S_MB_2U_LIB.S9S_MB_2U(SCH_1):PAGE279',
 PHYS_PAGE='293',
 XY='(-5375,12125)',
 ROT='0',
 VER='1',
 PACK_TYPE='C0805',
 LOCATION='PC448_P1_1',
 CDS_LIB='pure_quanta',
 CDS_PART_NAME='Q_CAP_C0805-22UF,16V,20%,X6S,CA',
 TOLERANCE='20%',
 MATERIAL='X6S',
 VOLTAGE='16V',
 VALUE='22UF',
 PRIM_FILE='./archive_libs/logical/q_cap/chips/chips.prt';

PART_NAME
 PC449_P1_2 'Q_CAP_C0805-22UF,16V,20%,X6S,CA':;

SECTION_NUMBER 1
 '@S9S_MB_2U_LIB.S9S_MB_2U(SCH_1):PAGE279_I43@PURE_QUANTA.Q_CAP(CHIPS)':
 C_PATH='@s9s_mb_2u_lib.s9s_mb_2u(sch_1):page279_i43@pure_quanta.q_cap(chips)',
 P_PATH='@s9s_mb_2u_lib.s9s_mb_2u(sch_1):page293_i43@pure_quanta.q_cap(chips)',
 PATH='I43',
 DRAWING='@S9S_MB_2U_LIB.S9S_MB_2U(SCH_1):PAGE279',
 PHYS_PAGE='293',
 XY='(-5375,9325)',
 ROT='0',
 VER='1',
 PACK_TYPE='C0805',
 LOCATION='PC449_P1_2',
 CDS_LIB='pure_quanta',
 CDS_PART_NAME='Q_CAP_C0805-22UF,16V,20%,X6S,CA',
 TOLERANCE='20%',
 MATERIAL='X6S',
 VOLTAGE='16V',
 VALUE='22UF',
 PRIM_FILE='./archive_libs/logical/q_cap/chips/chips.prt';

PART_NAME
 PC450_P1_1 'Q_CAP_C0805-22UF,16V,20%,X6S,CA':;

SECTION_NUMBER 1
 '@S9S_MB_2U_LIB.S9S_MB_2U(SCH_1):PAGE279_I53@PURE_QUANTA.Q_CAP(CHIPS)':
 C_PATH='@s9s_mb_2u_lib.s9s_mb_2u(sch_1):page279_i53@pure_quanta.q_cap(chips)',
 P_PATH='@s9s_mb_2u_lib.s9s_mb_2u(sch_1):page293_i53@pure_quanta.q_cap(chips)',
 PATH='I53',
 DRAWING='@S9S_MB_2U_LIB.S9S_MB_2U(SCH_1):PAGE279',
 PHYS_PAGE='293',
 XY='(-4975,12125)',
 ROT='0',
 VER='1',
 PACK_TYPE='C0805',
 LOCATION='PC450_P1_1',
 CDS_LIB='pure_quanta',
 CDS_PART_NAME='Q_CAP_C0805-22UF,16V,20%,X6S,CA',
 TOLERANCE='20%',
 MATERIAL='X6S',
 VOLTAGE='16V',
 VALUE='22UF',
 PRIM_FILE='./archive_libs/logical/q_cap/chips/chips.prt';

PART_NAME
 PC451_P1_2 'Q_CAP_C0805-22UF,16V,20%,X6S,CA':;

SECTION_NUMBER 1
 '@S9S_MB_2U_LIB.S9S_MB_2U(SCH_1):PAGE279_I45@PURE_QUANTA.Q_CAP(CHIPS)':
 C_PATH='@s9s_mb_2u_lib.s9s_mb_2u(sch_1):page279_i45@pure_quanta.q_cap(chips)',
 P_PATH='@s9s_mb_2u_lib.s9s_mb_2u(sch_1):page293_i45@pure_quanta.q_cap(chips)',
 PATH='I45',
 DRAWING='@S9S_MB_2U_LIB.S9S_MB_2U(SCH_1):PAGE279',
 PHYS_PAGE='293',
 XY='(-4975,9325)',
 ROT='0',
 VER='1',
 PACK_TYPE='C0805',
 LOCATION='PC451_P1_2',
 CDS_LIB='pure_quanta',
 CDS_PART_NAME='Q_CAP_C0805-22UF,16V,20%,X6S,CA',
 TOLERANCE='20%',
 MATERIAL='X6S',
 VOLTAGE='16V',
 VALUE='22UF',
 PRIM_FILE='./archive_libs/logical/q_cap/chips/chips.prt';

PART_NAME
 PC452_P1_1 'Q_CAP_C0402-100NF,50V,10%,X7R,A':;

SECTION_NUMBER 1
 '@S9S_MB_2U_LIB.S9S_MB_2U(SCH_1):PAGE279_I55@PURE_QUANTA.Q_CAP(CHIPS)':
 C_PATH='@s9s_mb_2u_lib.s9s_mb_2u(sch_1):page279_i55@pure_quanta.q_cap(chips)',
 P_PATH='@s9s_mb_2u_lib.s9s_mb_2u(sch_1):page293_i55@pure_quanta.q_cap(chips)',
 PATH='I55',
 DRAWING='@S9S_MB_2U_LIB.S9S_MB_2U(SCH_1):PAGE279',
 PHYS_PAGE='293',
 XY='(-3925,11025)',
 ROT='0',
 VER='1',
 PACK_TYPE='C0402',
 LOCATION='PC452_P1_1',
 CDS_LIB='pure_quanta',
 CDS_PART_NAME='Q_CAP_C0402-100NF,50V,10%,X7R,A',
 TOLERANCE='10%',
 MATERIAL='X7R',
 VOLTAGE='50V',
 VALUE='100NF',
 PRIM_FILE='./archive_libs/logical/q_cap/chips/chips.prt';

PART_NAME
 PC455_P1_1 'Q_CAP_C0805-22UF,4V,20%,X6S,CHA':;

SECTION_NUMBER 1
 '@S9S_MB_2U_LIB.S9S_MB_2U(SCH_1):PAGE279_I63@PURE_QUANTA.Q_CAP(CHIPS)':
 C_PATH='@s9s_mb_2u_lib.s9s_mb_2u(sch_1):page279_i63@pure_quanta.q_cap(chips)',
 P_PATH='@s9s_mb_2u_lib.s9s_mb_2u(sch_1):page293_i63@pure_quanta.q_cap(chips)',
 PATH='I63',
 DRAWING='@S9S_MB_2U_LIB.S9S_MB_2U(SCH_1):PAGE279',
 PHYS_PAGE='293',
 XY='(-3525,11025)',
 ROT='0',
 VER='1',
 PACK_TYPE='C0805',
 LOCATION='PC455_P1_1',
 CDS_LIB='pure_quanta',
 CDS_PART_NAME='Q_CAP_C0805-22UF,4V,20%,X6S,CHA',
 TOLERANCE='20%',
 MATERIAL='X6S',
 VOLTAGE='4V',
 VALUE='22UF',
 PRIM_FILE='./archive_libs/logical/q_cap/chips/chips.prt';

PART_NAME
 PC456_P1_2 'Q_CAP_C0805-22UF,4V,20%,X6S,CHA':;

SECTION_NUMBER 1
 '@S9S_MB_2U_LIB.S9S_MB_2U(SCH_1):PAGE279_I32@PURE_QUANTA.Q_CAP(CHIPS)':
 C_PATH='@s9s_mb_2u_lib.s9s_mb_2u(sch_1):page279_i32@pure_quanta.q_cap(chips)',
 P_PATH='@s9s_mb_2u_lib.s9s_mb_2u(sch_1):page293_i32@pure_quanta.q_cap(chips)',
 PATH='I32',
 DRAWING='@S9S_MB_2U_LIB.S9S_MB_2U(SCH_1):PAGE279',
 PHYS_PAGE='293',
 XY='(-3700,8225)',
 ROT='0',
 VER='1',
 PACK_TYPE='C0805',
 LOCATION='PC456_P1_2',
 CDS_LIB='pure_quanta',
 CDS_PART_NAME='Q_CAP_C0805-22UF,4V,20%,X6S,CHA',
 TOLERANCE='20%',
 MATERIAL='X6S',
 VOLTAGE='4V',
 VALUE='22UF',
 PRIM_FILE='./archive_libs/logical/q_cap/chips/chips.prt';

PART_NAME
 PC457_P1_1 'Q_CAP_C0805-22UF,4V,20%,X6S,CHA':;

SECTION_NUMBER 1
 '@S9S_MB_2U_LIB.S9S_MB_2U(SCH_1):PAGE279_I65@PURE_QUANTA.Q_CAP(CHIPS)':
 C_PATH='@s9s_mb_2u_lib.s9s_mb_2u(sch_1):page279_i65@pure_quanta.q_cap(chips)',
 P_PATH='@s9s_mb_2u_lib.s9s_mb_2u(sch_1):page293_i65@pure_quanta.q_cap(chips)',
 PATH='I65',
 DRAWING='@S9S_MB_2U_LIB.S9S_MB_2U(SCH_1):PAGE279',
 PHYS_PAGE='293',
 XY='(-3100,11025)',
 ROT='0',
 VER='1',
 PACK_TYPE='C0805',
 LOCATION='PC457_P1_1',
 CDS_LIB='pure_quanta',
 CDS_PART_NAME='Q_CAP_C0805-22UF,4V,20%,X6S,CHA',
 TOLERANCE='20%',
 MATERIAL='X6S',
 VOLTAGE='4V',
 VALUE='22UF',
 PRIM_FILE='./archive_libs/logical/q_cap/chips/chips.prt';

PART_NAME
 PC458_P1_2 'Q_CAP_C0805-22UF,4V,20%,X6S,CHA':;

SECTION_NUMBER 1
 '@S9S_MB_2U_LIB.S9S_MB_2U(SCH_1):PAGE279_I33@PURE_QUANTA.Q_CAP(CHIPS)':
 C_PATH='@s9s_mb_2u_lib.s9s_mb_2u(sch_1):page279_i33@pure_quanta.q_cap(chips)',
 P_PATH='@s9s_mb_2u_lib.s9s_mb_2u(sch_1):page293_i33@pure_quanta.q_cap(chips)',
 PATH='I33',
 DRAWING='@S9S_MB_2U_LIB.S9S_MB_2U(SCH_1):PAGE279',
 PHYS_PAGE='293',
 XY='(-3275,8225)',
 ROT='0',
 VER='1',
 PACK_TYPE='C0805',
 LOCATION='PC458_P1_2',
 CDS_LIB='pure_quanta',
 CDS_PART_NAME='Q_CAP_C0805-22UF,4V,20%,X6S,CHA',
 TOLERANCE='20%',
 MATERIAL='X6S',
 VOLTAGE='4V',
 VALUE='22UF',
 PRIM_FILE='./archive_libs/logical/q_cap/chips/chips.prt';

PART_NAME
 PC460 'Q_CAPP_THLF-270UF,16V,20%,OSCOA':;

SECTION_NUMBER 1
 '@S9S_MB_2U_LIB.S9S_MB_2U(SCH_1):PAGE279_I69@PURE_QUANTA.Q_CAPP(CHIPS)':
 C_PATH='@s9s_mb_2u_lib.s9s_mb_2u(sch_1):page279_i69@pure_quanta.q_capp(chips)',
 P_PATH='@s9s_mb_2u_lib.s9s_mb_2u(sch_1):page293_i69@pure_quanta.q_capp(chips)',
 PATH='I69',
 DRAWING='@S9S_MB_2U_LIB.S9S_MB_2U(SCH_1):PAGE279',
 PHYS_PAGE='293',
 XY='(-2375,12350)',
 ROT='0',
 VER='1',
 PACK_TYPE='THLF',
 LOCATION='PC460',
 CDS_LIB='pure_quanta',
 CDS_PART_NAME='Q_CAPP_THLF-270UF,16V,20%,OSCOA',
 TOLERANCE='20%',
 MATERIAL='OSCON',
 VOLTAGE='16V',
 VALUE='270UF',
 PRIM_FILE='./archive_libs/logical/q_capp/chips/chips.prt';

PART_NAME
 PC461 'Q_CAPP_THLF-270UF,16V,20%,OSCOA':;

SECTION_NUMBER 1
 '@S9S_MB_2U_LIB.S9S_MB_2U(SCH_1):PAGE279_I70@PURE_QUANTA.Q_CAPP(CHIPS)':
 C_PATH='@s9s_mb_2u_lib.s9s_mb_2u(sch_1):page279_i70@pure_quanta.q_capp(chips)',
 P_PATH='@s9s_mb_2u_lib.s9s_mb_2u(sch_1):page293_i70@pure_quanta.q_capp(chips)',
 PATH='I70',
 DRAWING='@S9S_MB_2U_LIB.S9S_MB_2U(SCH_1):PAGE279',
 PHYS_PAGE='293',
 XY='(-1975,12350)',
 ROT='0',
 VER='1',
 PACK_TYPE='THLF',
 LOCATION='PC461',
 CDS_LIB='pure_quanta',
 CDS_PART_NAME='Q_CAPP_THLF-270UF,16V,20%,OSCOA',
 TOLERANCE='20%',
 MATERIAL='OSCON',
 VOLTAGE='16V',
 VALUE='270UF',
 PRIM_FILE='./archive_libs/logical/q_capp/chips/chips.prt';

PART_NAME
 PC467 'Q_CAP_0402-0.1UF,25V,10%,EMPTYA':;

SECTION_NUMBER 1
 '@S9S_MB_2U_LIB.S9S_MB_2U(SCH_1):PAGE278_I28@PURE_QUANTA.Q_CAP(CHIPS)':
 C_PATH='@s9s_mb_2u_lib.s9s_mb_2u(sch_1):page278_i28@pure_quanta.q_cap(chips)',
 P_PATH='@s9s_mb_2u_lib.s9s_mb_2u(sch_1):page292_i28@pure_quanta.q_cap(chips)',
 PATH='I28',
 DRAWING='@S9S_MB_2U_LIB.S9S_MB_2U(SCH_1):PAGE278',
 PHYS_PAGE='292',
 XY='(1875,3500)',
 ROT='0',
 VER='1',
 PACK_TYPE='0402',
 LOCATION='PC467',
 CDS_LIB='pure_quanta',
 CDS_PART_NAME='Q_CAP_0402-0.1UF,25V,10%,EMPTYA',
 TOLERANCE='10%',
 MATERIAL='EMPTY',
 VOLTAGE='25V',
 VALUE='0.1UF',
 PRIM_FILE='./archive_libs/logical/q_cap/chips/chips.prt';

PART_NAME
 PC468 'Q_CAP_0402-3300PF,50V,10%,X7R,A':;

SECTION_NUMBER 1
 '@S9S_MB_2U_LIB.S9S_MB_2U(SCH_1):PAGE278_I53@PURE_QUANTA.Q_CAP(CHIPS)':
 C_PATH='@s9s_mb_2u_lib.s9s_mb_2u(sch_1):page278_i53@pure_quanta.q_cap(chips)',
 P_PATH='@s9s_mb_2u_lib.s9s_mb_2u(sch_1):page292_i53@pure_quanta.q_cap(chips)',
 PATH='I53',
 DRAWING='@S9S_MB_2U_LIB.S9S_MB_2U(SCH_1):PAGE278',
 PHYS_PAGE='292',
 XY='(1975,6975)',
 ROT='0',
 VER='1',
 PACK_TYPE='0402',
 LOCATION='PC468',
 CDS_LIB='pure_quanta',
 CDS_PART_NAME='Q_CAP_0402-3300PF,50V,10%,X7R,A',
 TOLERANCE='10%',
 MATERIAL='X7R',
 VOLTAGE='50V',
 VALUE='3300PF',
 PRIM_FILE='./archive_libs/logical/q_cap/chips/chips.prt';

PART_NAME
 PC469 'Q_CAP_0402-3300PF,50V,10%,X7R,A':;

SECTION_NUMBER 1
 '@S9S_MB_2U_LIB.S9S_MB_2U(SCH_1):PAGE278_I51@PURE_QUANTA.Q_CAP(CHIPS)':
 C_PATH='@s9s_mb_2u_lib.s9s_mb_2u(sch_1):page278_i51@pure_quanta.q_cap(chips)',
 P_PATH='@s9s_mb_2u_lib.s9s_mb_2u(sch_1):page292_i51@pure_quanta.q_cap(chips)',
 PATH='I51',
 DRAWING='@S9S_MB_2U_LIB.S9S_MB_2U(SCH_1):PAGE278',
 PHYS_PAGE='292',
 XY='(1975,5875)',
 ROT='0',
 VER='1',
 PACK_TYPE='0402',
 LOCATION='PC469',
 CDS_LIB='pure_quanta',
 CDS_PART_NAME='Q_CAP_0402-3300PF,50V,10%,X7R,A',
 TOLERANCE='10%',
 MATERIAL='X7R',
 VOLTAGE='50V',
 VALUE='3300PF',
 PRIM_FILE='./archive_libs/logical/q_cap/chips/chips.prt';

PART_NAME
 PC474 'Q_CAP_0402-0.1UF,25V,10%,X7R,CA':;

SECTION_NUMBER 1
 '@S9S_MB_2U_LIB.S9S_MB_2U(SCH_1):PAGE278_I36@PURE_QUANTA.Q_CAP(CHIPS)':
 C_PATH='@s9s_mb_2u_lib.s9s_mb_2u(sch_1):page278_i36@pure_quanta.q_cap(chips)',
 P_PATH='@s9s_mb_2u_lib.s9s_mb_2u(sch_1):page292_i36@pure_quanta.q_cap(chips)',
 PATH='I36',
 DRAWING='@S9S_MB_2U_LIB.S9S_MB_2U(SCH_1):PAGE278',
 PHYS_PAGE='292',
 XY='(2625,3500)',
 ROT='0',
 VER='1',
 PACK_TYPE='0402',
 LOCATION='PC474',
 CDS_LIB='pure_quanta',
 CDS_PART_NAME='Q_CAP_0402-0.1UF,25V,10%,X7R,CA',
 TOLERANCE='10%',
 MATERIAL='X7R',
 VOLTAGE='25V',
 VALUE='0.1UF',
 PRIM_FILE='./archive_libs/logical/q_cap/chips/chips.prt';

PART_NAME
 PC475 'Q_CAP_0402-470PF,50V,10%,X7R,TA':;

SECTION_NUMBER 1
 '@S9S_MB_2U_LIB.S9S_MB_2U(SCH_1):PAGE278_I66@PURE_QUANTA.Q_CAP(CHIPS)':
 C_PATH='@s9s_mb_2u_lib.s9s_mb_2u(sch_1):page278_i66@pure_quanta.q_cap(chips)',
 P_PATH='@s9s_mb_2u_lib.s9s_mb_2u(sch_1):page292_i66@pure_quanta.q_cap(chips)',
 PATH='I66',
 DRAWING='@S9S_MB_2U_LIB.S9S_MB_2U(SCH_1):PAGE278',
 PHYS_PAGE='292',
 XY='(4375,3775)',
 ROT='0',
 VER='1',
 PACK_TYPE='0402',
 LOCATION='PC475',
 CDS_LIB='pure_quanta',
 CDS_PART_NAME='Q_CAP_0402-470PF,50V,10%,X7R,TA',
 TOLERANCE='10%',
 MATERIAL='X7R',
 VOLTAGE='50V',
 VALUE='470PF',
 PRIM_FILE='./archive_libs/logical/q_cap/chips/chips.prt';

PART_NAME
 PC476 'Q_CAP_C0402-100NF,50V,10%,EMPTA':;

SECTION_NUMBER 1
 '@S9S_MB_2U_LIB.S9S_MB_2U(SCH_1):PAGE278_I93@PURE_QUANTA.Q_CAP(CHIPS)':
 C_PATH='@s9s_mb_2u_lib.s9s_mb_2u(sch_1):page278_i93@pure_quanta.q_cap(chips)',
 P_PATH='@s9s_mb_2u_lib.s9s_mb_2u(sch_1):page292_i93@pure_quanta.q_cap(chips)',
 PATH='I93',
 DRAWING='@S9S_MB_2U_LIB.S9S_MB_2U(SCH_1):PAGE278',
 PHYS_PAGE='292',
 XY='(4800,8950)',
 ROT='0',
 VER='1',
 PACK_TYPE='C0402',
 LOCATION='PC476',
 CDS_LIB='pure_quanta',
 CDS_PART_NAME='Q_CAP_C0402-100NF,50V,10%,EMPTA',
 TOLERANCE='10%',
 MATERIAL='EMPTY',
 VOLTAGE='50V',
 VALUE='100NF',
 PRIM_FILE='./archive_libs/logical/q_cap/chips/chips.prt';

PART_NAME
 PC477 'Q_CAP_C0402-10UF,6.3V,20%,X6S,B':;

SECTION_NUMBER 1
 '@S9S_MB_2U_LIB.S9S_MB_2U(SCH_1):PAGE278_I92@PURE_QUANTA.Q_CAP(CHIPS)':
 C_PATH='@s9s_mb_2u_lib.s9s_mb_2u(sch_1):page278_i92@pure_quanta.q_cap(chips)',
 P_PATH='@s9s_mb_2u_lib.s9s_mb_2u(sch_1):page292_i92@pure_quanta.q_cap(chips)',
 PATH='I92',
 DRAWING='@S9S_MB_2U_LIB.S9S_MB_2U(SCH_1):PAGE278',
 PHYS_PAGE='292',
 XY='(4800,8475)',
 ROT='0',
 VER='1',
 PACK_TYPE='C0402',
 LOCATION='PC477',
 CDS_LIB='pure_quanta',
 CDS_PART_NAME='Q_CAP_C0402-10UF,6.3V,20%,X6S,B',
 TOLERANCE='20%',
 MATERIAL='X6S',
 VOLTAGE='6.3V',
 VALUE='10UF',
 PRIM_FILE='./archive_libs/logical/q_cap/chips/chips.prt';

PART_NAME
 PC478 'Q_CAP_C0402-1UF,16V,10%,X6S,CHA':;

SECTION_NUMBER 1
 '@S9S_MB_2U_LIB.S9S_MB_2U(SCH_1):PAGE278_I97@PURE_QUANTA.Q_CAP(CHIPS)':
 C_PATH='@s9s_mb_2u_lib.s9s_mb_2u(sch_1):page278_i97@pure_quanta.q_cap(chips)',
 P_PATH='@s9s_mb_2u_lib.s9s_mb_2u(sch_1):page292_i97@pure_quanta.q_cap(chips)',
 PATH='I97',
 DRAWING='@S9S_MB_2U_LIB.S9S_MB_2U(SCH_1):PAGE278',
 PHYS_PAGE='292',
 XY='(5200,8950)',
 ROT='0',
 VER='1',
 PACK_TYPE='C0402',
 LOCATION='PC478',
 CDS_LIB='pure_quanta',
 CDS_PART_NAME='Q_CAP_C0402-1UF,16V,10%,X6S,CHA',
 TOLERANCE='10%',
 MATERIAL='X6S',
 VOLTAGE='16V',
 VALUE='1UF',
 PRIM_FILE='./archive_libs/logical/q_cap/chips/chips.prt';

PART_NAME
 PC479 'Q_CAP_C0402-2.2UF,10V,10%,X6S,A':;

SECTION_NUMBER 1
 '@S9S_MB_2U_LIB.S9S_MB_2U(SCH_1):PAGE274_I9@PURE_QUANTA.Q_CAP(CHIPS)':
 C_PATH='@s9s_mb_2u_lib.s9s_mb_2u(sch_1):page274_i9@pure_quanta.q_cap(chips)',
 P_PATH='@s9s_mb_2u_lib.s9s_mb_2u(sch_1):page288_i9@pure_quanta.q_cap(chips)',
 PATH='I9',
 DRAWING='@S9S_MB_2U_LIB.S9S_MB_2U(SCH_1):PAGE274',
 PHYS_PAGE='288',
 XY='(-7550,2200)',
 ROT='0',
 VER='1',
 PACK_TYPE='C0402',
 LOCATION='PC479',
 CDS_LIB='pure_quanta',
 CDS_PART_NAME='Q_CAP_C0402-2.2UF,10V,10%,X6S,A',
 TOLERANCE='10%',
 MATERIAL='X6S',
 VOLTAGE='10V',
 VALUE='2.2UF',
 PRIM_FILE='./archive_libs/logical/q_cap/chips/chips.prt';

PART_NAME
 PC480 'Q_CAP_C0402-2.2UF,10V,10%,X6S,A':;

SECTION_NUMBER 1
 '@S9S_MB_2U_LIB.S9S_MB_2U(SCH_1):PAGE274_I34@PURE_QUANTA.Q_CAP(CHIPS)':
 C_PATH='@s9s_mb_2u_lib.s9s_mb_2u(sch_1):page274_i34@pure_quanta.q_cap(chips)',
 P_PATH='@s9s_mb_2u_lib.s9s_mb_2u(sch_1):page288_i34@pure_quanta.q_cap(chips)',
 PATH='I34',
 DRAWING='@S9S_MB_2U_LIB.S9S_MB_2U(SCH_1):PAGE274',
 PHYS_PAGE='288',
 XY='(-7525,5025)',
 ROT='0',
 VER='1',
 PACK_TYPE='C0402',
 LOCATION='PC480',
 CDS_LIB='pure_quanta',
 CDS_PART_NAME='Q_CAP_C0402-2.2UF,10V,10%,X6S,A',
 TOLERANCE='10%',
 MATERIAL='X6S',
 VOLTAGE='10V',
 VALUE='2.2UF',
 PRIM_FILE='./archive_libs/logical/q_cap/chips/chips.prt';

PART_NAME
 PC481_P1_8 'Q_CAP_C0402-2.2UF,10V,10%,X6S,A':;

SECTION_NUMBER 1
 '@S9S_MB_2U_LIB.S9S_MB_2U(SCH_1):PAGE274_I18@PURE_QUANTA.Q_CAP(CHIPS)':
 C_PATH='@s9s_mb_2u_lib.s9s_mb_2u(sch_1):page274_i18@pure_quanta.q_cap(chips)',
 P_PATH='@s9s_mb_2u_lib.s9s_mb_2u(sch_1):page288_i18@pure_quanta.q_cap(chips)',
 PATH='I18',
 DRAWING='@S9S_MB_2U_LIB.S9S_MB_2U(SCH_1):PAGE274',
 PHYS_PAGE='288',
 XY='(-7125,2700)',
 ROT='0',
 VER='1',
 PACK_TYPE='C0402',
 LOCATION='PC481_P1_8',
 CDS_LIB='pure_quanta',
 CDS_PART_NAME='Q_CAP_C0402-2.2UF,10V,10%,X6S,A',
 TOLERANCE='10%',
 MATERIAL='X6S',
 VOLTAGE='10V',
 VALUE='2.2UF',
 PRIM_FILE='./archive_libs/logical/q_cap/chips/chips.prt';

PART_NAME
 PC482_P1_7 'Q_CAP_C0402-2.2UF,10V,10%,X6S,A':;

SECTION_NUMBER 1
 '@S9S_MB_2U_LIB.S9S_MB_2U(SCH_1):PAGE274_I69@PURE_QUANTA.Q_CAP(CHIPS)':
 C_PATH='@s9s_mb_2u_lib.s9s_mb_2u(sch_1):page274_i69@pure_quanta.q_cap(chips)',
 P_PATH='@s9s_mb_2u_lib.s9s_mb_2u(sch_1):page288_i69@pure_quanta.q_cap(chips)',
 PATH='I69',
 DRAWING='@S9S_MB_2U_LIB.S9S_MB_2U(SCH_1):PAGE274',
 PHYS_PAGE='288',
 XY='(-7100,5525)',
 ROT='0',
 VER='1',
 PACK_TYPE='C0402',
 LOCATION='PC482_P1_7',
 CDS_LIB='pure_quanta',
 CDS_PART_NAME='Q_CAP_C0402-2.2UF,10V,10%,X6S,A',
 TOLERANCE='10%',
 MATERIAL='X6S',
 VOLTAGE='10V',
 VALUE='2.2UF',
 PRIM_FILE='./archive_libs/logical/q_cap/chips/chips.prt';

PART_NAME
 PC483_P1_8 'Q_CAP_0402-3300PF,50V,10%,X7R,A':;

SECTION_NUMBER 1
 '@S9S_MB_2U_LIB.S9S_MB_2U(SCH_1):PAGE274_I24@PURE_QUANTA.Q_CAP(CHIPS)':
 C_PATH='@s9s_mb_2u_lib.s9s_mb_2u(sch_1):page274_i24@pure_quanta.q_cap(chips)',
 P_PATH='@s9s_mb_2u_lib.s9s_mb_2u(sch_1):page288_i24@pure_quanta.q_cap(chips)',
 PATH='I24',
 DRAWING='@S9S_MB_2U_LIB.S9S_MB_2U(SCH_1):PAGE274',
 PHYS_PAGE='288',
 XY='(-5225,2600)',
 ROT='0',
 VER='1',
 PACK_TYPE='0402',
 LOCATION='PC483_P1_8',
 CDS_LIB='pure_quanta',
 CDS_PART_NAME='Q_CAP_0402-3300PF,50V,10%,X7R,A',
 TOLERANCE='10%',
 MATERIAL='X7R',
 VOLTAGE='50V',
 VALUE='3300PF',
 PRIM_FILE='./archive_libs/logical/q_cap/chips/chips.prt';

PART_NAME
 PC484_P1_7 'Q_CAP_0402-3300PF,50V,10%,X7R,A':;

SECTION_NUMBER 1
 '@S9S_MB_2U_LIB.S9S_MB_2U(SCH_1):PAGE274_I37@PURE_QUANTA.Q_CAP(CHIPS)':
 C_PATH='@s9s_mb_2u_lib.s9s_mb_2u(sch_1):page274_i37@pure_quanta.q_cap(chips)',
 P_PATH='@s9s_mb_2u_lib.s9s_mb_2u(sch_1):page288_i37@pure_quanta.q_cap(chips)',
 PATH='I37',
 DRAWING='@S9S_MB_2U_LIB.S9S_MB_2U(SCH_1):PAGE274',
 PHYS_PAGE='288',
 XY='(-5200,5425)',
 ROT='0',
 VER='1',
 PACK_TYPE='0402',
 LOCATION='PC484_P1_7',
 CDS_LIB='pure_quanta',
 CDS_PART_NAME='Q_CAP_0402-3300PF,50V,10%,X7R,A',
 TOLERANCE='10%',
 MATERIAL='X7R',
 VOLTAGE='50V',
 VALUE='3300PF',
 PRIM_FILE='./archive_libs/logical/q_cap/chips/chips.prt';

PART_NAME
 PC485_P1_8 'Q_CAP_C0402-1UF,16V,10%,X6S,CHA':;

SECTION_NUMBER 1
 '@S9S_MB_2U_LIB.S9S_MB_2U(SCH_1):PAGE274_I27@PURE_QUANTA.Q_CAP(CHIPS)':
 C_PATH='@s9s_mb_2u_lib.s9s_mb_2u(sch_1):page274_i27@pure_quanta.q_cap(chips)',
 P_PATH='@s9s_mb_2u_lib.s9s_mb_2u(sch_1):page288_i27@pure_quanta.q_cap(chips)',
 PATH='I27',
 DRAWING='@S9S_MB_2U_LIB.S9S_MB_2U(SCH_1):PAGE274',
 PHYS_PAGE='288',
 XY='(-4825,2600)',
 ROT='0',
 VER='1',
 PACK_TYPE='C0402',
 LOCATION='PC485_P1_8',
 CDS_LIB='pure_quanta',
 CDS_PART_NAME='Q_CAP_C0402-1UF,16V,10%,X6S,CHA',
 TOLERANCE='10%',
 MATERIAL='X6S',
 VOLTAGE='16V',
 VALUE='1UF',
 PRIM_FILE='./archive_libs/logical/q_cap/chips/chips.prt';

PART_NAME
 PC486_P1_7 'Q_CAP_C0402-1UF,16V,10%,X6S,CHA':;

SECTION_NUMBER 1
 '@S9S_MB_2U_LIB.S9S_MB_2U(SCH_1):PAGE274_I40@PURE_QUANTA.Q_CAP(CHIPS)':
 C_PATH='@s9s_mb_2u_lib.s9s_mb_2u(sch_1):page274_i40@pure_quanta.q_cap(chips)',
 P_PATH='@s9s_mb_2u_lib.s9s_mb_2u(sch_1):page288_i40@pure_quanta.q_cap(chips)',
 PATH='I40',
 DRAWING='@S9S_MB_2U_LIB.S9S_MB_2U(SCH_1):PAGE274',
 PHYS_PAGE='288',
 XY='(-4800,5425)',
 ROT='0',
 VER='1',
 PACK_TYPE='C0402',
 LOCATION='PC486_P1_7',
 CDS_LIB='pure_quanta',
 CDS_PART_NAME='Q_CAP_C0402-1UF,16V,10%,X6S,CHA',
 TOLERANCE='10%',
 MATERIAL='X6S',
 VOLTAGE='16V',
 VALUE='1UF',
 PRIM_FILE='./archive_libs/logical/q_cap/chips/chips.prt';

PART_NAME
 PC487 'Q_CAP_C0402-100NF,50V,10%,X7R,A':;

SECTION_NUMBER 1
 '@S9S_MB_2U_LIB.S9S_MB_2U(SCH_1):PAGE274_I42@PURE_QUANTA.Q_CAP(CHIPS)':
 C_PATH='@s9s_mb_2u_lib.s9s_mb_2u(sch_1):page274_i42@pure_quanta.q_cap(chips)',
 P_PATH='@s9s_mb_2u_lib.s9s_mb_2u(sch_1):page288_i42@pure_quanta.q_cap(chips)',
 PATH='I42',
 DRAWING='@S9S_MB_2U_LIB.S9S_MB_2U(SCH_1):PAGE274',
 PHYS_PAGE='288',
 XY='(-4050,1975)',
 ROT='2',
 VER='1',
 PACK_TYPE='C0402',
 LOCATION='PC487',
 CDS_LIB='pure_quanta',
 CDS_PART_NAME='Q_CAP_C0402-100NF,50V,10%,X7R,A',
 TOLERANCE='10%',
 MATERIAL='X7R',
 VOLTAGE='50V',
 VALUE='100NF',
 PRIM_FILE='./archive_libs/logical/q_cap/chips/chips.prt';

PART_NAME
 PC488 'Q_CAP_C0402-100NF,50V,10%,X7R,A':;

SECTION_NUMBER 1
 '@S9S_MB_2U_LIB.S9S_MB_2U(SCH_1):PAGE274_I59@PURE_QUANTA.Q_CAP(CHIPS)':
 C_PATH='@s9s_mb_2u_lib.s9s_mb_2u(sch_1):page274_i59@pure_quanta.q_cap(chips)',
 P_PATH='@s9s_mb_2u_lib.s9s_mb_2u(sch_1):page288_i59@pure_quanta.q_cap(chips)',
 PATH='I59',
 DRAWING='@S9S_MB_2U_LIB.S9S_MB_2U(SCH_1):PAGE274',
 PHYS_PAGE='288',
 XY='(-4025,4800)',
 ROT='2',
 VER='1',
 PACK_TYPE='C0402',
 LOCATION='PC488',
 CDS_LIB='pure_quanta',
 CDS_PART_NAME='Q_CAP_C0402-100NF,50V,10%,X7R,A',
 TOLERANCE='10%',
 MATERIAL='X7R',
 VOLTAGE='50V',
 VALUE='100NF',
 PRIM_FILE='./archive_libs/logical/q_cap/chips/chips.prt';

PART_NAME
 PC489_P1_8 'Q_CAP_C0805-22UF,16V,20%,X6S,CA':;

SECTION_NUMBER 1
 '@S9S_MB_2U_LIB.S9S_MB_2U(SCH_1):PAGE274_I28@PURE_QUANTA.Q_CAP(CHIPS)':
 C_PATH='@s9s_mb_2u_lib.s9s_mb_2u(sch_1):page274_i28@pure_quanta.q_cap(chips)',
 P_PATH='@s9s_mb_2u_lib.s9s_mb_2u(sch_1):page288_i28@pure_quanta.q_cap(chips)',
 PATH='I28',
 DRAWING='@S9S_MB_2U_LIB.S9S_MB_2U(SCH_1):PAGE274',
 PHYS_PAGE='288',
 XY='(-4425,2600)',
 ROT='0',
 VER='1',
 PACK_TYPE='C0805',
 LOCATION='PC489_P1_8',
 CDS_LIB='pure_quanta',
 CDS_PART_NAME='Q_CAP_C0805-22UF,16V,20%,X6S,CA',
 TOLERANCE='20%',
 MATERIAL='X6S',
 VOLTAGE='16V',
 VALUE='22UF',
 PRIM_FILE='./archive_libs/logical/q_cap/chips/chips.prt';

PART_NAME
 PC490_P1_7 'Q_CAP_C0805-22UF,16V,20%,X6S,CA':;

SECTION_NUMBER 1
 '@S9S_MB_2U_LIB.S9S_MB_2U(SCH_1):PAGE274_I41@PURE_QUANTA.Q_CAP(CHIPS)':
 C_PATH='@s9s_mb_2u_lib.s9s_mb_2u(sch_1):page274_i41@pure_quanta.q_cap(chips)',
 P_PATH='@s9s_mb_2u_lib.s9s_mb_2u(sch_1):page288_i41@pure_quanta.q_cap(chips)',
 PATH='I41',
 DRAWING='@S9S_MB_2U_LIB.S9S_MB_2U(SCH_1):PAGE274',
 PHYS_PAGE='288',
 XY='(-4400,5425)',
 ROT='0',
 VER='1',
 PACK_TYPE='C0805',
 LOCATION='PC490_P1_7',
 CDS_LIB='pure_quanta',
 CDS_PART_NAME='Q_CAP_C0805-22UF,16V,20%,X6S,CA',
 TOLERANCE='20%',
 MATERIAL='X6S',
 VOLTAGE='16V',
 VALUE='22UF',
 PRIM_FILE='./archive_libs/logical/q_cap/chips/chips.prt';

PART_NAME
 PC491_P1_8 'Q_CAP_C0805-22UF,16V,20%,X6S,CA':;

SECTION_NUMBER 1
 '@S9S_MB_2U_LIB.S9S_MB_2U(SCH_1):PAGE274_I46@PURE_QUANTA.Q_CAP(CHIPS)':
 C_PATH='@s9s_mb_2u_lib.s9s_mb_2u(sch_1):page274_i46@pure_quanta.q_cap(chips)',
 P_PATH='@s9s_mb_2u_lib.s9s_mb_2u(sch_1):page288_i46@pure_quanta.q_cap(chips)',
 PATH='I46',
 DRAWING='@S9S_MB_2U_LIB.S9S_MB_2U(SCH_1):PAGE274',
 PHYS_PAGE='288',
 XY='(-4025,2600)',
 ROT='0',
 VER='1',
 PACK_TYPE='C0805',
 LOCATION='PC491_P1_8',
 CDS_LIB='pure_quanta',
 CDS_PART_NAME='Q_CAP_C0805-22UF,16V,20%,X6S,CA',
 TOLERANCE='20%',
 MATERIAL='X6S',
 VOLTAGE='16V',
 VALUE='22UF',
 PRIM_FILE='./archive_libs/logical/q_cap/chips/chips.prt';

PART_NAME
 PC492_P1_7 'Q_CAP_C0805-22UF,16V,20%,X6S,CA':;

SECTION_NUMBER 1
 '@S9S_MB_2U_LIB.S9S_MB_2U(SCH_1):PAGE274_I61@PURE_QUANTA.Q_CAP(CHIPS)':
 C_PATH='@s9s_mb_2u_lib.s9s_mb_2u(sch_1):page274_i61@pure_quanta.q_cap(chips)',
 P_PATH='@s9s_mb_2u_lib.s9s_mb_2u(sch_1):page288_i61@pure_quanta.q_cap(chips)',
 PATH='I61',
 DRAWING='@S9S_MB_2U_LIB.S9S_MB_2U(SCH_1):PAGE274',
 PHYS_PAGE='288',
 XY='(-4000,5425)',
 ROT='0',
 VER='1',
 PACK_TYPE='C0805',
 LOCATION='PC492_P1_7',
 CDS_LIB='pure_quanta',
 CDS_PART_NAME='Q_CAP_C0805-22UF,16V,20%,X6S,CA',
 TOLERANCE='20%',
 MATERIAL='X6S',
 VOLTAGE='16V',
 VALUE='22UF',
 PRIM_FILE='./archive_libs/logical/q_cap/chips/chips.prt';

PART_NAME
 PC493_P1_8 'Q_CAP_C0805-22UF,16V,20%,X6S,CA':;

SECTION_NUMBER 1
 '@S9S_MB_2U_LIB.S9S_MB_2U(SCH_1):PAGE274_I47@PURE_QUANTA.Q_CAP(CHIPS)':
 C_PATH='@s9s_mb_2u_lib.s9s_mb_2u(sch_1):page274_i47@pure_quanta.q_cap(chips)',
 P_PATH='@s9s_mb_2u_lib.s9s_mb_2u(sch_1):page288_i47@pure_quanta.q_cap(chips)',
 PATH='I47',
 DRAWING='@S9S_MB_2U_LIB.S9S_MB_2U(SCH_1):PAGE274',
 PHYS_PAGE='288',
 XY='(-3650,2600)',
 ROT='0',
 VER='1',
 PACK_TYPE='C0805',
 LOCATION='PC493_P1_8',
 CDS_LIB='pure_quanta',
 CDS_PART_NAME='Q_CAP_C0805-22UF,16V,20%,X6S,CA',
 TOLERANCE='20%',
 MATERIAL='X6S',
 VOLTAGE='16V',
 VALUE='22UF',
 PRIM_FILE='./archive_libs/logical/q_cap/chips/chips.prt';

PART_NAME
 PC494_P1_7 'Q_CAP_C0805-22UF,16V,20%,X6S,CA':;

SECTION_NUMBER 1
 '@S9S_MB_2U_LIB.S9S_MB_2U(SCH_1):PAGE274_I62@PURE_QUANTA.Q_CAP(CHIPS)':
 C_PATH='@s9s_mb_2u_lib.s9s_mb_2u(sch_1):page274_i62@pure_quanta.q_cap(chips)',
 P_PATH='@s9s_mb_2u_lib.s9s_mb_2u(sch_1):page288_i62@pure_quanta.q_cap(chips)',
 PATH='I62',
 DRAWING='@S9S_MB_2U_LIB.S9S_MB_2U(SCH_1):PAGE274',
 PHYS_PAGE='288',
 XY='(-3625,5425)',
 ROT='0',
 VER='1',
 PACK_TYPE='C0805',
 LOCATION='PC494_P1_7',
 CDS_LIB='pure_quanta',
 CDS_PART_NAME='Q_CAP_C0805-22UF,16V,20%,X6S,CA',
 TOLERANCE='20%',
 MATERIAL='X6S',
 VOLTAGE='16V',
 VALUE='22UF',
 PRIM_FILE='./archive_libs/logical/q_cap/chips/chips.prt';

PART_NAME
 PC495_P1_8 'Q_CAP_C0402-1UF,16V,10%,X6S,CHA':;

SECTION_NUMBER 1
 '@S9S_MB_2U_LIB.S9S_MB_2U(SCH_1):PAGE274_I52@PURE_QUANTA.Q_CAP(CHIPS)':
 C_PATH='@s9s_mb_2u_lib.s9s_mb_2u(sch_1):page274_i52@pure_quanta.q_cap(chips)',
 P_PATH='@s9s_mb_2u_lib.s9s_mb_2u(sch_1):page288_i52@pure_quanta.q_cap(chips)',
 PATH='I52',
 DRAWING='@S9S_MB_2U_LIB.S9S_MB_2U(SCH_1):PAGE274',
 PHYS_PAGE='288',
 XY='(-1925,1500)',
 ROT='0',
 VER='1',
 PACK_TYPE='C0402',
 LOCATION='PC495_P1_8',
 CDS_LIB='pure_quanta',
 CDS_PART_NAME='Q_CAP_C0402-1UF,16V,10%,X6S,CHA',
 TOLERANCE='10%',
 MATERIAL='X6S',
 VOLTAGE='16V',
 VALUE='1UF',
 PRIM_FILE='./archive_libs/logical/q_cap/chips/chips.prt';

PART_NAME
 PC496_P1_7 'Q_CAP_C0402-1UF,16V,10%,X6S,CHA':;

SECTION_NUMBER 1
 '@S9S_MB_2U_LIB.S9S_MB_2U(SCH_1):PAGE274_I64@PURE_QUANTA.Q_CAP(CHIPS)':
 C_PATH='@s9s_mb_2u_lib.s9s_mb_2u(sch_1):page274_i64@pure_quanta.q_cap(chips)',
 P_PATH='@s9s_mb_2u_lib.s9s_mb_2u(sch_1):page288_i64@pure_quanta.q_cap(chips)',
 PATH='I64',
 DRAWING='@S9S_MB_2U_LIB.S9S_MB_2U(SCH_1):PAGE274',
 PHYS_PAGE='288',
 XY='(-1675,4325)',
 ROT='0',
 VER='1',
 PACK_TYPE='C0402',
 LOCATION='PC496_P1_7',
 CDS_LIB='pure_quanta',
 CDS_PART_NAME='Q_CAP_C0402-1UF,16V,10%,X6S,CHA',
 TOLERANCE='10%',
 MATERIAL='X6S',
 VOLTAGE='16V',
 VALUE='1UF',
 PRIM_FILE='./archive_libs/logical/q_cap/chips/chips.prt';

PART_NAME
 PC497_P1_8 'Q_CAP_C0805-22UF,4V,20%,X6S,CHA':;

SECTION_NUMBER 1
 '@S9S_MB_2U_LIB.S9S_MB_2U(SCH_1):PAGE274_I53@PURE_QUANTA.Q_CAP(CHIPS)':
 C_PATH='@s9s_mb_2u_lib.s9s_mb_2u(sch_1):page274_i53@pure_quanta.q_cap(chips)',
 P_PATH='@s9s_mb_2u_lib.s9s_mb_2u(sch_1):page288_i53@pure_quanta.q_cap(chips)',
 PATH='I53',
 DRAWING='@S9S_MB_2U_LIB.S9S_MB_2U(SCH_1):PAGE274',
 PHYS_PAGE='288',
 XY='(-1500,1500)',
 ROT='0',
 VER='1',
 PACK_TYPE='C0805',
 LOCATION='PC497_P1_8',
 CDS_LIB='pure_quanta',
 CDS_PART_NAME='Q_CAP_C0805-22UF,4V,20%,X6S,CHA',
 TOLERANCE='20%',
 MATERIAL='X6S',
 VOLTAGE='4V',
 VALUE='22UF',
 PRIM_FILE='./archive_libs/logical/q_cap/chips/chips.prt';

PART_NAME
 PC498_P1_7 'Q_CAP_C0805-22UF,4V,20%,X6S,CHA':;

SECTION_NUMBER 1
 '@S9S_MB_2U_LIB.S9S_MB_2U(SCH_1):PAGE274_I65@PURE_QUANTA.Q_CAP(CHIPS)':
 C_PATH='@s9s_mb_2u_lib.s9s_mb_2u(sch_1):page274_i65@pure_quanta.q_cap(chips)',
 P_PATH='@s9s_mb_2u_lib.s9s_mb_2u(sch_1):page288_i65@pure_quanta.q_cap(chips)',
 PATH='I65',
 DRAWING='@S9S_MB_2U_LIB.S9S_MB_2U(SCH_1):PAGE274',
 PHYS_PAGE='288',
 XY='(-1250,4325)',
 ROT='0',
 VER='1',
 PACK_TYPE='C0805',
 LOCATION='PC498_P1_7',
 CDS_LIB='pure_quanta',
 CDS_PART_NAME='Q_CAP_C0805-22UF,4V,20%,X6S,CHA',
 TOLERANCE='20%',
 MATERIAL='X6S',
 VOLTAGE='4V',
 VALUE='22UF',
 PRIM_FILE='./archive_libs/logical/q_cap/chips/chips.prt';

PART_NAME
 PC499_P1_8 'Q_CAP_C0805-22UF,4V,20%,X6S,CHA':;

SECTION_NUMBER 1
 '@S9S_MB_2U_LIB.S9S_MB_2U(SCH_1):PAGE274_I54@PURE_QUANTA.Q_CAP(CHIPS)':
 C_PATH='@s9s_mb_2u_lib.s9s_mb_2u(sch_1):page274_i54@pure_quanta.q_cap(chips)',
 P_PATH='@s9s_mb_2u_lib.s9s_mb_2u(sch_1):page288_i54@pure_quanta.q_cap(chips)',
 PATH='I54',
 DRAWING='@S9S_MB_2U_LIB.S9S_MB_2U(SCH_1):PAGE274',
 PHYS_PAGE='288',
 XY='(-1075,1500)',
 ROT='0',
 VER='1',
 PACK_TYPE='C0805',
 LOCATION='PC499_P1_8',
 CDS_LIB='pure_quanta',
 CDS_PART_NAME='Q_CAP_C0805-22UF,4V,20%,X6S,CHA',
 TOLERANCE='20%',
 MATERIAL='X6S',
 VOLTAGE='4V',
 VALUE='22UF',
 PRIM_FILE='./archive_libs/logical/q_cap/chips/chips.prt';

PART_NAME
 PC500_P1_7 'Q_CAP_C0805-22UF,4V,20%,X6S,CHA':;

SECTION_NUMBER 1
 '@S9S_MB_2U_LIB.S9S_MB_2U(SCH_1):PAGE274_I66@PURE_QUANTA.Q_CAP(CHIPS)':
 C_PATH='@s9s_mb_2u_lib.s9s_mb_2u(sch_1):page274_i66@pure_quanta.q_cap(chips)',
 P_PATH='@s9s_mb_2u_lib.s9s_mb_2u(sch_1):page288_i66@pure_quanta.q_cap(chips)',
 PATH='I66',
 DRAWING='@S9S_MB_2U_LIB.S9S_MB_2U(SCH_1):PAGE274',
 PHYS_PAGE='288',
 XY='(-825,4325)',
 ROT='0',
 VER='1',
 PACK_TYPE='C0805',
 LOCATION='PC500_P1_7',
 CDS_LIB='pure_quanta',
 CDS_PART_NAME='Q_CAP_C0805-22UF,4V,20%,X6S,CHA',
 TOLERANCE='20%',
 MATERIAL='X6S',
 VOLTAGE='4V',
 VALUE='22UF',
 PRIM_FILE='./archive_libs/logical/q_cap/chips/chips.prt';

PART_NAME
 PC501 'Q_CAP_C0402-2.2UF,10V,10%,X6S,A':;

SECTION_NUMBER 1
 '@S9S_MB_2U_LIB.S9S_MB_2U(SCH_1):PAGE273_I17@PURE_QUANTA.Q_CAP(CHIPS)':
 C_PATH='@s9s_mb_2u_lib.s9s_mb_2u(sch_1):page273_i17@pure_quanta.q_cap(chips)',
 P_PATH='@s9s_mb_2u_lib.s9s_mb_2u(sch_1):page287_i17@pure_quanta.q_cap(chips)',
 PATH='I17',
 DRAWING='@S9S_MB_2U_LIB.S9S_MB_2U(SCH_1):PAGE273',
 PHYS_PAGE='287',
 XY='(3775,175)',
 ROT='0',
 VER='1',
 PACK_TYPE='C0402',
 LOCATION='PC501',
 CDS_LIB='pure_quanta',
 CDS_PART_NAME='Q_CAP_C0402-2.2UF,10V,10%,X6S,A',
 TOLERANCE='10%',
 MATERIAL='X6S',
 VOLTAGE='10V',
 VALUE='2.2UF',
 PRIM_FILE='./archive_libs/logical/q_cap/chips/chips.prt';

PART_NAME
 PC502 'Q_CAP_C0402-2.2UF,10V,10%,X6S,A':;

SECTION_NUMBER 1
 '@S9S_MB_2U_LIB.S9S_MB_2U(SCH_1):PAGE273_I37@PURE_QUANTA.Q_CAP(CHIPS)':
 C_PATH='@s9s_mb_2u_lib.s9s_mb_2u(sch_1):page273_i37@pure_quanta.q_cap(chips)',
 P_PATH='@s9s_mb_2u_lib.s9s_mb_2u(sch_1):page287_i37@pure_quanta.q_cap(chips)',
 PATH='I37',
 DRAWING='@S9S_MB_2U_LIB.S9S_MB_2U(SCH_1):PAGE273',
 PHYS_PAGE='287',
 XY='(3800,3000)',
 ROT='0',
 VER='1',
 PACK_TYPE='C0402',
 LOCATION='PC502',
 CDS_LIB='pure_quanta',
 CDS_PART_NAME='Q_CAP_C0402-2.2UF,10V,10%,X6S,A',
 TOLERANCE='10%',
 MATERIAL='X6S',
 VOLTAGE='10V',
 VALUE='2.2UF',
 PRIM_FILE='./archive_libs/logical/q_cap/chips/chips.prt';

PART_NAME
 PC503_P1_6 'Q_CAP_C0402-2.2UF,10V,10%,X6S,A':;

SECTION_NUMBER 1
 '@S9S_MB_2U_LIB.S9S_MB_2U(SCH_1):PAGE273_I21@PURE_QUANTA.Q_CAP(CHIPS)':
 C_PATH='@s9s_mb_2u_lib.s9s_mb_2u(sch_1):page273_i21@pure_quanta.q_cap(chips)',
 P_PATH='@s9s_mb_2u_lib.s9s_mb_2u(sch_1):page287_i21@pure_quanta.q_cap(chips)',
 PATH='I21',
 DRAWING='@S9S_MB_2U_LIB.S9S_MB_2U(SCH_1):PAGE273',
 PHYS_PAGE='287',
 XY='(4200,675)',
 ROT='0',
 VER='1',
 PACK_TYPE='C0402',
 LOCATION='PC503_P1_6',
 CDS_LIB='pure_quanta',
 CDS_PART_NAME='Q_CAP_C0402-2.2UF,10V,10%,X6S,A',
 TOLERANCE='10%',
 MATERIAL='X6S',
 VOLTAGE='10V',
 VALUE='2.2UF',
 PRIM_FILE='./archive_libs/logical/q_cap/chips/chips.prt';

PART_NAME
 PC504_P1_5 'Q_CAP_C0402-2.2UF,10V,10%,X6S,A':;

SECTION_NUMBER 1
 '@S9S_MB_2U_LIB.S9S_MB_2U(SCH_1):PAGE273_I41@PURE_QUANTA.Q_CAP(CHIPS)':
 C_PATH='@s9s_mb_2u_lib.s9s_mb_2u(sch_1):page273_i41@pure_quanta.q_cap(chips)',
 P_PATH='@s9s_mb_2u_lib.s9s_mb_2u(sch_1):page287_i41@pure_quanta.q_cap(chips)',
 PATH='I41',
 DRAWING='@S9S_MB_2U_LIB.S9S_MB_2U(SCH_1):PAGE273',
 PHYS_PAGE='287',
 XY='(4225,3500)',
 ROT='0',
 VER='1',
 PACK_TYPE='C0402',
 LOCATION='PC504_P1_5',
 CDS_LIB='pure_quanta',
 CDS_PART_NAME='Q_CAP_C0402-2.2UF,10V,10%,X6S,A',
 TOLERANCE='10%',
 MATERIAL='X6S',
 VOLTAGE='10V',
 VALUE='2.2UF',
 PRIM_FILE='./archive_libs/logical/q_cap/chips/chips.prt';

PART_NAME
 PC505_P1_6 'Q_CAP_0402-3300PF,50V,10%,X7R,A':;

SECTION_NUMBER 1
 '@S9S_MB_2U_LIB.S9S_MB_2U(SCH_1):PAGE273_I29@PURE_QUANTA.Q_CAP(CHIPS)':
 C_PATH='@s9s_mb_2u_lib.s9s_mb_2u(sch_1):page273_i29@pure_quanta.q_cap(chips)',
 P_PATH='@s9s_mb_2u_lib.s9s_mb_2u(sch_1):page287_i29@pure_quanta.q_cap(chips)',
 PATH='I29',
 DRAWING='@S9S_MB_2U_LIB.S9S_MB_2U(SCH_1):PAGE273',
 PHYS_PAGE='287',
 XY='(6100,575)',
 ROT='0',
 VER='1',
 PACK_TYPE='0402',
 LOCATION='PC505_P1_6',
 CDS_LIB='pure_quanta',
 CDS_PART_NAME='Q_CAP_0402-3300PF,50V,10%,X7R,A',
 TOLERANCE='10%',
 MATERIAL='X7R',
 VOLTAGE='50V',
 VALUE='3300PF',
 PRIM_FILE='./archive_libs/logical/q_cap/chips/chips.prt';

PART_NAME
 PC506_P1_5 'Q_CAP_0402-3300PF,50V,10%,X7R,A':;

SECTION_NUMBER 1
 '@S9S_MB_2U_LIB.S9S_MB_2U(SCH_1):PAGE273_I45@PURE_QUANTA.Q_CAP(CHIPS)':
 C_PATH='@s9s_mb_2u_lib.s9s_mb_2u(sch_1):page273_i45@pure_quanta.q_cap(chips)',
 P_PATH='@s9s_mb_2u_lib.s9s_mb_2u(sch_1):page287_i45@pure_quanta.q_cap(chips)',
 PATH='I45',
 DRAWING='@S9S_MB_2U_LIB.S9S_MB_2U(SCH_1):PAGE273',
 PHYS_PAGE='287',
 XY='(6125,3400)',
 ROT='0',
 VER='1',
 PACK_TYPE='0402',
 LOCATION='PC506_P1_5',
 CDS_LIB='pure_quanta',
 CDS_PART_NAME='Q_CAP_0402-3300PF,50V,10%,X7R,A',
 TOLERANCE='10%',
 MATERIAL='X7R',
 VOLTAGE='50V',
 VALUE='3300PF',
 PRIM_FILE='./archive_libs/logical/q_cap/chips/chips.prt';

PART_NAME
 PC507_P1_6 'Q_CAP_C0402-1UF,16V,10%,X6S,CHA':;

SECTION_NUMBER 1
 '@S9S_MB_2U_LIB.S9S_MB_2U(SCH_1):PAGE273_I31@PURE_QUANTA.Q_CAP(CHIPS)':
 C_PATH='@s9s_mb_2u_lib.s9s_mb_2u(sch_1):page273_i31@pure_quanta.q_cap(chips)',
 P_PATH='@s9s_mb_2u_lib.s9s_mb_2u(sch_1):page287_i31@pure_quanta.q_cap(chips)',
 PATH='I31',
 DRAWING='@S9S_MB_2U_LIB.S9S_MB_2U(SCH_1):PAGE273',
 PHYS_PAGE='287',
 XY='(6500,575)',
 ROT='0',
 VER='1',
 PACK_TYPE='C0402',
 LOCATION='PC507_P1_6',
 CDS_LIB='pure_quanta',
 CDS_PART_NAME='Q_CAP_C0402-1UF,16V,10%,X6S,CHA',
 TOLERANCE='10%',
 MATERIAL='X6S',
 VOLTAGE='16V',
 VALUE='1UF',
 PRIM_FILE='./archive_libs/logical/q_cap/chips/chips.prt';

PART_NAME
 PC508_P1_5 'Q_CAP_C0402-1UF,16V,10%,X6S,CHA':;

SECTION_NUMBER 1
 '@S9S_MB_2U_LIB.S9S_MB_2U(SCH_1):PAGE273_I46@PURE_QUANTA.Q_CAP(CHIPS)':
 C_PATH='@s9s_mb_2u_lib.s9s_mb_2u(sch_1):page273_i46@pure_quanta.q_cap(chips)',
 P_PATH='@s9s_mb_2u_lib.s9s_mb_2u(sch_1):page287_i46@pure_quanta.q_cap(chips)',
 PATH='I46',
 DRAWING='@S9S_MB_2U_LIB.S9S_MB_2U(SCH_1):PAGE273',
 PHYS_PAGE='287',
 XY='(6525,3400)',
 ROT='0',
 VER='1',
 PACK_TYPE='C0402',
 LOCATION='PC508_P1_5',
 CDS_LIB='pure_quanta',
 CDS_PART_NAME='Q_CAP_C0402-1UF,16V,10%,X6S,CHA',
 TOLERANCE='10%',
 MATERIAL='X6S',
 VOLTAGE='16V',
 VALUE='1UF',
 PRIM_FILE='./archive_libs/logical/q_cap/chips/chips.prt';

PART_NAME
 PC509 'Q_CAP_C0402-100NF,50V,10%,X7R,A':;

SECTION_NUMBER 1
 '@S9S_MB_2U_LIB.S9S_MB_2U(SCH_1):PAGE273_I26@PURE_QUANTA.Q_CAP(CHIPS)':
 C_PATH='@s9s_mb_2u_lib.s9s_mb_2u(sch_1):page273_i26@pure_quanta.q_cap(chips)',
 P_PATH='@s9s_mb_2u_lib.s9s_mb_2u(sch_1):page287_i26@pure_quanta.q_cap(chips)',
 PATH='I26',
 DRAWING='@S9S_MB_2U_LIB.S9S_MB_2U(SCH_1):PAGE273',
 PHYS_PAGE='287',
 XY='(7275,-50)',
 ROT='2',
 VER='1',
 PACK_TYPE='C0402',
 LOCATION='PC509',
 CDS_LIB='pure_quanta',
 CDS_PART_NAME='Q_CAP_C0402-100NF,50V,10%,X7R,A',
 TOLERANCE='10%',
 MATERIAL='X7R',
 VOLTAGE='50V',
 VALUE='100NF',
 PRIM_FILE='./archive_libs/logical/q_cap/chips/chips.prt';

PART_NAME
 PC510 'Q_CAP_C0402-100NF,50V,10%,X7R,A':;

SECTION_NUMBER 1
 '@S9S_MB_2U_LIB.S9S_MB_2U(SCH_1):PAGE273_I47@PURE_QUANTA.Q_CAP(CHIPS)':
 C_PATH='@s9s_mb_2u_lib.s9s_mb_2u(sch_1):page273_i47@pure_quanta.q_cap(chips)',
 P_PATH='@s9s_mb_2u_lib.s9s_mb_2u(sch_1):page287_i47@pure_quanta.q_cap(chips)',
 PATH='I47',
 DRAWING='@S9S_MB_2U_LIB.S9S_MB_2U(SCH_1):PAGE273',
 PHYS_PAGE='287',
 XY='(7300,2775)',
 ROT='2',
 VER='1',
 PACK_TYPE='C0402',
 LOCATION='PC510',
 CDS_LIB='pure_quanta',
 CDS_PART_NAME='Q_CAP_C0402-100NF,50V,10%,X7R,A',
 TOLERANCE='10%',
 MATERIAL='X7R',
 VOLTAGE='50V',
 VALUE='100NF',
 PRIM_FILE='./archive_libs/logical/q_cap/chips/chips.prt';

PART_NAME
 PC511_P1_6 'Q_CAP_C0805-22UF,16V,20%,X6S,CA':;

SECTION_NUMBER 1
 '@S9S_MB_2U_LIB.S9S_MB_2U(SCH_1):PAGE273_I33@PURE_QUANTA.Q_CAP(CHIPS)':
 C_PATH='@s9s_mb_2u_lib.s9s_mb_2u(sch_1):page273_i33@pure_quanta.q_cap(chips)',
 P_PATH='@s9s_mb_2u_lib.s9s_mb_2u(sch_1):page287_i33@pure_quanta.q_cap(chips)',
 PATH='I33',
 DRAWING='@S9S_MB_2U_LIB.S9S_MB_2U(SCH_1):PAGE273',
 PHYS_PAGE='287',
 XY='(6900,575)',
 ROT='0',
 VER='1',
 PACK_TYPE='C0805',
 LOCATION='PC511_P1_6',
 CDS_LIB='pure_quanta',
 CDS_PART_NAME='Q_CAP_C0805-22UF,16V,20%,X6S,CA',
 TOLERANCE='20%',
 MATERIAL='X6S',
 VOLTAGE='16V',
 VALUE='22UF',
 PRIM_FILE='./archive_libs/logical/q_cap/chips/chips.prt';

PART_NAME
 PC512_P1_5 'Q_CAP_C0805-22UF,16V,20%,X6S,CA':;

SECTION_NUMBER 1
 '@S9S_MB_2U_LIB.S9S_MB_2U(SCH_1):PAGE273_I50@PURE_QUANTA.Q_CAP(CHIPS)':
 C_PATH='@s9s_mb_2u_lib.s9s_mb_2u(sch_1):page273_i50@pure_quanta.q_cap(chips)',
 P_PATH='@s9s_mb_2u_lib.s9s_mb_2u(sch_1):page287_i50@pure_quanta.q_cap(chips)',
 PATH='I50',
 DRAWING='@S9S_MB_2U_LIB.S9S_MB_2U(SCH_1):PAGE273',
 PHYS_PAGE='287',
 XY='(6925,3400)',
 ROT='0',
 VER='1',
 PACK_TYPE='C0805',
 LOCATION='PC512_P1_5',
 CDS_LIB='pure_quanta',
 CDS_PART_NAME='Q_CAP_C0805-22UF,16V,20%,X6S,CA',
 TOLERANCE='20%',
 MATERIAL='X6S',
 VOLTAGE='16V',
 VALUE='22UF',
 PRIM_FILE='./archive_libs/logical/q_cap/chips/chips.prt';

PART_NAME
 PC513_P1_6 'Q_CAP_C0805-22UF,16V,20%,X6S,CA':;

SECTION_NUMBER 1
 '@S9S_MB_2U_LIB.S9S_MB_2U(SCH_1):PAGE273_I34@PURE_QUANTA.Q_CAP(CHIPS)':
 C_PATH='@s9s_mb_2u_lib.s9s_mb_2u(sch_1):page273_i34@pure_quanta.q_cap(chips)',
 P_PATH='@s9s_mb_2u_lib.s9s_mb_2u(sch_1):page287_i34@pure_quanta.q_cap(chips)',
 PATH='I34',
 DRAWING='@S9S_MB_2U_LIB.S9S_MB_2U(SCH_1):PAGE273',
 PHYS_PAGE='287',
 XY='(7300,575)',
 ROT='0',
 VER='1',
 PACK_TYPE='C0805',
 LOCATION='PC513_P1_6',
 CDS_LIB='pure_quanta',
 CDS_PART_NAME='Q_CAP_C0805-22UF,16V,20%,X6S,CA',
 TOLERANCE='20%',
 MATERIAL='X6S',
 VOLTAGE='16V',
 VALUE='22UF',
 PRIM_FILE='./archive_libs/logical/q_cap/chips/chips.prt';

PART_NAME
 PC514_P1_5 'Q_CAP_C0805-22UF,16V,20%,X6S,CA':;

SECTION_NUMBER 1
 '@S9S_MB_2U_LIB.S9S_MB_2U(SCH_1):PAGE273_I51@PURE_QUANTA.Q_CAP(CHIPS)':
 C_PATH='@s9s_mb_2u_lib.s9s_mb_2u(sch_1):page273_i51@pure_quanta.q_cap(chips)',
 P_PATH='@s9s_mb_2u_lib.s9s_mb_2u(sch_1):page287_i51@pure_quanta.q_cap(chips)',
 PATH='I51',
 DRAWING='@S9S_MB_2U_LIB.S9S_MB_2U(SCH_1):PAGE273',
 PHYS_PAGE='287',
 XY='(7325,3400)',
 ROT='0',
 VER='1',
 PACK_TYPE='C0805',
 LOCATION='PC514_P1_5',
 CDS_LIB='pure_quanta',
 CDS_PART_NAME='Q_CAP_C0805-22UF,16V,20%,X6S,CA',
 TOLERANCE='20%',
 MATERIAL='X6S',
 VOLTAGE='16V',
 VALUE='22UF',
 PRIM_FILE='./archive_libs/logical/q_cap/chips/chips.prt';

PART_NAME
 PC515_P1_6 'Q_CAP_C0805-22UF,16V,20%,X6S,CA':;

SECTION_NUMBER 1
 '@S9S_MB_2U_LIB.S9S_MB_2U(SCH_1):PAGE273_I35@PURE_QUANTA.Q_CAP(CHIPS)':
 C_PATH='@s9s_mb_2u_lib.s9s_mb_2u(sch_1):page273_i35@pure_quanta.q_cap(chips)',
 P_PATH='@s9s_mb_2u_lib.s9s_mb_2u(sch_1):page287_i35@pure_quanta.q_cap(chips)',
 PATH='I35',
 DRAWING='@S9S_MB_2U_LIB.S9S_MB_2U(SCH_1):PAGE273',
 PHYS_PAGE='287',
 XY='(7675,575)',
 ROT='0',
 VER='1',
 PACK_TYPE='C0805',
 LOCATION='PC515_P1_6',
 CDS_LIB='pure_quanta',
 CDS_PART_NAME='Q_CAP_C0805-22UF,16V,20%,X6S,CA',
 TOLERANCE='20%',
 MATERIAL='X6S',
 VOLTAGE='16V',
 VALUE='22UF',
 PRIM_FILE='./archive_libs/logical/q_cap/chips/chips.prt';

PART_NAME
 PC516_P1_5 'Q_CAP_C0805-22UF,16V,20%,X6S,CA':;

SECTION_NUMBER 1
 '@S9S_MB_2U_LIB.S9S_MB_2U(SCH_1):PAGE273_I52@PURE_QUANTA.Q_CAP(CHIPS)':
 C_PATH='@s9s_mb_2u_lib.s9s_mb_2u(sch_1):page273_i52@pure_quanta.q_cap(chips)',
 P_PATH='@s9s_mb_2u_lib.s9s_mb_2u(sch_1):page287_i52@pure_quanta.q_cap(chips)',
 PATH='I52',
 DRAWING='@S9S_MB_2U_LIB.S9S_MB_2U(SCH_1):PAGE273',
 PHYS_PAGE='287',
 XY='(7700,3400)',
 ROT='0',
 VER='1',
 PACK_TYPE='C0805',
 LOCATION='PC516_P1_5',
 CDS_LIB='pure_quanta',
 CDS_PART_NAME='Q_CAP_C0805-22UF,16V,20%,X6S,CA',
 TOLERANCE='20%',
 MATERIAL='X6S',
 VOLTAGE='16V',
 VALUE='22UF',
 PRIM_FILE='./archive_libs/logical/q_cap/chips/chips.prt';

PART_NAME
 PC519_P1_6 'Q_CAP_C0805-22UF,4V,20%,X6S,CHA':;

SECTION_NUMBER 1
 '@S9S_MB_2U_LIB.S9S_MB_2U(SCH_1):PAGE273_I54@PURE_QUANTA.Q_CAP(CHIPS)':
 C_PATH='@s9s_mb_2u_lib.s9s_mb_2u(sch_1):page273_i54@pure_quanta.q_cap(chips)',
 P_PATH='@s9s_mb_2u_lib.s9s_mb_2u(sch_1):page287_i54@pure_quanta.q_cap(chips)',
 PATH='I54',
 DRAWING='@S9S_MB_2U_LIB.S9S_MB_2U(SCH_1):PAGE273',
 PHYS_PAGE='287',
 XY='(9675,-525)',
 ROT='0',
 VER='1',
 PACK_TYPE='C0805',
 LOCATION='PC519_P1_6',
 CDS_LIB='pure_quanta',
 CDS_PART_NAME='Q_CAP_C0805-22UF,4V,20%,X6S,CHA',
 TOLERANCE='20%',
 MATERIAL='X6S',
 VOLTAGE='4V',
 VALUE='22UF',
 PRIM_FILE='./archive_libs/logical/q_cap/chips/chips.prt';

PART_NAME
 PC520_P1_5 'Q_CAP_C0805-22UF,4V,20%,X6S,CHA':;

SECTION_NUMBER 1
 '@S9S_MB_2U_LIB.S9S_MB_2U(SCH_1):PAGE273_I64@PURE_QUANTA.Q_CAP(CHIPS)':
 C_PATH='@s9s_mb_2u_lib.s9s_mb_2u(sch_1):page273_i64@pure_quanta.q_cap(chips)',
 P_PATH='@s9s_mb_2u_lib.s9s_mb_2u(sch_1):page287_i64@pure_quanta.q_cap(chips)',
 PATH='I64',
 DRAWING='@S9S_MB_2U_LIB.S9S_MB_2U(SCH_1):PAGE273',
 PHYS_PAGE='287',
 XY='(9550,2300)',
 ROT='0',
 VER='1',
 PACK_TYPE='C0805',
 LOCATION='PC520_P1_5',
 CDS_LIB='pure_quanta',
 CDS_PART_NAME='Q_CAP_C0805-22UF,4V,20%,X6S,CHA',
 TOLERANCE='20%',
 MATERIAL='X6S',
 VOLTAGE='4V',
 VALUE='22UF',
 PRIM_FILE='./archive_libs/logical/q_cap/chips/chips.prt';

PART_NAME
 PC521_P1_6 'Q_CAP_C0805-22UF,4V,20%,X6S,CHA':;

SECTION_NUMBER 1
 '@S9S_MB_2U_LIB.S9S_MB_2U(SCH_1):PAGE273_I57@PURE_QUANTA.Q_CAP(CHIPS)':
 C_PATH='@s9s_mb_2u_lib.s9s_mb_2u(sch_1):page273_i57@pure_quanta.q_cap(chips)',
 P_PATH='@s9s_mb_2u_lib.s9s_mb_2u(sch_1):page287_i57@pure_quanta.q_cap(chips)',
 PATH='I57',
 DRAWING='@S9S_MB_2U_LIB.S9S_MB_2U(SCH_1):PAGE273',
 PHYS_PAGE='287',
 XY='(10100,-525)',
 ROT='0',
 VER='1',
 PACK_TYPE='C0805',
 LOCATION='PC521_P1_6',
 CDS_LIB='pure_quanta',
 CDS_PART_NAME='Q_CAP_C0805-22UF,4V,20%,X6S,CHA',
 TOLERANCE='20%',
 MATERIAL='X6S',
 VOLTAGE='4V',
 VALUE='22UF',
 PRIM_FILE='./archive_libs/logical/q_cap/chips/chips.prt';

PART_NAME
 PC522_P1_5 'Q_CAP_C0805-22UF,4V,20%,X6S,CHA':;

SECTION_NUMBER 1
 '@S9S_MB_2U_LIB.S9S_MB_2U(SCH_1):PAGE273_I65@PURE_QUANTA.Q_CAP(CHIPS)':
 C_PATH='@s9s_mb_2u_lib.s9s_mb_2u(sch_1):page273_i65@pure_quanta.q_cap(chips)',
 P_PATH='@s9s_mb_2u_lib.s9s_mb_2u(sch_1):page287_i65@pure_quanta.q_cap(chips)',
 PATH='I65',
 DRAWING='@S9S_MB_2U_LIB.S9S_MB_2U(SCH_1):PAGE273',
 PHYS_PAGE='287',
 XY='(9975,2300)',
 ROT='0',
 VER='1',
 PACK_TYPE='C0805',
 LOCATION='PC522_P1_5',
 CDS_LIB='pure_quanta',
 CDS_PART_NAME='Q_CAP_C0805-22UF,4V,20%,X6S,CHA',
 TOLERANCE='20%',
 MATERIAL='X6S',
 VOLTAGE='4V',
 VALUE='22UF',
 PRIM_FILE='./archive_libs/logical/q_cap/chips/chips.prt';

PART_NAME
 PC523 'Q_CAP_C0402-2.2UF,10V,10%,X6S,A':;

SECTION_NUMBER 1
 '@S9S_MB_2U_LIB.S9S_MB_2U(SCH_1):PAGE272_I11@PURE_QUANTA.Q_CAP(CHIPS)':
 C_PATH='@s9s_mb_2u_lib.s9s_mb_2u(sch_1):page272_i11@pure_quanta.q_cap(chips)',
 P_PATH='@s9s_mb_2u_lib.s9s_mb_2u(sch_1):page286_i11@pure_quanta.q_cap(chips)',
 PATH='I11',
 DRAWING='@S9S_MB_2U_LIB.S9S_MB_2U(SCH_1):PAGE272',
 PHYS_PAGE='286',
 XY='(-2375,-1050)',
 ROT='0',
 VER='1',
 PACK_TYPE='C0402',
 LOCATION='PC523',
 CDS_LIB='pure_quanta',
 CDS_PART_NAME='Q_CAP_C0402-2.2UF,10V,10%,X6S,A',
 TOLERANCE='10%',
 MATERIAL='X6S',
 VOLTAGE='10V',
 VALUE='2.2UF',
 PRIM_FILE='./archive_libs/logical/q_cap/chips/chips.prt';

PART_NAME
 PC524 'Q_CAP_C0402-2.2UF,10V,10%,X6S,A':;

SECTION_NUMBER 1
 '@S9S_MB_2U_LIB.S9S_MB_2U(SCH_1):PAGE272_I24@PURE_QUANTA.Q_CAP(CHIPS)':
 C_PATH='@s9s_mb_2u_lib.s9s_mb_2u(sch_1):page272_i24@pure_quanta.q_cap(chips)',
 P_PATH='@s9s_mb_2u_lib.s9s_mb_2u(sch_1):page286_i24@pure_quanta.q_cap(chips)',
 PATH='I24',
 DRAWING='@S9S_MB_2U_LIB.S9S_MB_2U(SCH_1):PAGE272',
 PHYS_PAGE='286',
 XY='(-2350,1775)',
 ROT='0',
 VER='1',
 PACK_TYPE='C0402',
 LOCATION='PC524',
 CDS_LIB='pure_quanta',
 CDS_PART_NAME='Q_CAP_C0402-2.2UF,10V,10%,X6S,A',
 TOLERANCE='10%',
 MATERIAL='X6S',
 VOLTAGE='10V',
 VALUE='2.2UF',
 PRIM_FILE='./archive_libs/logical/q_cap/chips/chips.prt';

PART_NAME
 PC525_P1_4 'Q_CAP_C0402-2.2UF,10V,10%,X6S,A':;

SECTION_NUMBER 1
 '@S9S_MB_2U_LIB.S9S_MB_2U(SCH_1):PAGE272_I19@PURE_QUANTA.Q_CAP(CHIPS)':
 C_PATH='@s9s_mb_2u_lib.s9s_mb_2u(sch_1):page272_i19@pure_quanta.q_cap(chips)',
 P_PATH='@s9s_mb_2u_lib.s9s_mb_2u(sch_1):page286_i19@pure_quanta.q_cap(chips)',
 PATH='I19',
 DRAWING='@S9S_MB_2U_LIB.S9S_MB_2U(SCH_1):PAGE272',
 PHYS_PAGE='286',
 XY='(-1950,-550)',
 ROT='0',
 VER='1',
 PACK_TYPE='C0402',
 LOCATION='PC525_P1_4',
 CDS_LIB='pure_quanta',
 CDS_PART_NAME='Q_CAP_C0402-2.2UF,10V,10%,X6S,A',
 TOLERANCE='10%',
 MATERIAL='X6S',
 VOLTAGE='10V',
 VALUE='2.2UF',
 PRIM_FILE='./archive_libs/logical/q_cap/chips/chips.prt';

PART_NAME
 PC526_P1_3 'Q_CAP_C0402-2.2UF,10V,10%,X6S,A':;

SECTION_NUMBER 1
 '@S9S_MB_2U_LIB.S9S_MB_2U(SCH_1):PAGE272_I29@PURE_QUANTA.Q_CAP(CHIPS)':
 C_PATH='@s9s_mb_2u_lib.s9s_mb_2u(sch_1):page272_i29@pure_quanta.q_cap(chips)',
 P_PATH='@s9s_mb_2u_lib.s9s_mb_2u(sch_1):page286_i29@pure_quanta.q_cap(chips)',
 PATH='I29',
 DRAWING='@S9S_MB_2U_LIB.S9S_MB_2U(SCH_1):PAGE272',
 PHYS_PAGE='286',
 XY='(-1925,2275)',
 ROT='0',
 VER='1',
 PACK_TYPE='C0402',
 LOCATION='PC526_P1_3',
 CDS_LIB='pure_quanta',
 CDS_PART_NAME='Q_CAP_C0402-2.2UF,10V,10%,X6S,A',
 TOLERANCE='10%',
 MATERIAL='X6S',
 VOLTAGE='10V',
 VALUE='2.2UF',
 PRIM_FILE='./archive_libs/logical/q_cap/chips/chips.prt';

PART_NAME
 PC527_P1_4 'Q_CAP_0402-3300PF,50V,10%,X7R,A':;

SECTION_NUMBER 1
 '@S9S_MB_2U_LIB.S9S_MB_2U(SCH_1):PAGE272_I33@PURE_QUANTA.Q_CAP(CHIPS)':
 C_PATH='@s9s_mb_2u_lib.s9s_mb_2u(sch_1):page272_i33@pure_quanta.q_cap(chips)',
 P_PATH='@s9s_mb_2u_lib.s9s_mb_2u(sch_1):page286_i33@pure_quanta.q_cap(chips)',
 PATH='I33',
 DRAWING='@S9S_MB_2U_LIB.S9S_MB_2U(SCH_1):PAGE272',
 PHYS_PAGE='286',
 XY='(-50,-650)',
 ROT='0',
 VER='1',
 PACK_TYPE='0402',
 LOCATION='PC527_P1_4',
 CDS_LIB='pure_quanta',
 CDS_PART_NAME='Q_CAP_0402-3300PF,50V,10%,X7R,A',
 TOLERANCE='10%',
 MATERIAL='X7R',
 VOLTAGE='50V',
 VALUE='3300PF',
 PRIM_FILE='./archive_libs/logical/q_cap/chips/chips.prt';

PART_NAME
 PC528_P1_3 'Q_CAP_0402-3300PF,50V,10%,X7R,A':;

SECTION_NUMBER 1
 '@S9S_MB_2U_LIB.S9S_MB_2U(SCH_1):PAGE272_I48@PURE_QUANTA.Q_CAP(CHIPS)':
 C_PATH='@s9s_mb_2u_lib.s9s_mb_2u(sch_1):page272_i48@pure_quanta.q_cap(chips)',
 P_PATH='@s9s_mb_2u_lib.s9s_mb_2u(sch_1):page286_i48@pure_quanta.q_cap(chips)',
 PATH='I48',
 DRAWING='@S9S_MB_2U_LIB.S9S_MB_2U(SCH_1):PAGE272',
 PHYS_PAGE='286',
 XY='(-25,2175)',
 ROT='0',
 VER='1',
 PACK_TYPE='0402',
 LOCATION='PC528_P1_3',
 CDS_LIB='pure_quanta',
 CDS_PART_NAME='Q_CAP_0402-3300PF,50V,10%,X7R,A',
 TOLERANCE='10%',
 MATERIAL='X7R',
 VOLTAGE='50V',
 VALUE='3300PF',
 PRIM_FILE='./archive_libs/logical/q_cap/chips/chips.prt';

PART_NAME
 PC529_P1_4 'Q_CAP_C0402-1UF,16V,10%,X6S,CHA':;

SECTION_NUMBER 1
 '@S9S_MB_2U_LIB.S9S_MB_2U(SCH_1):PAGE272_I35@PURE_QUANTA.Q_CAP(CHIPS)':
 C_PATH='@s9s_mb_2u_lib.s9s_mb_2u(sch_1):page272_i35@pure_quanta.q_cap(chips)',
 P_PATH='@s9s_mb_2u_lib.s9s_mb_2u(sch_1):page286_i35@pure_quanta.q_cap(chips)',
 PATH='I35',
 DRAWING='@S9S_MB_2U_LIB.S9S_MB_2U(SCH_1):PAGE272',
 PHYS_PAGE='286',
 XY='(350,-650)',
 ROT='0',
 VER='1',
 PACK_TYPE='C0402',
 LOCATION='PC529_P1_4',
 CDS_LIB='pure_quanta',
 CDS_PART_NAME='Q_CAP_C0402-1UF,16V,10%,X6S,CHA',
 TOLERANCE='10%',
 MATERIAL='X6S',
 VOLTAGE='16V',
 VALUE='1UF',
 PRIM_FILE='./archive_libs/logical/q_cap/chips/chips.prt';

PART_NAME
 PC530_P1_3 'Q_CAP_C0402-1UF,16V,10%,X6S,CHA':;

SECTION_NUMBER 1
 '@S9S_MB_2U_LIB.S9S_MB_2U(SCH_1):PAGE272_I49@PURE_QUANTA.Q_CAP(CHIPS)':
 C_PATH='@s9s_mb_2u_lib.s9s_mb_2u(sch_1):page272_i49@pure_quanta.q_cap(chips)',
 P_PATH='@s9s_mb_2u_lib.s9s_mb_2u(sch_1):page286_i49@pure_quanta.q_cap(chips)',
 PATH='I49',
 DRAWING='@S9S_MB_2U_LIB.S9S_MB_2U(SCH_1):PAGE272',
 PHYS_PAGE='286',
 XY='(375,2175)',
 ROT='0',
 VER='1',
 PACK_TYPE='C0402',
 LOCATION='PC530_P1_3',
 CDS_LIB='pure_quanta',
 CDS_PART_NAME='Q_CAP_C0402-1UF,16V,10%,X6S,CHA',
 TOLERANCE='10%',
 MATERIAL='X6S',
 VOLTAGE='16V',
 VALUE='1UF',
 PRIM_FILE='./archive_libs/logical/q_cap/chips/chips.prt';

PART_NAME
 PC531 'Q_CAP_C0402-100NF,50V,10%,X7R,A':;

SECTION_NUMBER 1
 '@S9S_MB_2U_LIB.S9S_MB_2U(SCH_1):PAGE272_I39@PURE_QUANTA.Q_CAP(CHIPS)':
 C_PATH='@s9s_mb_2u_lib.s9s_mb_2u(sch_1):page272_i39@pure_quanta.q_cap(chips)',
 P_PATH='@s9s_mb_2u_lib.s9s_mb_2u(sch_1):page286_i39@pure_quanta.q_cap(chips)',
 PATH='I39',
 DRAWING='@S9S_MB_2U_LIB.S9S_MB_2U(SCH_1):PAGE272',
 PHYS_PAGE='286',
 XY='(1125,-1275)',
 ROT='2',
 VER='1',
 PACK_TYPE='C0402',
 LOCATION='PC531',
 CDS_LIB='pure_quanta',
 CDS_PART_NAME='Q_CAP_C0402-100NF,50V,10%,X7R,A',
 TOLERANCE='10%',
 MATERIAL='X7R',
 VOLTAGE='50V',
 VALUE='100NF',
 PRIM_FILE='./archive_libs/logical/q_cap/chips/chips.prt';

PART_NAME
 PC532 'Q_CAP_C0402-100NF,50V,10%,X7R,A':;

SECTION_NUMBER 1
 '@S9S_MB_2U_LIB.S9S_MB_2U(SCH_1):PAGE272_I52@PURE_QUANTA.Q_CAP(CHIPS)':
 C_PATH='@s9s_mb_2u_lib.s9s_mb_2u(sch_1):page272_i52@pure_quanta.q_cap(chips)',
 P_PATH='@s9s_mb_2u_lib.s9s_mb_2u(sch_1):page286_i52@pure_quanta.q_cap(chips)',
 PATH='I52',
 DRAWING='@S9S_MB_2U_LIB.S9S_MB_2U(SCH_1):PAGE272',
 PHYS_PAGE='286',
 XY='(1150,1550)',
 ROT='2',
 VER='1',
 PACK_TYPE='C0402',
 LOCATION='PC532',
 CDS_LIB='pure_quanta',
 CDS_PART_NAME='Q_CAP_C0402-100NF,50V,10%,X7R,A',
 TOLERANCE='10%',
 MATERIAL='X7R',
 VOLTAGE='50V',
 VALUE='100NF',
 PRIM_FILE='./archive_libs/logical/q_cap/chips/chips.prt';

PART_NAME
 PC533_P1_4 'Q_CAP_C0805-22UF,16V,20%,X6S,CA':;

SECTION_NUMBER 1
 '@S9S_MB_2U_LIB.S9S_MB_2U(SCH_1):PAGE272_I36@PURE_QUANTA.Q_CAP(CHIPS)':
 C_PATH='@s9s_mb_2u_lib.s9s_mb_2u(sch_1):page272_i36@pure_quanta.q_cap(chips)',
 P_PATH='@s9s_mb_2u_lib.s9s_mb_2u(sch_1):page286_i36@pure_quanta.q_cap(chips)',
 PATH='I36',
 DRAWING='@S9S_MB_2U_LIB.S9S_MB_2U(SCH_1):PAGE272',
 PHYS_PAGE='286',
 XY='(750,-650)',
 ROT='0',
 VER='1',
 PACK_TYPE='C0805',
 LOCATION='PC533_P1_4',
 CDS_LIB='pure_quanta',
 CDS_PART_NAME='Q_CAP_C0805-22UF,16V,20%,X6S,CA',
 TOLERANCE='20%',
 MATERIAL='X6S',
 VOLTAGE='16V',
 VALUE='22UF',
 PRIM_FILE='./archive_libs/logical/q_cap/chips/chips.prt';

PART_NAME
 PC534_P1_3 'Q_CAP_C0805-22UF,16V,20%,X6S,CA':;

SECTION_NUMBER 1
 '@S9S_MB_2U_LIB.S9S_MB_2U(SCH_1):PAGE272_I50@PURE_QUANTA.Q_CAP(CHIPS)':
 C_PATH='@s9s_mb_2u_lib.s9s_mb_2u(sch_1):page272_i50@pure_quanta.q_cap(chips)',
 P_PATH='@s9s_mb_2u_lib.s9s_mb_2u(sch_1):page286_i50@pure_quanta.q_cap(chips)',
 PATH='I50',
 DRAWING='@S9S_MB_2U_LIB.S9S_MB_2U(SCH_1):PAGE272',
 PHYS_PAGE='286',
 XY='(775,2175)',
 ROT='0',
 VER='1',
 PACK_TYPE='C0805',
 LOCATION='PC534_P1_3',
 CDS_LIB='pure_quanta',
 CDS_PART_NAME='Q_CAP_C0805-22UF,16V,20%,X6S,CA',
 TOLERANCE='20%',
 MATERIAL='X6S',
 VOLTAGE='16V',
 VALUE='22UF',
 PRIM_FILE='./archive_libs/logical/q_cap/chips/chips.prt';

PART_NAME
 PC535_P1_4 'Q_CAP_C0805-22UF,16V,20%,X6S,CA':;

SECTION_NUMBER 1
 '@S9S_MB_2U_LIB.S9S_MB_2U(SCH_1):PAGE272_I41@PURE_QUANTA.Q_CAP(CHIPS)':
 C_PATH='@s9s_mb_2u_lib.s9s_mb_2u(sch_1):page272_i41@pure_quanta.q_cap(chips)',
 P_PATH='@s9s_mb_2u_lib.s9s_mb_2u(sch_1):page286_i41@pure_quanta.q_cap(chips)',
 PATH='I41',
 DRAWING='@S9S_MB_2U_LIB.S9S_MB_2U(SCH_1):PAGE272',
 PHYS_PAGE='286',
 XY='(1150,-650)',
 ROT='0',
 VER='1',
 PACK_TYPE='C0805',
 LOCATION='PC535_P1_4',
 CDS_LIB='pure_quanta',
 CDS_PART_NAME='Q_CAP_C0805-22UF,16V,20%,X6S,CA',
 TOLERANCE='20%',
 MATERIAL='X6S',
 VOLTAGE='16V',
 VALUE='22UF',
 PRIM_FILE='./archive_libs/logical/q_cap/chips/chips.prt';

PART_NAME
 PC536_P1_3 'Q_CAP_C0805-22UF,16V,20%,X6S,CA':;

SECTION_NUMBER 1
 '@S9S_MB_2U_LIB.S9S_MB_2U(SCH_1):PAGE272_I54@PURE_QUANTA.Q_CAP(CHIPS)':
 C_PATH='@s9s_mb_2u_lib.s9s_mb_2u(sch_1):page272_i54@pure_quanta.q_cap(chips)',
 P_PATH='@s9s_mb_2u_lib.s9s_mb_2u(sch_1):page286_i54@pure_quanta.q_cap(chips)',
 PATH='I54',
 DRAWING='@S9S_MB_2U_LIB.S9S_MB_2U(SCH_1):PAGE272',
 PHYS_PAGE='286',
 XY='(1175,2175)',
 ROT='0',
 VER='1',
 PACK_TYPE='C0805',
 LOCATION='PC536_P1_3',
 CDS_LIB='pure_quanta',
 CDS_PART_NAME='Q_CAP_C0805-22UF,16V,20%,X6S,CA',
 TOLERANCE='20%',
 MATERIAL='X6S',
 VOLTAGE='16V',
 VALUE='22UF',
 PRIM_FILE='./archive_libs/logical/q_cap/chips/chips.prt';

PART_NAME
 PC537_P1_4 'Q_CAP_C0805-22UF,16V,20%,X6S,CA':;

SECTION_NUMBER 1
 '@S9S_MB_2U_LIB.S9S_MB_2U(SCH_1):PAGE272_I42@PURE_QUANTA.Q_CAP(CHIPS)':
 C_PATH='@s9s_mb_2u_lib.s9s_mb_2u(sch_1):page272_i42@pure_quanta.q_cap(chips)',
 P_PATH='@s9s_mb_2u_lib.s9s_mb_2u(sch_1):page286_i42@pure_quanta.q_cap(chips)',
 PATH='I42',
 DRAWING='@S9S_MB_2U_LIB.S9S_MB_2U(SCH_1):PAGE272',
 PHYS_PAGE='286',
 XY='(1525,-650)',
 ROT='0',
 VER='1',
 PACK_TYPE='C0805',
 LOCATION='PC537_P1_4',
 CDS_LIB='pure_quanta',
 CDS_PART_NAME='Q_CAP_C0805-22UF,16V,20%,X6S,CA',
 TOLERANCE='20%',
 MATERIAL='X6S',
 VOLTAGE='16V',
 VALUE='22UF',
 PRIM_FILE='./archive_libs/logical/q_cap/chips/chips.prt';

PART_NAME
 PC538_P1_3 'Q_CAP_C0805-22UF,16V,20%,X6S,CA':;

SECTION_NUMBER 1
 '@S9S_MB_2U_LIB.S9S_MB_2U(SCH_1):PAGE272_I55@PURE_QUANTA.Q_CAP(CHIPS)':
 C_PATH='@s9s_mb_2u_lib.s9s_mb_2u(sch_1):page272_i55@pure_quanta.q_cap(chips)',
 P_PATH='@s9s_mb_2u_lib.s9s_mb_2u(sch_1):page286_i55@pure_quanta.q_cap(chips)',
 PATH='I55',
 DRAWING='@S9S_MB_2U_LIB.S9S_MB_2U(SCH_1):PAGE272',
 PHYS_PAGE='286',
 XY='(1550,2175)',
 ROT='0',
 VER='1',
 PACK_TYPE='C0805',
 LOCATION='PC538_P1_3',
 CDS_LIB='pure_quanta',
 CDS_PART_NAME='Q_CAP_C0805-22UF,16V,20%,X6S,CA',
 TOLERANCE='20%',
 MATERIAL='X6S',
 VOLTAGE='16V',
 VALUE='22UF',
 PRIM_FILE='./archive_libs/logical/q_cap/chips/chips.prt';

PART_NAME
 PC541_P1_4 'Q_CAP_C0805-22UF,4V,20%,X6S,CHA':;

SECTION_NUMBER 1
 '@S9S_MB_2U_LIB.S9S_MB_2U(SCH_1):PAGE272_I58@PURE_QUANTA.Q_CAP(CHIPS)':
 C_PATH='@s9s_mb_2u_lib.s9s_mb_2u(sch_1):page272_i58@pure_quanta.q_cap(chips)',
 P_PATH='@s9s_mb_2u_lib.s9s_mb_2u(sch_1):page286_i58@pure_quanta.q_cap(chips)',
 PATH='I58',
 DRAWING='@S9S_MB_2U_LIB.S9S_MB_2U(SCH_1):PAGE272',
 PHYS_PAGE='286',
 XY='(3325,-1750)',
 ROT='0',
 VER='1',
 PACK_TYPE='C0805',
 LOCATION='PC541_P1_4',
 CDS_LIB='pure_quanta',
 CDS_PART_NAME='Q_CAP_C0805-22UF,4V,20%,X6S,CHA',
 TOLERANCE='20%',
 MATERIAL='X6S',
 VOLTAGE='4V',
 VALUE='22UF',
 PRIM_FILE='./archive_libs/logical/q_cap/chips/chips.prt';

PART_NAME
 PC542_P1_3 'Q_CAP_C0805-22UF,4V,20%,X6S,CHA':;

SECTION_NUMBER 1
 '@S9S_MB_2U_LIB.S9S_MB_2U(SCH_1):PAGE272_I63@PURE_QUANTA.Q_CAP(CHIPS)':
 C_PATH='@s9s_mb_2u_lib.s9s_mb_2u(sch_1):page272_i63@pure_quanta.q_cap(chips)',
 P_PATH='@s9s_mb_2u_lib.s9s_mb_2u(sch_1):page286_i63@pure_quanta.q_cap(chips)',
 PATH='I63',
 DRAWING='@S9S_MB_2U_LIB.S9S_MB_2U(SCH_1):PAGE272',
 PHYS_PAGE='286',
 XY='(3475,1075)',
 ROT='0',
 VER='1',
 PACK_TYPE='C0805',
 LOCATION='PC542_P1_3',
 CDS_LIB='pure_quanta',
 CDS_PART_NAME='Q_CAP_C0805-22UF,4V,20%,X6S,CHA',
 TOLERANCE='20%',
 MATERIAL='X6S',
 VOLTAGE='4V',
 VALUE='22UF',
 PRIM_FILE='./archive_libs/logical/q_cap/chips/chips.prt';

PART_NAME
 PC543_P1_4 'Q_CAP_C0805-22UF,4V,20%,X6S,CHA':;

SECTION_NUMBER 1
 '@S9S_MB_2U_LIB.S9S_MB_2U(SCH_1):PAGE272_I59@PURE_QUANTA.Q_CAP(CHIPS)':
 C_PATH='@s9s_mb_2u_lib.s9s_mb_2u(sch_1):page272_i59@pure_quanta.q_cap(chips)',
 P_PATH='@s9s_mb_2u_lib.s9s_mb_2u(sch_1):page286_i59@pure_quanta.q_cap(chips)',
 PATH='I59',
 DRAWING='@S9S_MB_2U_LIB.S9S_MB_2U(SCH_1):PAGE272',
 PHYS_PAGE='286',
 XY='(3750,-1750)',
 ROT='0',
 VER='1',
 PACK_TYPE='C0805',
 LOCATION='PC543_P1_4',
 CDS_LIB='pure_quanta',
 CDS_PART_NAME='Q_CAP_C0805-22UF,4V,20%,X6S,CHA',
 TOLERANCE='20%',
 MATERIAL='X6S',
 VOLTAGE='4V',
 VALUE='22UF',
 PRIM_FILE='./archive_libs/logical/q_cap/chips/chips.prt';

PART_NAME
 PC544_P1_3 'Q_CAP_C0805-22UF,4V,20%,X6S,CHA':;

SECTION_NUMBER 1
 '@S9S_MB_2U_LIB.S9S_MB_2U(SCH_1):PAGE272_I64@PURE_QUANTA.Q_CAP(CHIPS)':
 C_PATH='@s9s_mb_2u_lib.s9s_mb_2u(sch_1):page272_i64@pure_quanta.q_cap(chips)',
 P_PATH='@s9s_mb_2u_lib.s9s_mb_2u(sch_1):page286_i64@pure_quanta.q_cap(chips)',
 PATH='I64',
 DRAWING='@S9S_MB_2U_LIB.S9S_MB_2U(SCH_1):PAGE272',
 PHYS_PAGE='286',
 XY='(3900,1075)',
 ROT='0',
 VER='1',
 PACK_TYPE='C0805',
 LOCATION='PC544_P1_3',
 CDS_LIB='pure_quanta',
 CDS_PART_NAME='Q_CAP_C0805-22UF,4V,20%,X6S,CHA',
 TOLERANCE='20%',
 MATERIAL='X6S',
 VOLTAGE='4V',
 VALUE='22UF',
 PRIM_FILE='./archive_libs/logical/q_cap/chips/chips.prt';

PART_NAME
 PC547 'Q_CAP_0402-0.1UF,25V,10%,EMPTYA':;

SECTION_NUMBER 1
 '@S9S_MB_2U_LIB.S9S_MB_2U(SCH_1):PAGE270_I28@PURE_QUANTA.Q_CAP(CHIPS)':
 C_PATH='@s9s_mb_2u_lib.s9s_mb_2u(sch_1):page270_i28@pure_quanta.q_cap(chips)',
 P_PATH='@s9s_mb_2u_lib.s9s_mb_2u(sch_1):page284_i28@pure_quanta.q_cap(chips)',
 PATH='I28',
 DRAWING='@S9S_MB_2U_LIB.S9S_MB_2U(SCH_1):PAGE270',
 PHYS_PAGE='284',
 XY='(-1475,-2625)',
 ROT='0',
 VER='1',
 PACK_TYPE='0402',
 LOCATION='PC547',
 CDS_LIB='pure_quanta',
 CDS_PART_NAME='Q_CAP_0402-0.1UF,25V,10%,EMPTYA',
 TOLERANCE='10%',
 MATERIAL='EMPTY',
 VOLTAGE='25V',
 VALUE='0.1UF',
 PRIM_FILE='./archive_libs/logical/q_cap/chips/chips.prt';

PART_NAME
 PC548 'Q_CAP_0402-0.1UF,25V,10%,X7R,CA':;

SECTION_NUMBER 1
 '@S9S_MB_2U_LIB.S9S_MB_2U(SCH_1):PAGE270_I31@PURE_QUANTA.Q_CAP(CHIPS)':
 C_PATH='@s9s_mb_2u_lib.s9s_mb_2u(sch_1):page270_i31@pure_quanta.q_cap(chips)',
 P_PATH='@s9s_mb_2u_lib.s9s_mb_2u(sch_1):page284_i31@pure_quanta.q_cap(chips)',
 PATH='I31',
 DRAWING='@S9S_MB_2U_LIB.S9S_MB_2U(SCH_1):PAGE270',
 PHYS_PAGE='284',
 XY='(-725,-2625)',
 ROT='0',
 VER='1',
 PACK_TYPE='0402',
 LOCATION='PC548',
 CDS_LIB='pure_quanta',
 CDS_PART_NAME='Q_CAP_0402-0.1UF,25V,10%,X7R,CA',
 TOLERANCE='10%',
 MATERIAL='X7R',
 VOLTAGE='25V',
 VALUE='0.1UF',
 PRIM_FILE='./archive_libs/logical/q_cap/chips/chips.prt';

PART_NAME
 PC549 'Q_CAP_0402-3300PF,50V,10%,X7R,A':;

SECTION_NUMBER 1
 '@S9S_MB_2U_LIB.S9S_MB_2U(SCH_1):PAGE270_I64@PURE_QUANTA.Q_CAP(CHIPS)':
 C_PATH='@s9s_mb_2u_lib.s9s_mb_2u(sch_1):page270_i64@pure_quanta.q_cap(chips)',
 P_PATH='@s9s_mb_2u_lib.s9s_mb_2u(sch_1):page284_i64@pure_quanta.q_cap(chips)',
 PATH='I64',
 DRAWING='@S9S_MB_2U_LIB.S9S_MB_2U(SCH_1):PAGE270',
 PHYS_PAGE='284',
 XY='(-1375,850)',
 ROT='0',
 VER='1',
 PACK_TYPE='0402',
 LOCATION='PC549',
 CDS_LIB='pure_quanta',
 CDS_PART_NAME='Q_CAP_0402-3300PF,50V,10%,X7R,A',
 TOLERANCE='10%',
 MATERIAL='X7R',
 VOLTAGE='50V',
 VALUE='3300PF',
 PRIM_FILE='./archive_libs/logical/q_cap/chips/chips.prt';

PART_NAME
 PC552 'Q_CAP_C0402-100NF,50V,10%,EMPTA':;

SECTION_NUMBER 1
 '@S9S_MB_2U_LIB.S9S_MB_2U(SCH_1):PAGE270_I120@PURE_QUANTA.Q_CAP(CHIPS)':
 C_PATH='@s9s_mb_2u_lib.s9s_mb_2u(sch_1):page270_i120@pure_quanta.q_cap(chips)',
 P_PATH='@s9s_mb_2u_lib.s9s_mb_2u(sch_1):page284_i120@pure_quanta.q_cap(chips)',
 PATH='I120',
 DRAWING='@S9S_MB_2U_LIB.S9S_MB_2U(SCH_1):PAGE270',
 PHYS_PAGE='284',
 XY='(1450,2825)',
 ROT='0',
 VER='1',
 PACK_TYPE='C0402',
 LOCATION='PC552',
 CDS_LIB='pure_quanta',
 CDS_PART_NAME='Q_CAP_C0402-100NF,50V,10%,EMPTA',
 TOLERANCE='10%',
 MATERIAL='EMPTY',
 VOLTAGE='50V',
 VALUE='100NF',
 PRIM_FILE='./archive_libs/logical/q_cap/chips/chips.prt';

PART_NAME
 PC553 'Q_CAP_C0402-10UF,6.3V,20%,X6S,B':;

SECTION_NUMBER 1
 '@S9S_MB_2U_LIB.S9S_MB_2U(SCH_1):PAGE270_I119@PURE_QUANTA.Q_CAP(CHIPS)':
 C_PATH='@s9s_mb_2u_lib.s9s_mb_2u(sch_1):page270_i119@pure_quanta.q_cap(chips)',
 P_PATH='@s9s_mb_2u_lib.s9s_mb_2u(sch_1):page284_i119@pure_quanta.q_cap(chips)',
 PATH='I119',
 DRAWING='@S9S_MB_2U_LIB.S9S_MB_2U(SCH_1):PAGE270',
 PHYS_PAGE='284',
 XY='(1450,2350)',
 ROT='0',
 VER='1',
 PACK_TYPE='C0402',
 LOCATION='PC553',
 CDS_LIB='pure_quanta',
 CDS_PART_NAME='Q_CAP_C0402-10UF,6.3V,20%,X6S,B',
 TOLERANCE='20%',
 MATERIAL='X6S',
 VOLTAGE='6.3V',
 VALUE='10UF',
 PRIM_FILE='./archive_libs/logical/q_cap/chips/chips.prt';

PART_NAME
 PC554 'Q_CAP_0402-470PF,50V,10%,X7R,TA':;

SECTION_NUMBER 1
 '@S9S_MB_2U_LIB.S9S_MB_2U(SCH_1):PAGE270_I72@PURE_QUANTA.Q_CAP(CHIPS)':
 C_PATH='@s9s_mb_2u_lib.s9s_mb_2u(sch_1):page270_i72@pure_quanta.q_cap(chips)',
 P_PATH='@s9s_mb_2u_lib.s9s_mb_2u(sch_1):page284_i72@pure_quanta.q_cap(chips)',
 PATH='I72',
 DRAWING='@S9S_MB_2U_LIB.S9S_MB_2U(SCH_1):PAGE270',
 PHYS_PAGE='284',
 XY='(1200,-2375)',
 ROT='0',
 VER='1',
 PACK_TYPE='0402',
 LOCATION='PC554',
 CDS_LIB='pure_quanta',
 CDS_PART_NAME='Q_CAP_0402-470PF,50V,10%,X7R,TA',
 TOLERANCE='10%',
 MATERIAL='X7R',
 VOLTAGE='50V',
 VALUE='470PF',
 PRIM_FILE='./archive_libs/logical/q_cap/chips/chips.prt';

PART_NAME
 PC555 'Q_CAP_C0402-1UF,16V,10%,X6S,CHA':;

SECTION_NUMBER 1
 '@S9S_MB_2U_LIB.S9S_MB_2U(SCH_1):PAGE270_I122@PURE_QUANTA.Q_CAP(CHIPS)':
 C_PATH='@s9s_mb_2u_lib.s9s_mb_2u(sch_1):page270_i122@pure_quanta.q_cap(chips)',
 P_PATH='@s9s_mb_2u_lib.s9s_mb_2u(sch_1):page284_i122@pure_quanta.q_cap(chips)',
 PATH='I122',
 DRAWING='@S9S_MB_2U_LIB.S9S_MB_2U(SCH_1):PAGE270',
 PHYS_PAGE='284',
 XY='(1850,2825)',
 ROT='0',
 VER='1',
 PACK_TYPE='C0402',
 LOCATION='PC555',
 CDS_LIB='pure_quanta',
 CDS_PART_NAME='Q_CAP_C0402-1UF,16V,10%,X6S,CHA',
 TOLERANCE='10%',
 MATERIAL='X6S',
 VOLTAGE='16V',
 VALUE='1UF',
 PRIM_FILE='./archive_libs/logical/q_cap/chips/chips.prt';

PART_NAME
 PC556 'Q_CAP_C0402-2.2UF,10V,10%,X6S,A':;

SECTION_NUMBER 1
 '@S9S_MB_2U_LIB.S9S_MB_2U(SCH_1):PAGE271_I11@PURE_QUANTA.Q_CAP(CHIPS)':
 C_PATH='@s9s_mb_2u_lib.s9s_mb_2u(sch_1):page271_i11@pure_quanta.q_cap(chips)',
 P_PATH='@s9s_mb_2u_lib.s9s_mb_2u(sch_1):page285_i11@pure_quanta.q_cap(chips)',
 PATH='I11',
 DRAWING='@S9S_MB_2U_LIB.S9S_MB_2U(SCH_1):PAGE271',
 PHYS_PAGE='285',
 XY='(-3650,-1200)',
 ROT='0',
 VER='1',
 PACK_TYPE='C0402',
 LOCATION='PC556',
 CDS_LIB='pure_quanta',
 CDS_PART_NAME='Q_CAP_C0402-2.2UF,10V,10%,X6S,A',
 TOLERANCE='10%',
 MATERIAL='X6S',
 VOLTAGE='10V',
 VALUE='2.2UF',
 PRIM_FILE='./archive_libs/logical/q_cap/chips/chips.prt';

PART_NAME
 PC557 'Q_CAP_C0402-2.2UF,10V,10%,X6S,A':;

SECTION_NUMBER 1
 '@S9S_MB_2U_LIB.S9S_MB_2U(SCH_1):PAGE271_I36@PURE_QUANTA.Q_CAP(CHIPS)':
 C_PATH='@s9s_mb_2u_lib.s9s_mb_2u(sch_1):page271_i36@pure_quanta.q_cap(chips)',
 P_PATH='@s9s_mb_2u_lib.s9s_mb_2u(sch_1):page285_i36@pure_quanta.q_cap(chips)',
 PATH='I36',
 DRAWING='@S9S_MB_2U_LIB.S9S_MB_2U(SCH_1):PAGE271',
 PHYS_PAGE='285',
 XY='(-3625,1625)',
 ROT='0',
 VER='1',
 PACK_TYPE='C0402',
 LOCATION='PC557',
 CDS_LIB='pure_quanta',
 CDS_PART_NAME='Q_CAP_C0402-2.2UF,10V,10%,X6S,A',
 TOLERANCE='10%',
 MATERIAL='X6S',
 VOLTAGE='10V',
 VALUE='2.2UF',
 PRIM_FILE='./archive_libs/logical/q_cap/chips/chips.prt';

PART_NAME
 PC558_P1_2 'Q_CAP_C0402-2.2UF,10V,10%,X6S,A':;

SECTION_NUMBER 1
 '@S9S_MB_2U_LIB.S9S_MB_2U(SCH_1):PAGE271_I15@PURE_QUANTA.Q_CAP(CHIPS)':
 C_PATH='@s9s_mb_2u_lib.s9s_mb_2u(sch_1):page271_i15@pure_quanta.q_cap(chips)',
 P_PATH='@s9s_mb_2u_lib.s9s_mb_2u(sch_1):page285_i15@pure_quanta.q_cap(chips)',
 PATH='I15',
 DRAWING='@S9S_MB_2U_LIB.S9S_MB_2U(SCH_1):PAGE271',
 PHYS_PAGE='285',
 XY='(-3225,-700)',
 ROT='0',
 VER='1',
 PACK_TYPE='C0402',
 LOCATION='PC558_P1_2',
 CDS_LIB='pure_quanta',
 CDS_PART_NAME='Q_CAP_C0402-2.2UF,10V,10%,X6S,A',
 TOLERANCE='10%',
 MATERIAL='X6S',
 VOLTAGE='10V',
 VALUE='2.2UF',
 PRIM_FILE='./archive_libs/logical/q_cap/chips/chips.prt';

PART_NAME
 PC559_P1_1 'Q_CAP_C0402-2.2UF,10V,10%,X6S,A':;

SECTION_NUMBER 1
 '@S9S_MB_2U_LIB.S9S_MB_2U(SCH_1):PAGE271_I39@PURE_QUANTA.Q_CAP(CHIPS)':
 C_PATH='@s9s_mb_2u_lib.s9s_mb_2u(sch_1):page271_i39@pure_quanta.q_cap(chips)',
 P_PATH='@s9s_mb_2u_lib.s9s_mb_2u(sch_1):page285_i39@pure_quanta.q_cap(chips)',
 PATH='I39',
 DRAWING='@S9S_MB_2U_LIB.S9S_MB_2U(SCH_1):PAGE271',
 PHYS_PAGE='285',
 XY='(-3200,2125)',
 ROT='0',
 VER='1',
 PACK_TYPE='C0402',
 LOCATION='PC559_P1_1',
 CDS_LIB='pure_quanta',
 CDS_PART_NAME='Q_CAP_C0402-2.2UF,10V,10%,X6S,A',
 TOLERANCE='10%',
 MATERIAL='X6S',
 VOLTAGE='10V',
 VALUE='2.2UF',
 PRIM_FILE='./archive_libs/logical/q_cap/chips/chips.prt';

PART_NAME
 PC560_P1_2 'Q_CAP_0402-3300PF,50V,10%,X7R,A':;

SECTION_NUMBER 1
 '@S9S_MB_2U_LIB.S9S_MB_2U(SCH_1):PAGE271_I19@PURE_QUANTA.Q_CAP(CHIPS)':
 C_PATH='@s9s_mb_2u_lib.s9s_mb_2u(sch_1):page271_i19@pure_quanta.q_cap(chips)',
 P_PATH='@s9s_mb_2u_lib.s9s_mb_2u(sch_1):page285_i19@pure_quanta.q_cap(chips)',
 PATH='I19',
 DRAWING='@S9S_MB_2U_LIB.S9S_MB_2U(SCH_1):PAGE271',
 PHYS_PAGE='285',
 XY='(-1325,-800)',
 ROT='0',
 VER='1',
 PACK_TYPE='0402',
 LOCATION='PC560_P1_2',
 CDS_LIB='pure_quanta',
 CDS_PART_NAME='Q_CAP_0402-3300PF,50V,10%,X7R,A',
 TOLERANCE='10%',
 MATERIAL='X7R',
 VOLTAGE='50V',
 VALUE='3300PF',
 PRIM_FILE='./archive_libs/logical/q_cap/chips/chips.prt';

PART_NAME
 PC561_P1_1 'Q_CAP_0402-3300PF,50V,10%,X7R,A':;

SECTION_NUMBER 1
 '@S9S_MB_2U_LIB.S9S_MB_2U(SCH_1):PAGE271_I44@PURE_QUANTA.Q_CAP(CHIPS)':
 C_PATH='@s9s_mb_2u_lib.s9s_mb_2u(sch_1):page271_i44@pure_quanta.q_cap(chips)',
 P_PATH='@s9s_mb_2u_lib.s9s_mb_2u(sch_1):page285_i44@pure_quanta.q_cap(chips)',
 PATH='I44',
 DRAWING='@S9S_MB_2U_LIB.S9S_MB_2U(SCH_1):PAGE271',
 PHYS_PAGE='285',
 XY='(-1300,2025)',
 ROT='0',
 VER='1',
 PACK_TYPE='0402',
 LOCATION='PC561_P1_1',
 CDS_LIB='pure_quanta',
 CDS_PART_NAME='Q_CAP_0402-3300PF,50V,10%,X7R,A',
 TOLERANCE='10%',
 MATERIAL='X7R',
 VOLTAGE='50V',
 VALUE='3300PF',
 PRIM_FILE='./archive_libs/logical/q_cap/chips/chips.prt';

PART_NAME
 PC562_P1_2 'Q_CAP_C0402-1UF,16V,10%,X6S,CHA':;

SECTION_NUMBER 1
 '@S9S_MB_2U_LIB.S9S_MB_2U(SCH_1):PAGE271_I21@PURE_QUANTA.Q_CAP(CHIPS)':
 C_PATH='@s9s_mb_2u_lib.s9s_mb_2u(sch_1):page271_i21@pure_quanta.q_cap(chips)',
 P_PATH='@s9s_mb_2u_lib.s9s_mb_2u(sch_1):page285_i21@pure_quanta.q_cap(chips)',
 PATH='I21',
 DRAWING='@S9S_MB_2U_LIB.S9S_MB_2U(SCH_1):PAGE271',
 PHYS_PAGE='285',
 XY='(-925,-800)',
 ROT='0',
 VER='1',
 PACK_TYPE='C0402',
 LOCATION='PC562_P1_2',
 CDS_LIB='pure_quanta',
 CDS_PART_NAME='Q_CAP_C0402-1UF,16V,10%,X6S,CHA',
 TOLERANCE='10%',
 MATERIAL='X6S',
 VOLTAGE='16V',
 VALUE='1UF',
 PRIM_FILE='./archive_libs/logical/q_cap/chips/chips.prt';

PART_NAME
 PC563_P1_1 'Q_CAP_C0402-1UF,16V,10%,X6S,CHA':;

SECTION_NUMBER 1
 '@S9S_MB_2U_LIB.S9S_MB_2U(SCH_1):PAGE271_I47@PURE_QUANTA.Q_CAP(CHIPS)':
 C_PATH='@s9s_mb_2u_lib.s9s_mb_2u(sch_1):page271_i47@pure_quanta.q_cap(chips)',
 P_PATH='@s9s_mb_2u_lib.s9s_mb_2u(sch_1):page285_i47@pure_quanta.q_cap(chips)',
 PATH='I47',
 DRAWING='@S9S_MB_2U_LIB.S9S_MB_2U(SCH_1):PAGE271',
 PHYS_PAGE='285',
 XY='(-900,2025)',
 ROT='0',
 VER='1',
 PACK_TYPE='C0402',
 LOCATION='PC563_P1_1',
 CDS_LIB='pure_quanta',
 CDS_PART_NAME='Q_CAP_C0402-1UF,16V,10%,X6S,CHA',
 TOLERANCE='10%',
 MATERIAL='X6S',
 VOLTAGE='16V',
 VALUE='1UF',
 PRIM_FILE='./archive_libs/logical/q_cap/chips/chips.prt';

PART_NAME
 PC564 'Q_CAP_C0402-100NF,50V,10%,X7R,A':;

SECTION_NUMBER 1
 '@S9S_MB_2U_LIB.S9S_MB_2U(SCH_1):PAGE271_I23@PURE_QUANTA.Q_CAP(CHIPS)':
 C_PATH='@s9s_mb_2u_lib.s9s_mb_2u(sch_1):page271_i23@pure_quanta.q_cap(chips)',
 P_PATH='@s9s_mb_2u_lib.s9s_mb_2u(sch_1):page285_i23@pure_quanta.q_cap(chips)',
 PATH='I23',
 DRAWING='@S9S_MB_2U_LIB.S9S_MB_2U(SCH_1):PAGE271',
 PHYS_PAGE='285',
 XY='(-150,-1425)',
 ROT='2',
 VER='1',
 PACK_TYPE='C0402',
 LOCATION='PC564',
 CDS_LIB='pure_quanta',
 CDS_PART_NAME='Q_CAP_C0402-100NF,50V,10%,X7R,A',
 TOLERANCE='10%',
 MATERIAL='X7R',
 VOLTAGE='50V',
 VALUE='100NF',
 PRIM_FILE='./archive_libs/logical/q_cap/chips/chips.prt';

PART_NAME
 PC565 'Q_CAP_C0402-100NF,50V,10%,X7R,A':;

SECTION_NUMBER 1
 '@S9S_MB_2U_LIB.S9S_MB_2U(SCH_1):PAGE271_I49@PURE_QUANTA.Q_CAP(CHIPS)':
 C_PATH='@s9s_mb_2u_lib.s9s_mb_2u(sch_1):page271_i49@pure_quanta.q_cap(chips)',
 P_PATH='@s9s_mb_2u_lib.s9s_mb_2u(sch_1):page285_i49@pure_quanta.q_cap(chips)',
 PATH='I49',
 DRAWING='@S9S_MB_2U_LIB.S9S_MB_2U(SCH_1):PAGE271',
 PHYS_PAGE='285',
 XY='(-125,1400)',
 ROT='2',
 VER='1',
 PACK_TYPE='C0402',
 LOCATION='PC565',
 CDS_LIB='pure_quanta',
 CDS_PART_NAME='Q_CAP_C0402-100NF,50V,10%,X7R,A',
 TOLERANCE='10%',
 MATERIAL='X7R',
 VOLTAGE='50V',
 VALUE='100NF',
 PRIM_FILE='./archive_libs/logical/q_cap/chips/chips.prt';

PART_NAME
 PC566 'Q_CAPP_THLF-270UF,16V,20%,OSCOA':;

SECTION_NUMBER 1
 '@S9S_MB_2U_LIB.S9S_MB_2U(SCH_1):PAGE245_I104@PURE_QUANTA.Q_CAPP(CHIPS)':
 C_PATH='@s9s_mb_2u_lib.s9s_mb_2u(sch_1):page245_i104@pure_quanta.q_capp(chips)',
 P_PATH='@s9s_mb_2u_lib.s9s_mb_2u(sch_1):page259_i104@pure_quanta.q_capp(chips)',
 PATH='I104',
 DRAWING='@S9S_MB_2U_LIB.S9S_MB_2U(SCH_1):PAGE245',
 PHYS_PAGE='259',
 XY='(-3675,850)',
 ROT='0',
 VER='1',
 PACK_TYPE='THLF',
 LOCATION='PC566',
 CDS_LIB='pure_quanta',
 CDS_PART_NAME='Q_CAPP_THLF-270UF,16V,20%,OSCOA',
 TOLERANCE='20%',
 MATERIAL='OSCON',
 VOLTAGE='16V',
 VALUE='270UF',
 PRIM_FILE='./archive_libs/logical/q_capp/chips/chips.prt';

PART_NAME
 PC566_P1_2 'Q_CAP_C0805-22UF,16V,20%,X6S,CA':;

SECTION_NUMBER 1
 '@S9S_MB_2U_LIB.S9S_MB_2U(SCH_1):PAGE271_I22@PURE_QUANTA.Q_CAP(CHIPS)':
 C_PATH='@s9s_mb_2u_lib.s9s_mb_2u(sch_1):page271_i22@pure_quanta.q_cap(chips)',
 P_PATH='@s9s_mb_2u_lib.s9s_mb_2u(sch_1):page285_i22@pure_quanta.q_cap(chips)',
 PATH='I22',
 DRAWING='@S9S_MB_2U_LIB.S9S_MB_2U(SCH_1):PAGE271',
 PHYS_PAGE='285',
 XY='(-525,-800)',
 ROT='0',
 VER='1',
 PACK_TYPE='C0805',
 LOCATION='PC566_P1_2',
 CDS_LIB='pure_quanta',
 CDS_PART_NAME='Q_CAP_C0805-22UF,16V,20%,X6S,CA',
 TOLERANCE='20%',
 MATERIAL='X6S',
 VOLTAGE='16V',
 VALUE='22UF',
 PRIM_FILE='./archive_libs/logical/q_cap/chips/chips.prt';

PART_NAME
 PC567 'Q_CAP_C0805-22UF,16V,20%,X6S,CA':;

SECTION_NUMBER 1
 '@S9S_MB_2U_LIB.S9S_MB_2U(SCH_1):PAGE245_I106@PURE_QUANTA.Q_CAP(CHIPS)':
 C_PATH='@s9s_mb_2u_lib.s9s_mb_2u(sch_1):page245_i106@pure_quanta.q_cap(chips)',
 P_PATH='@s9s_mb_2u_lib.s9s_mb_2u(sch_1):page259_i106@pure_quanta.q_cap(chips)',
 PATH='I106',
 DRAWING='@S9S_MB_2U_LIB.S9S_MB_2U(SCH_1):PAGE245',
 PHYS_PAGE='259',
 XY='(-3350,850)',
 ROT='0',
 VER='1',
 PACK_TYPE='C0805',
 LOCATION='PC567',
 CDS_LIB='pure_quanta',
 CDS_PART_NAME='Q_CAP_C0805-22UF,16V,20%,X6S,CA',
 TOLERANCE='20%',
 MATERIAL='X6S',
 VOLTAGE='16V',
 VALUE='22UF',
 PRIM_FILE='./archive_libs/logical/q_cap/chips/chips.prt';

PART_NAME
 PC567_P1_1 'Q_CAP_C0805-22UF,16V,20%,X6S,CA':;

SECTION_NUMBER 1
 '@S9S_MB_2U_LIB.S9S_MB_2U(SCH_1):PAGE271_I48@PURE_QUANTA.Q_CAP(CHIPS)':
 C_PATH='@s9s_mb_2u_lib.s9s_mb_2u(sch_1):page271_i48@pure_quanta.q_cap(chips)',
 P_PATH='@s9s_mb_2u_lib.s9s_mb_2u(sch_1):page285_i48@pure_quanta.q_cap(chips)',
 PATH='I48',
 DRAWING='@S9S_MB_2U_LIB.S9S_MB_2U(SCH_1):PAGE271',
 PHYS_PAGE='285',
 XY='(-500,2025)',
 ROT='0',
 VER='1',
 PACK_TYPE='C0805',
 LOCATION='PC567_P1_1',
 CDS_LIB='pure_quanta',
 CDS_PART_NAME='Q_CAP_C0805-22UF,16V,20%,X6S,CA',
 TOLERANCE='20%',
 MATERIAL='X6S',
 VOLTAGE='16V',
 VALUE='22UF',
 PRIM_FILE='./archive_libs/logical/q_cap/chips/chips.prt';

PART_NAME
 PC568 'Q_CAP_C0402-0.22UF,25V,10%,X7RA':;

SECTION_NUMBER 1
 '@S9S_MB_2U_LIB.S9S_MB_2U(SCH_1):PAGE245_I122@PURE_QUANTA.Q_CAP(CHIPS)':
 C_PATH='@s9s_mb_2u_lib.s9s_mb_2u(sch_1):page245_i122@pure_quanta.q_cap(chips)',
 P_PATH='@s9s_mb_2u_lib.s9s_mb_2u(sch_1):page259_i122@pure_quanta.q_cap(chips)',
 PATH='I122',
 DRAWING='@S9S_MB_2U_LIB.S9S_MB_2U(SCH_1):PAGE245',
 PHYS_PAGE='259',
 XY='(725,-550)',
 ROT='0',
 VER='2',
 PACK_TYPE='C0402',
 LOCATION='PC568',
 CDS_LIB='pure_quanta',
 CDS_PART_NAME='Q_CAP_C0402-0.22UF,25V,10%,X7RA',
 TOLERANCE='10%',
 MATERIAL='X7R',
 VOLTAGE='25V',
 VALUE='0.22UF',
 PRIM_FILE='./archive_libs/logical/q_cap/chips/chips.prt';

PART_NAME
 PC568_P1_2 'Q_CAP_C0805-22UF,16V,20%,X6S,CA':;

SECTION_NUMBER 1
 '@S9S_MB_2U_LIB.S9S_MB_2U(SCH_1):PAGE271_I24@PURE_QUANTA.Q_CAP(CHIPS)':
 C_PATH='@s9s_mb_2u_lib.s9s_mb_2u(sch_1):page271_i24@pure_quanta.q_cap(chips)',
 P_PATH='@s9s_mb_2u_lib.s9s_mb_2u(sch_1):page285_i24@pure_quanta.q_cap(chips)',
 PATH='I24',
 DRAWING='@S9S_MB_2U_LIB.S9S_MB_2U(SCH_1):PAGE271',
 PHYS_PAGE='285',
 XY='(-125,-800)',
 ROT='0',
 VER='1',
 PACK_TYPE='C0805',
 LOCATION='PC568_P1_2',
 CDS_LIB='pure_quanta',
 CDS_PART_NAME='Q_CAP_C0805-22UF,16V,20%,X6S,CA',
 TOLERANCE='20%',
 MATERIAL='X6S',
 VOLTAGE='16V',
 VALUE='22UF',
 PRIM_FILE='./archive_libs/logical/q_cap/chips/chips.prt';

PART_NAME
 PC569 'Q_CAP_0402-220PF,50V,10%,X7R,TA':;

SECTION_NUMBER 1
 '@S9S_MB_2U_LIB.S9S_MB_2U(SCH_1):PAGE245_I127@PURE_QUANTA.Q_CAP(CHIPS)':
 C_PATH='@s9s_mb_2u_lib.s9s_mb_2u(sch_1):page245_i127@pure_quanta.q_cap(chips)',
 P_PATH='@s9s_mb_2u_lib.s9s_mb_2u(sch_1):page259_i127@pure_quanta.q_cap(chips)',
 PATH='I127',
 DRAWING='@S9S_MB_2U_LIB.S9S_MB_2U(SCH_1):PAGE245',
 PHYS_PAGE='259',
 XY='(2100,-1850)',
 ROT='0',
 VER='2',
 PACK_TYPE='0402',
 LOCATION='PC569',
 CDS_LIB='pure_quanta',
 CDS_PART_NAME='Q_CAP_0402-220PF,50V,10%,X7R,TA',
 TOLERANCE='10%',
 MATERIAL='X7R',
 VOLTAGE='50V',
 VALUE='220PF',
 PRIM_FILE='./archive_libs/logical/q_cap/chips/chips.prt';

PART_NAME
 PC569_P1_1 'Q_CAP_C0805-22UF,16V,20%,X6S,CA':;

SECTION_NUMBER 1
 '@S9S_MB_2U_LIB.S9S_MB_2U(SCH_1):PAGE271_I50@PURE_QUANTA.Q_CAP(CHIPS)':
 C_PATH='@s9s_mb_2u_lib.s9s_mb_2u(sch_1):page271_i50@pure_quanta.q_cap(chips)',
 P_PATH='@s9s_mb_2u_lib.s9s_mb_2u(sch_1):page285_i50@pure_quanta.q_cap(chips)',
 PATH='I50',
 DRAWING='@S9S_MB_2U_LIB.S9S_MB_2U(SCH_1):PAGE271',
 PHYS_PAGE='285',
 XY='(-100,2025)',
 ROT='0',
 VER='1',
 PACK_TYPE='C0805',
 LOCATION='PC569_P1_1',
 CDS_LIB='pure_quanta',
 CDS_PART_NAME='Q_CAP_C0805-22UF,16V,20%,X6S,CA',
 TOLERANCE='20%',
 MATERIAL='X6S',
 VOLTAGE='16V',
 VALUE='22UF',
 PRIM_FILE='./archive_libs/logical/q_cap/chips/chips.prt';

PART_NAME
 PC570 'Q_CAP_C0805-22UF,16V,20%,X6S,CA':;

SECTION_NUMBER 1
 '@S9S_MB_2U_LIB.S9S_MB_2U(SCH_1):PAGE245_I109@PURE_QUANTA.Q_CAP(CHIPS)':
 C_PATH='@s9s_mb_2u_lib.s9s_mb_2u(sch_1):page245_i109@pure_quanta.q_cap(chips)',
 P_PATH='@s9s_mb_2u_lib.s9s_mb_2u(sch_1):page259_i109@pure_quanta.q_cap(chips)',
 PATH='I109',
 DRAWING='@S9S_MB_2U_LIB.S9S_MB_2U(SCH_1):PAGE245',
 PHYS_PAGE='259',
 XY='(-3025,850)',
 ROT='0',
 VER='1',
 PACK_TYPE='C0805',
 LOCATION='PC570',
 CDS_LIB='pure_quanta',
 CDS_PART_NAME='Q_CAP_C0805-22UF,16V,20%,X6S,CA',
 TOLERANCE='20%',
 MATERIAL='X6S',
 VOLTAGE='16V',
 VALUE='22UF',
 PRIM_FILE='./archive_libs/logical/q_cap/chips/chips.prt';

PART_NAME
 PC570_P1_2 'Q_CAP_C0805-22UF,16V,20%,X6S,CA':;

SECTION_NUMBER 1
 '@S9S_MB_2U_LIB.S9S_MB_2U(SCH_1):PAGE271_I53@PURE_QUANTA.Q_CAP(CHIPS)':
 C_PATH='@s9s_mb_2u_lib.s9s_mb_2u(sch_1):page271_i53@pure_quanta.q_cap(chips)',
 P_PATH='@s9s_mb_2u_lib.s9s_mb_2u(sch_1):page285_i53@pure_quanta.q_cap(chips)',
 PATH='I53',
 DRAWING='@S9S_MB_2U_LIB.S9S_MB_2U(SCH_1):PAGE271',
 PHYS_PAGE='285',
 XY='(250,-800)',
 ROT='0',
 VER='1',
 PACK_TYPE='C0805',
 LOCATION='PC570_P1_2',
 CDS_LIB='pure_quanta',
 CDS_PART_NAME='Q_CAP_C0805-22UF,16V,20%,X6S,CA',
 TOLERANCE='20%',
 MATERIAL='X6S',
 VOLTAGE='16V',
 VALUE='22UF',
 PRIM_FILE='./archive_libs/logical/q_cap/chips/chips.prt';

PART_NAME
 PC571 'Q_CAP_C0805-22UF,16V,20%,X6S,CA':;

SECTION_NUMBER 1
 '@S9S_MB_2U_LIB.S9S_MB_2U(SCH_1):PAGE245_I110@PURE_QUANTA.Q_CAP(CHIPS)':
 C_PATH='@s9s_mb_2u_lib.s9s_mb_2u(sch_1):page245_i110@pure_quanta.q_cap(chips)',
 P_PATH='@s9s_mb_2u_lib.s9s_mb_2u(sch_1):page259_i110@pure_quanta.q_cap(chips)',
 PATH='I110',
 DRAWING='@S9S_MB_2U_LIB.S9S_MB_2U(SCH_1):PAGE245',
 PHYS_PAGE='259',
 XY='(-2700,850)',
 ROT='0',
 VER='1',
 PACK_TYPE='C0805',
 LOCATION='PC571',
 CDS_LIB='pure_quanta',
 CDS_PART_NAME='Q_CAP_C0805-22UF,16V,20%,X6S,CA',
 TOLERANCE='20%',
 MATERIAL='X6S',
 VOLTAGE='16V',
 VALUE='22UF',
 PRIM_FILE='./archive_libs/logical/q_cap/chips/chips.prt';

PART_NAME
 PC571_P1_1 'Q_CAP_C0805-22UF,16V,20%,X6S,CA':;

SECTION_NUMBER 1
 '@S9S_MB_2U_LIB.S9S_MB_2U(SCH_1):PAGE271_I76@PURE_QUANTA.Q_CAP(CHIPS)':
 C_PATH='@s9s_mb_2u_lib.s9s_mb_2u(sch_1):page271_i76@pure_quanta.q_cap(chips)',
 P_PATH='@s9s_mb_2u_lib.s9s_mb_2u(sch_1):page285_i76@pure_quanta.q_cap(chips)',
 PATH='I76',
 DRAWING='@S9S_MB_2U_LIB.S9S_MB_2U(SCH_1):PAGE271',
 PHYS_PAGE='285',
 XY='(275,2025)',
 ROT='0',
 VER='1',
 PACK_TYPE='C0805',
 LOCATION='PC571_P1_1',
 CDS_LIB='pure_quanta',
 CDS_PART_NAME='Q_CAP_C0805-22UF,16V,20%,X6S,CA',
 TOLERANCE='20%',
 MATERIAL='X6S',
 VOLTAGE='16V',
 VALUE='22UF',
 PRIM_FILE='./archive_libs/logical/q_cap/chips/chips.prt';

PART_NAME
 PC572_P1_1 'Q_CAP_C0402-100NF,50V,10%,X7R,A':;

SECTION_NUMBER 1
 '@S9S_MB_2U_LIB.S9S_MB_2U(SCH_1):PAGE271_I84@PURE_QUANTA.Q_CAP(CHIPS)':
 C_PATH='@s9s_mb_2u_lib.s9s_mb_2u(sch_1):page271_i84@pure_quanta.q_cap(chips)',
 P_PATH='@s9s_mb_2u_lib.s9s_mb_2u(sch_1):page285_i84@pure_quanta.q_cap(chips)',
 PATH='I84',
 DRAWING='@S9S_MB_2U_LIB.S9S_MB_2U(SCH_1):PAGE271',
 PHYS_PAGE='285',
 XY='(2550,950)',
 ROT='0',
 VER='1',
 PACK_TYPE='C0402',
 LOCATION='PC572_P1_1',
 CDS_LIB='pure_quanta',
 CDS_PART_NAME='Q_CAP_C0402-100NF,50V,10%,X7R,A',
 TOLERANCE='10%',
 MATERIAL='X7R',
 VOLTAGE='50V',
 VALUE='100NF',
 PRIM_FILE='./archive_libs/logical/q_cap/chips/chips.prt';

PART_NAME
 PC574_P1_1 'Q_CAP_C0402-1UF,16V,10%,X6S,CHA':;

SECTION_NUMBER 1
 '@S9S_MB_2U_LIB.S9S_MB_2U(SCH_1):PAGE271_I85@PURE_QUANTA.Q_CAP(CHIPS)':
 C_PATH='@s9s_mb_2u_lib.s9s_mb_2u(sch_1):page271_i85@pure_quanta.q_cap(chips)',
 P_PATH='@s9s_mb_2u_lib.s9s_mb_2u(sch_1):page285_i85@pure_quanta.q_cap(chips)',
 PATH='I85',
 DRAWING='@S9S_MB_2U_LIB.S9S_MB_2U(SCH_1):PAGE271',
 PHYS_PAGE='285',
 XY='(2950,950)',
 ROT='0',
 VER='1',
 PACK_TYPE='C0402',
 LOCATION='PC574_P1_1',
 CDS_LIB='pure_quanta',
 CDS_PART_NAME='Q_CAP_C0402-1UF,16V,10%,X6S,CHA',
 TOLERANCE='10%',
 MATERIAL='X6S',
 VOLTAGE='16V',
 VALUE='1UF',
 PRIM_FILE='./archive_libs/logical/q_cap/chips/chips.prt';

PART_NAME
 PC575_P1_2 'Q_CAP_C0805-22UF,4V,20%,X6S,CHA':;

SECTION_NUMBER 1
 '@S9S_MB_2U_LIB.S9S_MB_2U(SCH_1):PAGE271_I57@PURE_QUANTA.Q_CAP(CHIPS)':
 C_PATH='@s9s_mb_2u_lib.s9s_mb_2u(sch_1):page271_i57@pure_quanta.q_cap(chips)',
 P_PATH='@s9s_mb_2u_lib.s9s_mb_2u(sch_1):page285_i57@pure_quanta.q_cap(chips)',
 PATH='I57',
 DRAWING='@S9S_MB_2U_LIB.S9S_MB_2U(SCH_1):PAGE271',
 PHYS_PAGE='285',
 XY='(2775,-1975)',
 ROT='0',
 VER='1',
 PACK_TYPE='C0805',
 LOCATION='PC575_P1_2',
 CDS_LIB='pure_quanta',
 CDS_PART_NAME='Q_CAP_C0805-22UF,4V,20%,X6S,CHA',
 TOLERANCE='20%',
 MATERIAL='X6S',
 VOLTAGE='4V',
 VALUE='22UF',
 PRIM_FILE='./archive_libs/logical/q_cap/chips/chips.prt';

PART_NAME
 PC576 'Q_CAP_C0805-22UF,16V,20%,X6S,CA':;

SECTION_NUMBER 1
 '@S9S_MB_2U_LIB.S9S_MB_2U(SCH_1):PAGE245_I113@PURE_QUANTA.Q_CAP(CHIPS)':
 C_PATH='@s9s_mb_2u_lib.s9s_mb_2u(sch_1):page245_i113@pure_quanta.q_cap(chips)',
 P_PATH='@s9s_mb_2u_lib.s9s_mb_2u(sch_1):page259_i113@pure_quanta.q_cap(chips)',
 PATH='I113',
 DRAWING='@S9S_MB_2U_LIB.S9S_MB_2U(SCH_1):PAGE245',
 PHYS_PAGE='259',
 XY='(-2375,850)',
 ROT='0',
 VER='1',
 PACK_TYPE='C0805',
 LOCATION='PC576',
 CDS_LIB='pure_quanta',
 CDS_PART_NAME='Q_CAP_C0805-22UF,16V,20%,X6S,CA',
 TOLERANCE='20%',
 MATERIAL='X6S',
 VOLTAGE='16V',
 VALUE='22UF',
 PRIM_FILE='./archive_libs/logical/q_cap/chips/chips.prt';

PART_NAME
 PC576_P1_1 'Q_CAP_C0805-22UF,4V,20%,X6S,CHA':;

SECTION_NUMBER 1
 '@S9S_MB_2U_LIB.S9S_MB_2U(SCH_1):PAGE271_I88@PURE_QUANTA.Q_CAP(CHIPS)':
 C_PATH='@s9s_mb_2u_lib.s9s_mb_2u(sch_1):page271_i88@pure_quanta.q_cap(chips)',
 P_PATH='@s9s_mb_2u_lib.s9s_mb_2u(sch_1):page285_i88@pure_quanta.q_cap(chips)',
 PATH='I88',
 DRAWING='@S9S_MB_2U_LIB.S9S_MB_2U(SCH_1):PAGE271',
 PHYS_PAGE='285',
 XY='(3375,950)',
 ROT='0',
 VER='1',
 PACK_TYPE='C0805',
 LOCATION='PC576_P1_1',
 CDS_LIB='pure_quanta',
 CDS_PART_NAME='Q_CAP_C0805-22UF,4V,20%,X6S,CHA',
 TOLERANCE='20%',
 MATERIAL='X6S',
 VOLTAGE='4V',
 VALUE='22UF',
 PRIM_FILE='./archive_libs/logical/q_cap/chips/chips.prt';

PART_NAME
 PC577 'Q_CAP_0402-0.1UF,25V,10%,X7R,CA':;

SECTION_NUMBER 1
 '@S9S_MB_2U_LIB.S9S_MB_2U(SCH_1):PAGE245_I115@PURE_QUANTA.Q_CAP(CHIPS)':
 C_PATH='@s9s_mb_2u_lib.s9s_mb_2u(sch_1):page245_i115@pure_quanta.q_cap(chips)',
 P_PATH='@s9s_mb_2u_lib.s9s_mb_2u(sch_1):page259_i115@pure_quanta.q_cap(chips)',
 PATH='I115',
 DRAWING='@S9S_MB_2U_LIB.S9S_MB_2U(SCH_1):PAGE245',
 PHYS_PAGE='259',
 XY='(-1725,850)',
 ROT='0',
 VER='1',
 PACK_TYPE='0402',
 LOCATION='PC577',
 CDS_LIB='pure_quanta',
 CDS_PART_NAME='Q_CAP_0402-0.1UF,25V,10%,X7R,CA',
 TOLERANCE='10%',
 MATERIAL='X7R',
 VOLTAGE='25V',
 VALUE='0.1UF',
 PRIM_FILE='./archive_libs/logical/q_cap/chips/chips.prt';

PART_NAME
 PC577_P1_2 'Q_CAP_C0805-22UF,4V,20%,X6S,CHA':;

SECTION_NUMBER 1
 '@S9S_MB_2U_LIB.S9S_MB_2U(SCH_1):PAGE271_I58@PURE_QUANTA.Q_CAP(CHIPS)':
 C_PATH='@s9s_mb_2u_lib.s9s_mb_2u(sch_1):page271_i58@pure_quanta.q_cap(chips)',
 P_PATH='@s9s_mb_2u_lib.s9s_mb_2u(sch_1):page285_i58@pure_quanta.q_cap(chips)',
 PATH='I58',
 DRAWING='@S9S_MB_2U_LIB.S9S_MB_2U(SCH_1):PAGE271',
 PHYS_PAGE='285',
 XY='(3200,-1975)',
 ROT='0',
 VER='1',
 PACK_TYPE='C0805',
 LOCATION='PC577_P1_2',
 CDS_LIB='pure_quanta',
 CDS_PART_NAME='Q_CAP_C0805-22UF,4V,20%,X6S,CHA',
 TOLERANCE='20%',
 MATERIAL='X6S',
 VOLTAGE='4V',
 VALUE='22UF',
 PRIM_FILE='./archive_libs/logical/q_cap/chips/chips.prt';

PART_NAME
 PC578_P1_1 'Q_CAP_C0805-22UF,4V,20%,X6S,CHA':;

SECTION_NUMBER 1
 '@S9S_MB_2U_LIB.S9S_MB_2U(SCH_1):PAGE271_I91@PURE_QUANTA.Q_CAP(CHIPS)':
 C_PATH='@s9s_mb_2u_lib.s9s_mb_2u(sch_1):page271_i91@pure_quanta.q_cap(chips)',
 P_PATH='@s9s_mb_2u_lib.s9s_mb_2u(sch_1):page285_i91@pure_quanta.q_cap(chips)',
 PATH='I91',
 DRAWING='@S9S_MB_2U_LIB.S9S_MB_2U(SCH_1):PAGE271',
 PHYS_PAGE='285',
 XY='(3800,950)',
 ROT='0',
 VER='1',
 PACK_TYPE='C0805',
 LOCATION='PC578_P1_1',
 CDS_LIB='pure_quanta',
 CDS_PART_NAME='Q_CAP_C0805-22UF,4V,20%,X6S,CHA',
 TOLERANCE='20%',
 MATERIAL='X6S',
 VOLTAGE='4V',
 VALUE='22UF',
 PRIM_FILE='./archive_libs/logical/q_cap/chips/chips.prt';

PART_NAME
 PC579 'Q_CAPP_THLF-270UF,16V,20%,OSCOA':;

SECTION_NUMBER 1
 '@S9S_MB_2U_LIB.S9S_MB_2U(SCH_1):PAGE271_I86@PURE_QUANTA.Q_CAPP(CHIPS)':
 C_PATH='@s9s_mb_2u_lib.s9s_mb_2u(sch_1):page271_i86@pure_quanta.q_capp(chips)',
 P_PATH='@s9s_mb_2u_lib.s9s_mb_2u(sch_1):page285_i86@pure_quanta.q_capp(chips)',
 PATH='I86',
 DRAWING='@S9S_MB_2U_LIB.S9S_MB_2U(SCH_1):PAGE271',
 PHYS_PAGE='285',
 XY='(2500,2250)',
 ROT='0',
 VER='1',
 PACK_TYPE='THLF',
 LOCATION='PC579',
 CDS_LIB='pure_quanta',
 CDS_PART_NAME='Q_CAPP_THLF-270UF,16V,20%,OSCOA',
 TOLERANCE='20%',
 MATERIAL='OSCON',
 VOLTAGE='16V',
 VALUE='270UF',
 PRIM_FILE='./archive_libs/logical/q_capp/chips/chips.prt';

PART_NAME
 PC580 'Q_CAPP_THLF-560UF,2.5V,20%,OSCA':;

SECTION_NUMBER 1
 '@S9S_MB_2U_LIB.S9S_MB_2U(SCH_1):PAGE271_I63@PURE_QUANTA.Q_CAPP(CHIPS)':
 C_PATH='@s9s_mb_2u_lib.s9s_mb_2u(sch_1):page271_i63@pure_quanta.q_capp(chips)',
 P_PATH='@s9s_mb_2u_lib.s9s_mb_2u(sch_1):page285_i63@pure_quanta.q_capp(chips)',
 PATH='I63',
 DRAWING='@S9S_MB_2U_LIB.S9S_MB_2U(SCH_1):PAGE271',
 PHYS_PAGE='285',
 XY='(2500,-75)',
 ROT='0',
 VER='1',
 PACK_TYPE='THLF',
 LOCATION='PC580',
 CDS_LIB='pure_quanta',
 CDS_PART_NAME='Q_CAPP_THLF-560UF,2.5V,20%,OSCA',
 TOLERANCE='20%',
 MATERIAL='OSCON',
 VOLTAGE='2.5V',
 VALUE='560UF',
 PRIM_FILE='./archive_libs/logical/q_capp/chips/chips.prt';

PART_NAME
 PC581 'Q_CAP_C0603-4.7UF,16V,10%,X6S,A':;

SECTION_NUMBER 1
 '@S9S_MB_2U_LIB.S9S_MB_2U(SCH_1):PAGE245_I86@PURE_QUANTA.Q_CAP(CHIPS)':
 C_PATH='@s9s_mb_2u_lib.s9s_mb_2u(sch_1):page245_i86@pure_quanta.q_cap(chips)',
 P_PATH='@s9s_mb_2u_lib.s9s_mb_2u(sch_1):page259_i86@pure_quanta.q_cap(chips)',
 PATH='I86',
 DRAWING='@S9S_MB_2U_LIB.S9S_MB_2U(SCH_1):PAGE245',
 PHYS_PAGE='259',
 XY='(-2050,-625)',
 ROT='0',
 VER='1',
 PACK_TYPE='C0603',
 LOCATION='PC581',
 CDS_LIB='pure_quanta',
 CDS_PART_NAME='Q_CAP_C0603-4.7UF,16V,10%,X6S,A',
 TOLERANCE='10%',
 MATERIAL='X6S',
 VOLTAGE='16V',
 VALUE='4.7UF',
 PRIM_FILE='./archive_libs/logical/q_cap/chips/chips.prt';

PART_NAME
 PC582 'Q_CAPP_THLF-270UF,16V,20%,OSCOA':;

SECTION_NUMBER 1
 '@S9S_MB_2U_LIB.S9S_MB_2U(SCH_1):PAGE271_I87@PURE_QUANTA.Q_CAPP(CHIPS)':
 C_PATH='@s9s_mb_2u_lib.s9s_mb_2u(sch_1):page271_i87@pure_quanta.q_capp(chips)',
 P_PATH='@s9s_mb_2u_lib.s9s_mb_2u(sch_1):page285_i87@pure_quanta.q_capp(chips)',
 PATH='I87',
 DRAWING='@S9S_MB_2U_LIB.S9S_MB_2U(SCH_1):PAGE271',
 PHYS_PAGE='285',
 XY='(2900,2250)',
 ROT='0',
 VER='1',
 PACK_TYPE='THLF',
 LOCATION='PC582',
 CDS_LIB='pure_quanta',
 CDS_PART_NAME='Q_CAPP_THLF-270UF,16V,20%,OSCOA',
 TOLERANCE='20%',
 MATERIAL='OSCON',
 VOLTAGE='16V',
 VALUE='270UF',
 PRIM_FILE='./archive_libs/logical/q_capp/chips/chips.prt';

PART_NAME
 PC583 'Q_CAPP_THLF-560UF,2.5V,20%,OSCA':;

SECTION_NUMBER 1
 '@S9S_MB_2U_LIB.S9S_MB_2U(SCH_1):PAGE271_I64@PURE_QUANTA.Q_CAPP(CHIPS)':
 C_PATH='@s9s_mb_2u_lib.s9s_mb_2u(sch_1):page271_i64@pure_quanta.q_capp(chips)',
 P_PATH='@s9s_mb_2u_lib.s9s_mb_2u(sch_1):page285_i64@pure_quanta.q_capp(chips)',
 PATH='I64',
 DRAWING='@S9S_MB_2U_LIB.S9S_MB_2U(SCH_1):PAGE271',
 PHYS_PAGE='285',
 XY='(3025,-75)',
 ROT='0',
 VER='1',
 PACK_TYPE='THLF',
 LOCATION='PC583',
 CDS_LIB='pure_quanta',
 CDS_PART_NAME='Q_CAPP_THLF-560UF,2.5V,20%,OSCA',
 TOLERANCE='20%',
 MATERIAL='OSCON',
 VOLTAGE='2.5V',
 VALUE='560UF',
 PRIM_FILE='./archive_libs/logical/q_capp/chips/chips.prt';

PART_NAME
 PC585 'Q_CAPP_THLF-270UF,16V,20%,OSCOA':;

SECTION_NUMBER 1
 '@S9S_MB_2U_LIB.S9S_MB_2U(SCH_1):PAGE271_I92@PURE_QUANTA.Q_CAPP(CHIPS)':
 C_PATH='@s9s_mb_2u_lib.s9s_mb_2u(sch_1):page271_i92@pure_quanta.q_capp(chips)',
 P_PATH='@s9s_mb_2u_lib.s9s_mb_2u(sch_1):page285_i92@pure_quanta.q_capp(chips)',
 PATH='I92',
 DRAWING='@S9S_MB_2U_LIB.S9S_MB_2U(SCH_1):PAGE271',
 PHYS_PAGE='285',
 XY='(3300,2250)',
 ROT='0',
 VER='1',
 PACK_TYPE='THLF',
 LOCATION='PC585',
 CDS_LIB='pure_quanta',
 CDS_PART_NAME='Q_CAPP_THLF-270UF,16V,20%,OSCOA',
 TOLERANCE='20%',
 MATERIAL='OSCON',
 VOLTAGE='16V',
 VALUE='270UF',
 PRIM_FILE='./archive_libs/logical/q_capp/chips/chips.prt';

PART_NAME
 PC586 'Q_CAPP_THLF-560UF,2.5V,20%,OSCA':;

SECTION_NUMBER 1
 '@S9S_MB_2U_LIB.S9S_MB_2U(SCH_1):PAGE271_I69@PURE_QUANTA.Q_CAPP(CHIPS)':
 C_PATH='@s9s_mb_2u_lib.s9s_mb_2u(sch_1):page271_i69@pure_quanta.q_capp(chips)',
 P_PATH='@s9s_mb_2u_lib.s9s_mb_2u(sch_1):page285_i69@pure_quanta.q_capp(chips)',
 PATH='I69',
 DRAWING='@S9S_MB_2U_LIB.S9S_MB_2U(SCH_1):PAGE271',
 PHYS_PAGE='285',
 XY='(3550,-75)',
 ROT='0',
 VER='1',
 PACK_TYPE='THLF',
 LOCATION='PC586',
 CDS_LIB='pure_quanta',
 CDS_PART_NAME='Q_CAPP_THLF-560UF,2.5V,20%,OSCA',
 TOLERANCE='20%',
 MATERIAL='OSCON',
 VOLTAGE='2.5V',
 VALUE='560UF',
 PRIM_FILE='./archive_libs/logical/q_capp/chips/chips.prt';

PART_NAME
 PC587 'Q_CAPP_SMLF-330UF,2.5V,+10/-35A':;

SECTION_NUMBER 1
 '@S9S_MB_2U_LIB.S9S_MB_2U(SCH_1):PAGE271_I65@PURE_QUANTA.Q_CAPP(CHIPS)':
 C_PATH='@s9s_mb_2u_lib.s9s_mb_2u(sch_1):page271_i65@pure_quanta.q_capp(chips)',
 P_PATH='@s9s_mb_2u_lib.s9s_mb_2u(sch_1):page285_i65@pure_quanta.q_capp(chips)',
 PATH='I65',
 DRAWING='@S9S_MB_2U_LIB.S9S_MB_2U(SCH_1):PAGE271',
 PHYS_PAGE='285',
 XY='(3550,-950)',
 ROT='0',
 VER='1',
 PACK_TYPE='SMLF',
 LOCATION='PC587',
 CDS_LIB='pure_quanta',
 CDS_PART_NAME='Q_CAPP_SMLF-330UF,2.5V,+10/-35A',
 TOLERANCE='+10/-35%',
 MATERIAL='EMPTY',
 VOLTAGE='2.5V',
 VALUE='330UF',
 PRIM_FILE='./archive_libs/logical/q_capp/chips/chips.prt';

PART_NAME
 PC588 'Q_CAPP_THLF-270UF,16V,20%,OSCOA':;

SECTION_NUMBER 1
 '@S9S_MB_2U_LIB.S9S_MB_2U(SCH_1):PAGE271_I94@PURE_QUANTA.Q_CAPP(CHIPS)':
 C_PATH='@s9s_mb_2u_lib.s9s_mb_2u(sch_1):page271_i94@pure_quanta.q_capp(chips)',
 P_PATH='@s9s_mb_2u_lib.s9s_mb_2u(sch_1):page285_i94@pure_quanta.q_capp(chips)',
 PATH='I94',
 DRAWING='@S9S_MB_2U_LIB.S9S_MB_2U(SCH_1):PAGE271',
 PHYS_PAGE='285',
 XY='(3700,2250)',
 ROT='0',
 VER='1',
 PACK_TYPE='THLF',
 LOCATION='PC588',
 CDS_LIB='pure_quanta',
 CDS_PART_NAME='Q_CAPP_THLF-270UF,16V,20%,OSCOA',
 TOLERANCE='20%',
 MATERIAL='OSCON',
 VOLTAGE='16V',
 VALUE='270UF',
 PRIM_FILE='./archive_libs/logical/q_capp/chips/chips.prt';

PART_NAME
 PC589 'Q_CAPP_THLF-560UF,2.5V,20%,OSCA':;

SECTION_NUMBER 1
 '@S9S_MB_2U_LIB.S9S_MB_2U(SCH_1):PAGE271_I72@PURE_QUANTA.Q_CAPP(CHIPS)':
 C_PATH='@s9s_mb_2u_lib.s9s_mb_2u(sch_1):page271_i72@pure_quanta.q_capp(chips)',
 P_PATH='@s9s_mb_2u_lib.s9s_mb_2u(sch_1):page285_i72@pure_quanta.q_capp(chips)',
 PATH='I72',
 DRAWING='@S9S_MB_2U_LIB.S9S_MB_2U(SCH_1):PAGE271',
 PHYS_PAGE='285',
 XY='(4050,-75)',
 ROT='0',
 VER='1',
 PACK_TYPE='THLF',
 LOCATION='PC589',
 CDS_LIB='pure_quanta',
 CDS_PART_NAME='Q_CAPP_THLF-560UF,2.5V,20%,OSCA',
 TOLERANCE='20%',
 MATERIAL='OSCON',
 VOLTAGE='2.5V',
 VALUE='560UF',
 PRIM_FILE='./archive_libs/logical/q_capp/chips/chips.prt';

PART_NAME
 PC590 'Q_CAPP_SMLF-330UF,2.5V,+10/-35A':;

SECTION_NUMBER 1
 '@S9S_MB_2U_LIB.S9S_MB_2U(SCH_1):PAGE271_I68@PURE_QUANTA.Q_CAPP(CHIPS)':
 C_PATH='@s9s_mb_2u_lib.s9s_mb_2u(sch_1):page271_i68@pure_quanta.q_capp(chips)',
 P_PATH='@s9s_mb_2u_lib.s9s_mb_2u(sch_1):page285_i68@pure_quanta.q_capp(chips)',
 PATH='I68',
 DRAWING='@S9S_MB_2U_LIB.S9S_MB_2U(SCH_1):PAGE271',
 PHYS_PAGE='285',
 XY='(4050,-950)',
 ROT='0',
 VER='1',
 PACK_TYPE='SMLF',
 LOCATION='PC590',
 CDS_LIB='pure_quanta',
 CDS_PART_NAME='Q_CAPP_SMLF-330UF,2.5V,+10/-35A',
 TOLERANCE='+10/-35%',
 MATERIAL='EMPTY',
 VOLTAGE='2.5V',
 VALUE='330UF',
 PRIM_FILE='./archive_libs/logical/q_capp/chips/chips.prt';

PART_NAME
 PC591 'Q_CAP_C0603-2.2UF,16V,10%,X6S,A':;

SECTION_NUMBER 1
 '@S9S_MB_2U_LIB.S9S_MB_2U(SCH_1):PAGE245_I93@PURE_QUANTA.Q_CAP(CHIPS)':
 C_PATH='@s9s_mb_2u_lib.s9s_mb_2u(sch_1):page245_i93@pure_quanta.q_cap(chips)',
 P_PATH='@s9s_mb_2u_lib.s9s_mb_2u(sch_1):page259_i93@pure_quanta.q_cap(chips)',
 PATH='I93',
 DRAWING='@S9S_MB_2U_LIB.S9S_MB_2U(SCH_1):PAGE245',
 PHYS_PAGE='259',
 XY='(-1625,-625)',
 ROT='0',
 VER='1',
 PACK_TYPE='C0603',
 LOCATION='PC591',
 CDS_LIB='pure_quanta',
 CDS_PART_NAME='Q_CAP_C0603-2.2UF,16V,10%,X6S,A',
 TOLERANCE='10%',
 MATERIAL='X6S',
 VOLTAGE='16V',
 VALUE='2.2UF',
 PRIM_FILE='./archive_libs/logical/q_cap/chips/chips.prt';

PART_NAME
 PC594 'Q_CAP_0402-3300PF,50V,10%,X7R,A':;

SECTION_NUMBER 1
 '@S9S_MB_2U_LIB.S9S_MB_2U(SCH_1):PAGE252_I67@PURE_QUANTA.Q_CAP(CHIPS)':
 C_PATH='@s9s_mb_2u_lib.s9s_mb_2u(sch_1):page252_i67@pure_quanta.q_cap(chips)',
 P_PATH='@s9s_mb_2u_lib.s9s_mb_2u(sch_1):page266_i67@pure_quanta.q_cap(chips)',
 PATH='I67',
 DRAWING='@S9S_MB_2U_LIB.S9S_MB_2U(SCH_1):PAGE252',
 PHYS_PAGE='266',
 XY='(-4275,3275)',
 ROT='0',
 VER='1',
 PACK_TYPE='0402',
 LOCATION='PC594',
 CDS_LIB='pure_quanta',
 CDS_PART_NAME='Q_CAP_0402-3300PF,50V,10%,X7R,A',
 TOLERANCE='10%',
 MATERIAL='X7R',
 VOLTAGE='50V',
 VALUE='3300PF',
 PRIM_FILE='./archive_libs/logical/q_cap/chips/chips.prt';

PART_NAME
 PC600 'Q_CAP_C0402-2.2UF,10V,10%,X6S,A':;

SECTION_NUMBER 1
 '@S9S_MB_2U_LIB.S9S_MB_2U(SCH_1):PAGE257_I37@PURE_QUANTA.Q_CAP(CHIPS)':
 C_PATH='@s9s_mb_2u_lib.s9s_mb_2u(sch_1):page257_i37@pure_quanta.q_cap(chips)',
 P_PATH='@s9s_mb_2u_lib.s9s_mb_2u(sch_1):page271_i37@pure_quanta.q_cap(chips)',
 PATH='I37',
 DRAWING='@S9S_MB_2U_LIB.S9S_MB_2U(SCH_1):PAGE257',
 PHYS_PAGE='271',
 XY='(-4250,5650)',
 ROT='0',
 VER='1',
 PACK_TYPE='C0402',
 LOCATION='PC600',
 CDS_LIB='pure_quanta',
 CDS_PART_NAME='Q_CAP_C0402-2.2UF,10V,10%,X6S,A',
 TOLERANCE='10%',
 MATERIAL='X6S',
 VOLTAGE='10V',
 VALUE='2.2UF',
 PRIM_FILE='./archive_libs/logical/q_cap/chips/chips.prt';

PART_NAME
 PC601 'Q_CAP_C0402-2.2UF,10V,10%,X6S,A':;

SECTION_NUMBER 1
 '@S9S_MB_2U_LIB.S9S_MB_2U(SCH_1):PAGE257_I18@PURE_QUANTA.Q_CAP(CHIPS)':
 C_PATH='@s9s_mb_2u_lib.s9s_mb_2u(sch_1):page257_i18@pure_quanta.q_cap(chips)',
 P_PATH='@s9s_mb_2u_lib.s9s_mb_2u(sch_1):page271_i18@pure_quanta.q_cap(chips)',
 PATH='I18',
 DRAWING='@S9S_MB_2U_LIB.S9S_MB_2U(SCH_1):PAGE257',
 PHYS_PAGE='271',
 XY='(-4250,2850)',
 ROT='0',
 VER='1',
 PACK_TYPE='C0402',
 LOCATION='PC601',
 CDS_LIB='pure_quanta',
 CDS_PART_NAME='Q_CAP_C0402-2.2UF,10V,10%,X6S,A',
 TOLERANCE='10%',
 MATERIAL='X6S',
 VOLTAGE='10V',
 VALUE='2.2UF',
 PRIM_FILE='./archive_libs/logical/q_cap/chips/chips.prt';

PART_NAME
 PC602_P0_1 'Q_CAP_0402-3300PF,50V,10%,X7R,A':;

SECTION_NUMBER 1
 '@S9S_MB_2U_LIB.S9S_MB_2U(SCH_1):PAGE257_I44@PURE_QUANTA.Q_CAP(CHIPS)':
 C_PATH='@s9s_mb_2u_lib.s9s_mb_2u(sch_1):page257_i44@pure_quanta.q_cap(chips)',
 P_PATH='@s9s_mb_2u_lib.s9s_mb_2u(sch_1):page271_i44@pure_quanta.q_cap(chips)',
 PATH='I44',
 DRAWING='@S9S_MB_2U_LIB.S9S_MB_2U(SCH_1):PAGE257',
 PHYS_PAGE='271',
 XY='(-1925,6100)',
 ROT='0',
 VER='1',
 PACK_TYPE='0402',
 LOCATION='PC602_P0_1',
 CDS_LIB='pure_quanta',
 CDS_PART_NAME='Q_CAP_0402-3300PF,50V,10%,X7R,A',
 TOLERANCE='10%',
 MATERIAL='X7R',
 VOLTAGE='50V',
 VALUE='3300PF',
 PRIM_FILE='./archive_libs/logical/q_cap/chips/chips.prt';

PART_NAME
 PC603_P0_2 'Q_CAP_0402-3300PF,50V,10%,X7R,A':;

SECTION_NUMBER 1
 '@S9S_MB_2U_LIB.S9S_MB_2U(SCH_1):PAGE257_I27@PURE_QUANTA.Q_CAP(CHIPS)':
 C_PATH='@s9s_mb_2u_lib.s9s_mb_2u(sch_1):page257_i27@pure_quanta.q_cap(chips)',
 P_PATH='@s9s_mb_2u_lib.s9s_mb_2u(sch_1):page271_i27@pure_quanta.q_cap(chips)',
 PATH='I27',
 DRAWING='@S9S_MB_2U_LIB.S9S_MB_2U(SCH_1):PAGE257',
 PHYS_PAGE='271',
 XY='(-1925,3300)',
 ROT='0',
 VER='1',
 PACK_TYPE='0402',
 LOCATION='PC603_P0_2',
 CDS_LIB='pure_quanta',
 CDS_PART_NAME='Q_CAP_0402-3300PF,50V,10%,X7R,A',
 TOLERANCE='10%',
 MATERIAL='X7R',
 VOLTAGE='50V',
 VALUE='3300PF',
 PRIM_FILE='./archive_libs/logical/q_cap/chips/chips.prt';

PART_NAME
 PC604_P0_1 'Q_CAP_C0402-1UF,16V,10%,X6S,CHA':;

SECTION_NUMBER 1
 '@S9S_MB_2U_LIB.S9S_MB_2U(SCH_1):PAGE257_I45@PURE_QUANTA.Q_CAP(CHIPS)':
 C_PATH='@s9s_mb_2u_lib.s9s_mb_2u(sch_1):page257_i45@pure_quanta.q_cap(chips)',
 P_PATH='@s9s_mb_2u_lib.s9s_mb_2u(sch_1):page271_i45@pure_quanta.q_cap(chips)',
 PATH='I45',
 DRAWING='@S9S_MB_2U_LIB.S9S_MB_2U(SCH_1):PAGE257',
 PHYS_PAGE='271',
 XY='(-1525,6100)',
 ROT='0',
 VER='1',
 PACK_TYPE='C0402',
 LOCATION='PC604_P0_1',
 CDS_LIB='pure_quanta',
 CDS_PART_NAME='Q_CAP_C0402-1UF,16V,10%,X6S,CHA',
 TOLERANCE='10%',
 MATERIAL='X6S',
 VOLTAGE='16V',
 VALUE='1UF',
 PRIM_FILE='./archive_libs/logical/q_cap/chips/chips.prt';

PART_NAME
 PC605_P0_2 'Q_CAP_C0402-1UF,16V,10%,X6S,CHA':;

SECTION_NUMBER 1
 '@S9S_MB_2U_LIB.S9S_MB_2U(SCH_1):PAGE257_I28@PURE_QUANTA.Q_CAP(CHIPS)':
 C_PATH='@s9s_mb_2u_lib.s9s_mb_2u(sch_1):page257_i28@pure_quanta.q_cap(chips)',
 P_PATH='@s9s_mb_2u_lib.s9s_mb_2u(sch_1):page271_i28@pure_quanta.q_cap(chips)',
 PATH='I28',
 DRAWING='@S9S_MB_2U_LIB.S9S_MB_2U(SCH_1):PAGE257',
 PHYS_PAGE='271',
 XY='(-1525,3300)',
 ROT='0',
 VER='1',
 PACK_TYPE='C0402',
 LOCATION='PC605_P0_2',
 CDS_LIB='pure_quanta',
 CDS_PART_NAME='Q_CAP_C0402-1UF,16V,10%,X6S,CHA',
 TOLERANCE='10%',
 MATERIAL='X6S',
 VOLTAGE='16V',
 VALUE='1UF',
 PRIM_FILE='./archive_libs/logical/q_cap/chips/chips.prt';

PART_NAME
 PC606 'Q_CAP_C0402-100NF,50V,10%,X7R,A':;

SECTION_NUMBER 1
 '@S9S_MB_2U_LIB.S9S_MB_2U(SCH_1):PAGE257_I71@PURE_QUANTA.Q_CAP(CHIPS)':
 C_PATH='@s9s_mb_2u_lib.s9s_mb_2u(sch_1):page257_i71@pure_quanta.q_cap(chips)',
 P_PATH='@s9s_mb_2u_lib.s9s_mb_2u(sch_1):page271_i71@pure_quanta.q_cap(chips)',
 PATH='I71',
 DRAWING='@S9S_MB_2U_LIB.S9S_MB_2U(SCH_1):PAGE257',
 PHYS_PAGE='271',
 XY='(-300,5475)',
 ROT='2',
 VER='1',
 PACK_TYPE='C0402',
 LOCATION='PC606',
 CDS_LIB='pure_quanta',
 CDS_PART_NAME='Q_CAP_C0402-100NF,50V,10%,X7R,A',
 TOLERANCE='10%',
 MATERIAL='X7R',
 VOLTAGE='50V',
 VALUE='100NF',
 PRIM_FILE='./archive_libs/logical/q_cap/chips/chips.prt';

PART_NAME
 PC607 'Q_CAP_C0402-100NF,50V,10%,X7R,A':;

SECTION_NUMBER 1
 '@S9S_MB_2U_LIB.S9S_MB_2U(SCH_1):PAGE257_I53@PURE_QUANTA.Q_CAP(CHIPS)':
 C_PATH='@s9s_mb_2u_lib.s9s_mb_2u(sch_1):page257_i53@pure_quanta.q_cap(chips)',
 P_PATH='@s9s_mb_2u_lib.s9s_mb_2u(sch_1):page271_i53@pure_quanta.q_cap(chips)',
 PATH='I53',
 DRAWING='@S9S_MB_2U_LIB.S9S_MB_2U(SCH_1):PAGE257',
 PHYS_PAGE='271',
 XY='(-300,2675)',
 ROT='2',
 VER='1',
 PACK_TYPE='C0402',
 LOCATION='PC607',
 CDS_LIB='pure_quanta',
 CDS_PART_NAME='Q_CAP_C0402-100NF,50V,10%,X7R,A',
 TOLERANCE='10%',
 MATERIAL='X7R',
 VOLTAGE='50V',
 VALUE='100NF',
 PRIM_FILE='./archive_libs/logical/q_cap/chips/chips.prt';

PART_NAME
 PC608_P0_1 'Q_CAP_C0805-22UF,16V,20%,X6S,CA':;

SECTION_NUMBER 1
 '@S9S_MB_2U_LIB.S9S_MB_2U(SCH_1):PAGE257_I47@PURE_QUANTA.Q_CAP(CHIPS)':
 C_PATH='@s9s_mb_2u_lib.s9s_mb_2u(sch_1):page257_i47@pure_quanta.q_cap(chips)',
 P_PATH='@s9s_mb_2u_lib.s9s_mb_2u(sch_1):page271_i47@pure_quanta.q_cap(chips)',
 PATH='I47',
 DRAWING='@S9S_MB_2U_LIB.S9S_MB_2U(SCH_1):PAGE257',
 PHYS_PAGE='271',
 XY='(-1125,6100)',
 ROT='0',
 VER='1',
 PACK_TYPE='C0805',
 LOCATION='PC608_P0_1',
 CDS_LIB='pure_quanta',
 CDS_PART_NAME='Q_CAP_C0805-22UF,16V,20%,X6S,CA',
 TOLERANCE='20%',
 MATERIAL='X6S',
 VOLTAGE='16V',
 VALUE='22UF',
 PRIM_FILE='./archive_libs/logical/q_cap/chips/chips.prt';

PART_NAME
 PC609_P0_2 'Q_CAP_C0805-22UF,16V,20%,X6S,CA':;

SECTION_NUMBER 1
 '@S9S_MB_2U_LIB.S9S_MB_2U(SCH_1):PAGE257_I31@PURE_QUANTA.Q_CAP(CHIPS)':
 C_PATH='@s9s_mb_2u_lib.s9s_mb_2u(sch_1):page257_i31@pure_quanta.q_cap(chips)',
 P_PATH='@s9s_mb_2u_lib.s9s_mb_2u(sch_1):page271_i31@pure_quanta.q_cap(chips)',
 PATH='I31',
 DRAWING='@S9S_MB_2U_LIB.S9S_MB_2U(SCH_1):PAGE257',
 PHYS_PAGE='271',
 XY='(-1125,3300)',
 ROT='0',
 VER='1',
 PACK_TYPE='C0805',
 LOCATION='PC609_P0_2',
 CDS_LIB='pure_quanta',
 CDS_PART_NAME='Q_CAP_C0805-22UF,16V,20%,X6S,CA',
 TOLERANCE='20%',
 MATERIAL='X6S',
 VOLTAGE='16V',
 VALUE='22UF',
 PRIM_FILE='./archive_libs/logical/q_cap/chips/chips.prt';

PART_NAME
 PC610_P0_1 'Q_CAP_C0805-22UF,16V,20%,X6S,CA':;

SECTION_NUMBER 1
 '@S9S_MB_2U_LIB.S9S_MB_2U(SCH_1):PAGE257_I48@PURE_QUANTA.Q_CAP(CHIPS)':
 C_PATH='@s9s_mb_2u_lib.s9s_mb_2u(sch_1):page257_i48@pure_quanta.q_cap(chips)',
 P_PATH='@s9s_mb_2u_lib.s9s_mb_2u(sch_1):page271_i48@pure_quanta.q_cap(chips)',
 PATH='I48',
 DRAWING='@S9S_MB_2U_LIB.S9S_MB_2U(SCH_1):PAGE257',
 PHYS_PAGE='271',
 XY='(-725,6100)',
 ROT='0',
 VER='1',
 PACK_TYPE='C0805',
 LOCATION='PC610_P0_1',
 CDS_LIB='pure_quanta',
 CDS_PART_NAME='Q_CAP_C0805-22UF,16V,20%,X6S,CA',
 TOLERANCE='20%',
 MATERIAL='X6S',
 VOLTAGE='16V',
 VALUE='22UF',
 PRIM_FILE='./archive_libs/logical/q_cap/chips/chips.prt';

PART_NAME
 PC611_P0_2 'Q_CAP_C0805-22UF,16V,20%,X6S,CA':;

SECTION_NUMBER 1
 '@S9S_MB_2U_LIB.S9S_MB_2U(SCH_1):PAGE257_I32@PURE_QUANTA.Q_CAP(CHIPS)':
 C_PATH='@s9s_mb_2u_lib.s9s_mb_2u(sch_1):page257_i32@pure_quanta.q_cap(chips)',
 P_PATH='@s9s_mb_2u_lib.s9s_mb_2u(sch_1):page271_i32@pure_quanta.q_cap(chips)',
 PATH='I32',
 DRAWING='@S9S_MB_2U_LIB.S9S_MB_2U(SCH_1):PAGE257',
 PHYS_PAGE='271',
 XY='(-725,3300)',
 ROT='0',
 VER='1',
 PACK_TYPE='C0805',
 LOCATION='PC611_P0_2',
 CDS_LIB='pure_quanta',
 CDS_PART_NAME='Q_CAP_C0805-22UF,16V,20%,X6S,CA',
 TOLERANCE='20%',
 MATERIAL='X6S',
 VOLTAGE='16V',
 VALUE='22UF',
 PRIM_FILE='./archive_libs/logical/q_cap/chips/chips.prt';

PART_NAME
 PC612_P0_1 'Q_CAP_C0402-100NF,50V,10%,X7R,A':;

SECTION_NUMBER 1
 '@S9S_MB_2U_LIB.S9S_MB_2U(SCH_1):PAGE257_I75@PURE_QUANTA.Q_CAP(CHIPS)':
 C_PATH='@s9s_mb_2u_lib.s9s_mb_2u(sch_1):page257_i75@pure_quanta.q_cap(chips)',
 P_PATH='@s9s_mb_2u_lib.s9s_mb_2u(sch_1):page271_i75@pure_quanta.q_cap(chips)',
 PATH='I75',
 DRAWING='@S9S_MB_2U_LIB.S9S_MB_2U(SCH_1):PAGE257',
 PHYS_PAGE='271',
 XY='(950,5000)',
 ROT='0',
 VER='1',
 PACK_TYPE='C0402',
 LOCATION='PC612_P0_1',
 CDS_LIB='pure_quanta',
 CDS_PART_NAME='Q_CAP_C0402-100NF,50V,10%,X7R,A',
 TOLERANCE='10%',
 MATERIAL='X7R',
 VOLTAGE='50V',
 VALUE='100NF',
 PRIM_FILE='./archive_libs/logical/q_cap/chips/chips.prt';

PART_NAME
 PC613_P0_2 'Q_CAP_C0402-1UF,16V,10%,X6S,CHA':;

SECTION_NUMBER 1
 '@S9S_MB_2U_LIB.S9S_MB_2U(SCH_1):PAGE257_I51@PURE_QUANTA.Q_CAP(CHIPS)':
 C_PATH='@s9s_mb_2u_lib.s9s_mb_2u(sch_1):page257_i51@pure_quanta.q_cap(chips)',
 P_PATH='@s9s_mb_2u_lib.s9s_mb_2u(sch_1):page271_i51@pure_quanta.q_cap(chips)',
 PATH='I51',
 DRAWING='@S9S_MB_2U_LIB.S9S_MB_2U(SCH_1):PAGE257',
 PHYS_PAGE='271',
 XY='(1000,2200)',
 ROT='0',
 VER='1',
 PACK_TYPE='C0402',
 LOCATION='PC613_P0_2',
 CDS_LIB='pure_quanta',
 CDS_PART_NAME='Q_CAP_C0402-1UF,16V,10%,X6S,CHA',
 TOLERANCE='10%',
 MATERIAL='X6S',
 VOLTAGE='16V',
 VALUE='1UF',
 PRIM_FILE='./archive_libs/logical/q_cap/chips/chips.prt';

PART_NAME
 PC615_P0_1 'Q_CAP_C0805-22UF,4V,20%,X6S,CHA':;

SECTION_NUMBER 1
 '@S9S_MB_2U_LIB.S9S_MB_2U(SCH_1):PAGE257_I77@PURE_QUANTA.Q_CAP(CHIPS)':
 C_PATH='@s9s_mb_2u_lib.s9s_mb_2u(sch_1):page257_i77@pure_quanta.q_cap(chips)',
 P_PATH='@s9s_mb_2u_lib.s9s_mb_2u(sch_1):page271_i77@pure_quanta.q_cap(chips)',
 PATH='I77',
 DRAWING='@S9S_MB_2U_LIB.S9S_MB_2U(SCH_1):PAGE257',
 PHYS_PAGE='271',
 XY='(1450,5000)',
 ROT='0',
 VER='1',
 PACK_TYPE='C0805',
 LOCATION='PC615_P0_1',
 CDS_LIB='pure_quanta',
 CDS_PART_NAME='Q_CAP_C0805-22UF,4V,20%,X6S,CHA',
 TOLERANCE='20%',
 MATERIAL='X6S',
 VOLTAGE='4V',
 VALUE='22UF',
 PRIM_FILE='./archive_libs/logical/q_cap/chips/chips.prt';

PART_NAME
 PC616_P0_2 'Q_CAP_C0805-22UF,4V,20%,X6S,CHA':;

SECTION_NUMBER 1
 '@S9S_MB_2U_LIB.S9S_MB_2U(SCH_1):PAGE257_I52@PURE_QUANTA.Q_CAP(CHIPS)':
 C_PATH='@s9s_mb_2u_lib.s9s_mb_2u(sch_1):page257_i52@pure_quanta.q_cap(chips)',
 P_PATH='@s9s_mb_2u_lib.s9s_mb_2u(sch_1):page271_i52@pure_quanta.q_cap(chips)',
 PATH='I52',
 DRAWING='@S9S_MB_2U_LIB.S9S_MB_2U(SCH_1):PAGE257',
 PHYS_PAGE='271',
 XY='(1450,2200)',
 ROT='0',
 VER='1',
 PACK_TYPE='C0805',
 LOCATION='PC616_P0_2',
 CDS_LIB='pure_quanta',
 CDS_PART_NAME='Q_CAP_C0805-22UF,4V,20%,X6S,CHA',
 TOLERANCE='20%',
 MATERIAL='X6S',
 VOLTAGE='4V',
 VALUE='22UF',
 PRIM_FILE='./archive_libs/logical/q_cap/chips/chips.prt';

PART_NAME
 PC617_P0_1 'Q_CAP_C0805-22UF,4V,20%,X6S,CHA':;

SECTION_NUMBER 1
 '@S9S_MB_2U_LIB.S9S_MB_2U(SCH_1):PAGE257_I81@PURE_QUANTA.Q_CAP(CHIPS)':
 C_PATH='@s9s_mb_2u_lib.s9s_mb_2u(sch_1):page257_i81@pure_quanta.q_cap(chips)',
 P_PATH='@s9s_mb_2u_lib.s9s_mb_2u(sch_1):page271_i81@pure_quanta.q_cap(chips)',
 PATH='I81',
 DRAWING='@S9S_MB_2U_LIB.S9S_MB_2U(SCH_1):PAGE257',
 PHYS_PAGE='271',
 XY='(1875,5000)',
 ROT='0',
 VER='1',
 PACK_TYPE='C0805',
 LOCATION='PC617_P0_1',
 CDS_LIB='pure_quanta',
 CDS_PART_NAME='Q_CAP_C0805-22UF,4V,20%,X6S,CHA',
 TOLERANCE='20%',
 MATERIAL='X6S',
 VOLTAGE='4V',
 VALUE='22UF',
 PRIM_FILE='./archive_libs/logical/q_cap/chips/chips.prt';

PART_NAME
 PC618_P0_2 'Q_CAP_C0805-22UF,4V,20%,X6S,CHA':;

SECTION_NUMBER 1
 '@S9S_MB_2U_LIB.S9S_MB_2U(SCH_1):PAGE257_I59@PURE_QUANTA.Q_CAP(CHIPS)':
 C_PATH='@s9s_mb_2u_lib.s9s_mb_2u(sch_1):page257_i59@pure_quanta.q_cap(chips)',
 P_PATH='@s9s_mb_2u_lib.s9s_mb_2u(sch_1):page271_i59@pure_quanta.q_cap(chips)',
 PATH='I59',
 DRAWING='@S9S_MB_2U_LIB.S9S_MB_2U(SCH_1):PAGE257',
 PHYS_PAGE='271',
 XY='(1875,2200)',
 ROT='0',
 VER='1',
 PACK_TYPE='C0805',
 LOCATION='PC618_P0_2',
 CDS_LIB='pure_quanta',
 CDS_PART_NAME='Q_CAP_C0805-22UF,4V,20%,X6S,CHA',
 TOLERANCE='20%',
 MATERIAL='X6S',
 VOLTAGE='4V',
 VALUE='22UF',
 PRIM_FILE='./archive_libs/logical/q_cap/chips/chips.prt';

PART_NAME
 PC619 'Q_CAPP_THLF-560UF,2.5V,20%,OSCA':;

SECTION_NUMBER 1
 '@S9S_MB_2U_LIB.S9S_MB_2U(SCH_1):PAGE257_I57@PURE_QUANTA.Q_CAPP(CHIPS)':
 C_PATH='@s9s_mb_2u_lib.s9s_mb_2u(sch_1):page257_i57@pure_quanta.q_capp(chips)',
 P_PATH='@s9s_mb_2u_lib.s9s_mb_2u(sch_1):page271_i57@pure_quanta.q_capp(chips)',
 PATH='I57',
 DRAWING='@S9S_MB_2U_LIB.S9S_MB_2U(SCH_1):PAGE257',
 PHYS_PAGE='271',
 XY='(1175,3325)',
 ROT='0',
 VER='1',
 PACK_TYPE='THLF',
 LOCATION='PC619',
 CDS_LIB='pure_quanta',
 CDS_PART_NAME='Q_CAPP_THLF-560UF,2.5V,20%,OSCA',
 TOLERANCE='20%',
 MATERIAL='OSCON',
 VOLTAGE='2.5V',
 VALUE='560UF',
 PRIM_FILE='./archive_libs/logical/q_capp/chips/chips.prt';

PART_NAME
 PC620 'Q_CAPP_THLF-560UF,2.5V,20%,OSCA':;

SECTION_NUMBER 1
 '@S9S_MB_2U_LIB.S9S_MB_2U(SCH_1):PAGE257_I58@PURE_QUANTA.Q_CAPP(CHIPS)':
 C_PATH='@s9s_mb_2u_lib.s9s_mb_2u(sch_1):page257_i58@pure_quanta.q_capp(chips)',
 P_PATH='@s9s_mb_2u_lib.s9s_mb_2u(sch_1):page271_i58@pure_quanta.q_capp(chips)',
 PATH='I58',
 DRAWING='@S9S_MB_2U_LIB.S9S_MB_2U(SCH_1):PAGE257',
 PHYS_PAGE='271',
 XY='(1700,3325)',
 ROT='0',
 VER='1',
 PACK_TYPE='THLF',
 LOCATION='PC620',
 CDS_LIB='pure_quanta',
 CDS_PART_NAME='Q_CAPP_THLF-560UF,2.5V,20%,OSCA',
 TOLERANCE='20%',
 MATERIAL='OSCON',
 VOLTAGE='2.5V',
 VALUE='560UF',
 PRIM_FILE='./archive_libs/logical/q_capp/chips/chips.prt';

PART_NAME
 PC621 'Q_CAPP_THLF-560UF,2.5V,20%,OSCA':;

SECTION_NUMBER 1
 '@S9S_MB_2U_LIB.S9S_MB_2U(SCH_1):PAGE257_I62@PURE_QUANTA.Q_CAPP(CHIPS)':
 C_PATH='@s9s_mb_2u_lib.s9s_mb_2u(sch_1):page257_i62@pure_quanta.q_capp(chips)',
 P_PATH='@s9s_mb_2u_lib.s9s_mb_2u(sch_1):page271_i62@pure_quanta.q_capp(chips)',
 PATH='I62',
 DRAWING='@S9S_MB_2U_LIB.S9S_MB_2U(SCH_1):PAGE257',
 PHYS_PAGE='271',
 XY='(2225,3325)',
 ROT='0',
 VER='1',
 PACK_TYPE='THLF',
 LOCATION='PC621',
 CDS_LIB='pure_quanta',
 CDS_PART_NAME='Q_CAPP_THLF-560UF,2.5V,20%,OSCA',
 TOLERANCE='20%',
 MATERIAL='OSCON',
 VOLTAGE='2.5V',
 VALUE='560UF',
 PRIM_FILE='./archive_libs/logical/q_capp/chips/chips.prt';

PART_NAME
 PC621_P1_1 'Q_CAP_C0402-100NF,50V,10%,X7R,A':;

SECTION_NUMBER 1
 '@S9S_MB_2U_LIB.S9S_MB_2U(SCH_1):PAGE275_I60@PURE_QUANTA.Q_CAP(CHIPS)':
 C_PATH='@s9s_mb_2u_lib.s9s_mb_2u(sch_1):page275_i60@pure_quanta.q_cap(chips)',
 P_PATH='@s9s_mb_2u_lib.s9s_mb_2u(sch_1):page289_i60@pure_quanta.q_cap(chips)',
 PATH='I60',
 DRAWING='@S9S_MB_2U_LIB.S9S_MB_2U(SCH_1):PAGE275',
 PHYS_PAGE='289',
 XY='(-5050,4475)',
 ROT='0',
 VER='1',
 PACK_TYPE='C0402',
 LOCATION='PC621_P1_1',
 CDS_LIB='pure_quanta',
 CDS_PART_NAME='Q_CAP_C0402-100NF,50V,10%,X7R,A',
 TOLERANCE='10%',
 MATERIAL='X7R',
 VOLTAGE='50V',
 VALUE='100NF',
 PRIM_FILE='./archive_libs/logical/q_cap/chips/chips.prt';

PART_NAME
 PC622 'Q_CAPP_THLF-270UF,16V,20%,OSCOA':;

SECTION_NUMBER 1
 '@S9S_MB_2U_LIB.S9S_MB_2U(SCH_1):PAGE257_I88@PURE_QUANTA.Q_CAPP(CHIPS)':
 C_PATH='@s9s_mb_2u_lib.s9s_mb_2u(sch_1):page257_i88@pure_quanta.q_capp(chips)',
 P_PATH='@s9s_mb_2u_lib.s9s_mb_2u(sch_1):page271_i88@pure_quanta.q_capp(chips)',
 PATH='I88',
 DRAWING='@S9S_MB_2U_LIB.S9S_MB_2U(SCH_1):PAGE257',
 PHYS_PAGE='271',
 XY='(2900,5850)',
 ROT='0',
 VER='1',
 PACK_TYPE='THLF',
 LOCATION='PC622',
 CDS_LIB='pure_quanta',
 CDS_PART_NAME='Q_CAPP_THLF-270UF,16V,20%,OSCOA',
 TOLERANCE='20%',
 MATERIAL='OSCON',
 VOLTAGE='16V',
 VALUE='270UF',
 PRIM_FILE='./archive_libs/logical/q_capp/chips/chips.prt';

PART_NAME
 PC623 'Q_CAPP_SMLF-330UF,2.5V,+10/-35B':;

SECTION_NUMBER 1
 '@S9S_MB_2U_LIB.S9S_MB_2U(SCH_1):PAGE257_I63@PURE_QUANTA.Q_CAPP(CHIPS)':
 C_PATH='@s9s_mb_2u_lib.s9s_mb_2u(sch_1):page257_i63@pure_quanta.q_capp(chips)',
 P_PATH='@s9s_mb_2u_lib.s9s_mb_2u(sch_1):page271_i63@pure_quanta.q_capp(chips)',
 PATH='I63',
 DRAWING='@S9S_MB_2U_LIB.S9S_MB_2U(SCH_1):PAGE257',
 PHYS_PAGE='271',
 XY='(2725,3325)',
 ROT='0',
 VER='1',
 PACK_TYPE='SMLF',
 LOCATION='PC623',
 CDS_LIB='pure_quanta',
 CDS_PART_NAME='Q_CAPP_SMLF-330UF,2.5V,+10/-35B',
 TOLERANCE='+10/-35%',
 MATERIAL='SPCAP',
 VOLTAGE='2.5V',
 VALUE='330UF',
 PRIM_FILE='./archive_libs/logical/q_capp/chips/chips.prt';

PART_NAME
 PC624 'Q_CAP_0402-0.1UF,25V,10%,X7R,CA':;

SECTION_NUMBER 1
 '@S9S_MB_2U_LIB.S9S_MB_2U(SCH_1):PAGE264_I9@PURE_QUANTA.Q_CAP(CHIPS)':
 C_PATH='@s9s_mb_2u_lib.s9s_mb_2u(sch_1):page264_i9@pure_quanta.q_cap(chips)',
 P_PATH='@s9s_mb_2u_lib.s9s_mb_2u(sch_1):page278_i9@pure_quanta.q_cap(chips)',
 PATH='I9',
 DRAWING='@S9S_MB_2U_LIB.S9S_MB_2U(SCH_1):PAGE264',
 PHYS_PAGE='278',
 XY='(-9225,3175)',
 ROT='0',
 VER='1',
 PACK_TYPE='0402',
 LOCATION='PC624',
 CDS_LIB='pure_quanta',
 CDS_PART_NAME='Q_CAP_0402-0.1UF,25V,10%,X7R,CA',
 TOLERANCE='10%',
 MATERIAL='X7R',
 VOLTAGE='25V',
 VALUE='0.1UF',
 PRIM_FILE='./archive_libs/logical/q_cap/chips/chips.prt';

PART_NAME
 PC627 'Q_CAP_0402-3300PF,50V,10%,X7R,A':;

SECTION_NUMBER 1
 '@S9S_MB_2U_LIB.S9S_MB_2U(SCH_1):PAGE264_I37@PURE_QUANTA.Q_CAP(CHIPS)':
 C_PATH='@s9s_mb_2u_lib.s9s_mb_2u(sch_1):page264_i37@pure_quanta.q_cap(chips)',
 P_PATH='@s9s_mb_2u_lib.s9s_mb_2u(sch_1):page278_i37@pure_quanta.q_cap(chips)',
 PATH='I37',
 DRAWING='@S9S_MB_2U_LIB.S9S_MB_2U(SCH_1):PAGE264',
 PHYS_PAGE='278',
 XY='(-9000,6775)',
 ROT='0',
 VER='1',
 PACK_TYPE='0402',
 LOCATION='PC627',
 CDS_LIB='pure_quanta',
 CDS_PART_NAME='Q_CAP_0402-3300PF,50V,10%,X7R,A',
 TOLERANCE='10%',
 MATERIAL='X7R',
 VOLTAGE='50V',
 VALUE='3300PF',
 PRIM_FILE='./archive_libs/logical/q_cap/chips/chips.prt';

PART_NAME
 PC628 'Q_CAP_0402-0.1UF,25V,10%,X7R,CA':;

SECTION_NUMBER 1
 '@S9S_MB_2U_LIB.S9S_MB_2U(SCH_1):PAGE264_I50@PURE_QUANTA.Q_CAP(CHIPS)':
 C_PATH='@s9s_mb_2u_lib.s9s_mb_2u(sch_1):page264_i50@pure_quanta.q_cap(chips)',
 P_PATH='@s9s_mb_2u_lib.s9s_mb_2u(sch_1):page278_i50@pure_quanta.q_cap(chips)',
 PATH='I50',
 DRAWING='@S9S_MB_2U_LIB.S9S_MB_2U(SCH_1):PAGE264',
 PHYS_PAGE='278',
 XY='(-8475,3175)',
 ROT='0',
 VER='1',
 PACK_TYPE='0402',
 LOCATION='PC628',
 CDS_LIB='pure_quanta',
 CDS_PART_NAME='Q_CAP_0402-0.1UF,25V,10%,X7R,CA',
 TOLERANCE='10%',
 MATERIAL='X7R',
 VOLTAGE='25V',
 VALUE='0.1UF',
 PRIM_FILE='./archive_libs/logical/q_cap/chips/chips.prt';

PART_NAME
 PC629 'Q_CAP_C0402-100NF,50V,10%,EMPTA':;

SECTION_NUMBER 1
 '@S9S_MB_2U_LIB.S9S_MB_2U(SCH_1):PAGE264_I72@PURE_QUANTA.Q_CAP(CHIPS)':
 C_PATH='@s9s_mb_2u_lib.s9s_mb_2u(sch_1):page264_i72@pure_quanta.q_cap(chips)',
 P_PATH='@s9s_mb_2u_lib.s9s_mb_2u(sch_1):page278_i72@pure_quanta.q_cap(chips)',
 PATH='I72',
 DRAWING='@S9S_MB_2U_LIB.S9S_MB_2U(SCH_1):PAGE264',
 PHYS_PAGE='278',
 XY='(-6225,8750)',
 ROT='0',
 VER='1',
 PACK_TYPE='C0402',
 LOCATION='PC629',
 CDS_LIB='pure_quanta',
 CDS_PART_NAME='Q_CAP_C0402-100NF,50V,10%,EMPTA',
 TOLERANCE='10%',
 MATERIAL='EMPTY',
 VOLTAGE='50V',
 VALUE='100NF',
 PRIM_FILE='./archive_libs/logical/q_cap/chips/chips.prt';

PART_NAME
 PC630 'Q_CAP_C0402-10UF,6.3V,20%,X6S,B':;

SECTION_NUMBER 1
 '@S9S_MB_2U_LIB.S9S_MB_2U(SCH_1):PAGE264_I70@PURE_QUANTA.Q_CAP(CHIPS)':
 C_PATH='@s9s_mb_2u_lib.s9s_mb_2u(sch_1):page264_i70@pure_quanta.q_cap(chips)',
 P_PATH='@s9s_mb_2u_lib.s9s_mb_2u(sch_1):page278_i70@pure_quanta.q_cap(chips)',
 PATH='I70',
 DRAWING='@S9S_MB_2U_LIB.S9S_MB_2U(SCH_1):PAGE264',
 PHYS_PAGE='278',
 XY='(-6225,8275)',
 ROT='0',
 VER='1',
 PACK_TYPE='C0402',
 LOCATION='PC630',
 CDS_LIB='pure_quanta',
 CDS_PART_NAME='Q_CAP_C0402-10UF,6.3V,20%,X6S,B',
 TOLERANCE='20%',
 MATERIAL='X6S',
 VOLTAGE='6.3V',
 VALUE='10UF',
 PRIM_FILE='./archive_libs/logical/q_cap/chips/chips.prt';

PART_NAME
 PC631 'Q_CAP_0402-470PF,50V,10%,X7R,TA':;

SECTION_NUMBER 1
 '@S9S_MB_2U_LIB.S9S_MB_2U(SCH_1):PAGE264_I56@PURE_QUANTA.Q_CAP(CHIPS)':
 C_PATH='@s9s_mb_2u_lib.s9s_mb_2u(sch_1):page264_i56@pure_quanta.q_cap(chips)',
 P_PATH='@s9s_mb_2u_lib.s9s_mb_2u(sch_1):page278_i56@pure_quanta.q_cap(chips)',
 PATH='I56',
 DRAWING='@S9S_MB_2U_LIB.S9S_MB_2U(SCH_1):PAGE264',
 PHYS_PAGE='278',
 XY='(-5850,3550)',
 ROT='0',
 VER='1',
 PACK_TYPE='0402',
 LOCATION='PC631',
 CDS_LIB='pure_quanta',
 CDS_PART_NAME='Q_CAP_0402-470PF,50V,10%,X7R,TA',
 TOLERANCE='10%',
 MATERIAL='X7R',
 VOLTAGE='50V',
 VALUE='470PF',
 PRIM_FILE='./archive_libs/logical/q_cap/chips/chips.prt';

PART_NAME
 PC632 'Q_CAP_C0402-1UF,16V,10%,X6S,CHA':;

SECTION_NUMBER 1
 '@S9S_MB_2U_LIB.S9S_MB_2U(SCH_1):PAGE264_I73@PURE_QUANTA.Q_CAP(CHIPS)':
 C_PATH='@s9s_mb_2u_lib.s9s_mb_2u(sch_1):page264_i73@pure_quanta.q_cap(chips)',
 P_PATH='@s9s_mb_2u_lib.s9s_mb_2u(sch_1):page278_i73@pure_quanta.q_cap(chips)',
 PATH='I73',
 DRAWING='@S9S_MB_2U_LIB.S9S_MB_2U(SCH_1):PAGE264',
 PHYS_PAGE='278',
 XY='(-5825,8750)',
 ROT='0',
 VER='1',
 PACK_TYPE='C0402',
 LOCATION='PC632',
 CDS_LIB='pure_quanta',
 CDS_PART_NAME='Q_CAP_C0402-1UF,16V,10%,X6S,CHA',
 TOLERANCE='10%',
 MATERIAL='X6S',
 VOLTAGE='16V',
 VALUE='1UF',
 PRIM_FILE='./archive_libs/logical/q_cap/chips/chips.prt';

PART_NAME
 PC633 'Q_CAP_C0402-2.2UF,10V,10%,X6S,A':;

SECTION_NUMBER 1
 '@S9S_MB_2U_LIB.S9S_MB_2U(SCH_1):PAGE265_I11@PURE_QUANTA.Q_CAP(CHIPS)':
 C_PATH='@s9s_mb_2u_lib.s9s_mb_2u(sch_1):page265_i11@pure_quanta.q_cap(chips)',
 P_PATH='@s9s_mb_2u_lib.s9s_mb_2u(sch_1):page279_i11@pure_quanta.q_cap(chips)',
 PATH='I11',
 DRAWING='@S9S_MB_2U_LIB.S9S_MB_2U(SCH_1):PAGE265',
 PHYS_PAGE='279',
 XY='(-8225,2375)',
 ROT='0',
 VER='1',
 PACK_TYPE='C0402',
 LOCATION='PC633',
 CDS_LIB='pure_quanta',
 CDS_PART_NAME='Q_CAP_C0402-2.2UF,10V,10%,X6S,A',
 TOLERANCE='10%',
 MATERIAL='X6S',
 VOLTAGE='10V',
 VALUE='2.2UF',
 PRIM_FILE='./archive_libs/logical/q_cap/chips/chips.prt';

PART_NAME
 PC634 'Q_CAP_0402-3300PF,50V,10%,X7R,A':;

SECTION_NUMBER 1
 '@S9S_MB_2U_LIB.S9S_MB_2U(SCH_1):PAGE265_I18@PURE_QUANTA.Q_CAP(CHIPS)':
 C_PATH='@s9s_mb_2u_lib.s9s_mb_2u(sch_1):page265_i18@pure_quanta.q_cap(chips)',
 P_PATH='@s9s_mb_2u_lib.s9s_mb_2u(sch_1):page279_i18@pure_quanta.q_cap(chips)',
 PATH='I18',
 DRAWING='@S9S_MB_2U_LIB.S9S_MB_2U(SCH_1):PAGE265',
 PHYS_PAGE='279',
 XY='(-5900,2825)',
 ROT='0',
 VER='1',
 PACK_TYPE='0402',
 LOCATION='PC634',
 CDS_LIB='pure_quanta',
 CDS_PART_NAME='Q_CAP_0402-3300PF,50V,10%,X7R,A',
 TOLERANCE='10%',
 MATERIAL='X7R',
 VOLTAGE='50V',
 VALUE='3300PF',
 PRIM_FILE='./archive_libs/logical/q_cap/chips/chips.prt';

PART_NAME
 PC635 'Q_CAP_C0402-1UF,16V,10%,X6S,CHA':;

SECTION_NUMBER 1
 '@S9S_MB_2U_LIB.S9S_MB_2U(SCH_1):PAGE265_I20@PURE_QUANTA.Q_CAP(CHIPS)':
 C_PATH='@s9s_mb_2u_lib.s9s_mb_2u(sch_1):page265_i20@pure_quanta.q_cap(chips)',
 P_PATH='@s9s_mb_2u_lib.s9s_mb_2u(sch_1):page279_i20@pure_quanta.q_cap(chips)',
 PATH='I20',
 DRAWING='@S9S_MB_2U_LIB.S9S_MB_2U(SCH_1):PAGE265',
 PHYS_PAGE='279',
 XY='(-5500,2825)',
 ROT='0',
 VER='1',
 PACK_TYPE='C0402',
 LOCATION='PC635',
 CDS_LIB='pure_quanta',
 CDS_PART_NAME='Q_CAP_C0402-1UF,16V,10%,X6S,CHA',
 TOLERANCE='10%',
 MATERIAL='X6S',
 VOLTAGE='16V',
 VALUE='1UF',
 PRIM_FILE='./archive_libs/logical/q_cap/chips/chips.prt';

PART_NAME
 PC636 'Q_CAP_C0402-100NF,50V,10%,X7R,A':;

SECTION_NUMBER 1
 '@S9S_MB_2U_LIB.S9S_MB_2U(SCH_1):PAGE265_I22@PURE_QUANTA.Q_CAP(CHIPS)':
 C_PATH='@s9s_mb_2u_lib.s9s_mb_2u(sch_1):page265_i22@pure_quanta.q_cap(chips)',
 P_PATH='@s9s_mb_2u_lib.s9s_mb_2u(sch_1):page279_i22@pure_quanta.q_cap(chips)',
 PATH='I22',
 DRAWING='@S9S_MB_2U_LIB.S9S_MB_2U(SCH_1):PAGE265',
 PHYS_PAGE='279',
 XY='(-4675,2200)',
 ROT='2',
 VER='1',
 PACK_TYPE='C0402',
 LOCATION='PC636',
 CDS_LIB='pure_quanta',
 CDS_PART_NAME='Q_CAP_C0402-100NF,50V,10%,X7R,A',
 TOLERANCE='10%',
 MATERIAL='X7R',
 VOLTAGE='50V',
 VALUE='100NF',
 PRIM_FILE='./archive_libs/logical/q_cap/chips/chips.prt';

PART_NAME
 PC637 'Q_CAP_C0805-22UF,16V,20%,X6S,CA':;

SECTION_NUMBER 1
 '@S9S_MB_2U_LIB.S9S_MB_2U(SCH_1):PAGE265_I21@PURE_QUANTA.Q_CAP(CHIPS)':
 C_PATH='@s9s_mb_2u_lib.s9s_mb_2u(sch_1):page265_i21@pure_quanta.q_cap(chips)',
 P_PATH='@s9s_mb_2u_lib.s9s_mb_2u(sch_1):page279_i21@pure_quanta.q_cap(chips)',
 PATH='I21',
 DRAWING='@S9S_MB_2U_LIB.S9S_MB_2U(SCH_1):PAGE265',
 PHYS_PAGE='279',
 XY='(-5100,2825)',
 ROT='0',
 VER='1',
 PACK_TYPE='C0805',
 LOCATION='PC637',
 CDS_LIB='pure_quanta',
 CDS_PART_NAME='Q_CAP_C0805-22UF,16V,20%,X6S,CA',
 TOLERANCE='20%',
 MATERIAL='X6S',
 VOLTAGE='16V',
 VALUE='22UF',
 PRIM_FILE='./archive_libs/logical/q_cap/chips/chips.prt';

PART_NAME
 PC638 'Q_CAP_C0805-22UF,16V,20%,X6S,CA':;

SECTION_NUMBER 1
 '@S9S_MB_2U_LIB.S9S_MB_2U(SCH_1):PAGE265_I23@PURE_QUANTA.Q_CAP(CHIPS)':
 C_PATH='@s9s_mb_2u_lib.s9s_mb_2u(sch_1):page265_i23@pure_quanta.q_cap(chips)',
 P_PATH='@s9s_mb_2u_lib.s9s_mb_2u(sch_1):page279_i23@pure_quanta.q_cap(chips)',
 PATH='I23',
 DRAWING='@S9S_MB_2U_LIB.S9S_MB_2U(SCH_1):PAGE265',
 PHYS_PAGE='279',
 XY='(-4700,2825)',
 ROT='0',
 VER='1',
 PACK_TYPE='C0805',
 LOCATION='PC638',
 CDS_LIB='pure_quanta',
 CDS_PART_NAME='Q_CAP_C0805-22UF,16V,20%,X6S,CA',
 TOLERANCE='20%',
 MATERIAL='X6S',
 VOLTAGE='16V',
 VALUE='22UF',
 PRIM_FILE='./archive_libs/logical/q_cap/chips/chips.prt';

PART_NAME
 PC639 'Q_CAP_C0402-100NF,50V,10%,X7R,A':;

SECTION_NUMBER 1
 '@S9S_MB_2U_LIB.S9S_MB_2U(SCH_1):PAGE265_I24@PURE_QUANTA.Q_CAP(CHIPS)':
 C_PATH='@s9s_mb_2u_lib.s9s_mb_2u(sch_1):page265_i24@pure_quanta.q_cap(chips)',
 P_PATH='@s9s_mb_2u_lib.s9s_mb_2u(sch_1):page279_i24@pure_quanta.q_cap(chips)',
 PATH='I24',
 DRAWING='@S9S_MB_2U_LIB.S9S_MB_2U(SCH_1):PAGE265',
 PHYS_PAGE='279',
 XY='(-3750,1725)',
 ROT='0',
 VER='1',
 PACK_TYPE='C0402',
 LOCATION='PC639',
 CDS_LIB='pure_quanta',
 CDS_PART_NAME='Q_CAP_C0402-100NF,50V,10%,X7R,A',
 TOLERANCE='10%',
 MATERIAL='X7R',
 VOLTAGE='50V',
 VALUE='100NF',
 PRIM_FILE='./archive_libs/logical/q_cap/chips/chips.prt';

PART_NAME
 PC641 'Q_CAP_C0805-22UF,4V,20%,X6S,CHA':;

SECTION_NUMBER 1
 '@S9S_MB_2U_LIB.S9S_MB_2U(SCH_1):PAGE265_I25@PURE_QUANTA.Q_CAP(CHIPS)':
 C_PATH='@s9s_mb_2u_lib.s9s_mb_2u(sch_1):page265_i25@pure_quanta.q_cap(chips)',
 P_PATH='@s9s_mb_2u_lib.s9s_mb_2u(sch_1):page279_i25@pure_quanta.q_cap(chips)',
 PATH='I25',
 DRAWING='@S9S_MB_2U_LIB.S9S_MB_2U(SCH_1):PAGE265',
 PHYS_PAGE='279',
 XY='(-3350,1725)',
 ROT='0',
 VER='1',
 PACK_TYPE='C0805',
 LOCATION='PC641',
 CDS_LIB='pure_quanta',
 CDS_PART_NAME='Q_CAP_C0805-22UF,4V,20%,X6S,CHA',
 TOLERANCE='20%',
 MATERIAL='X6S',
 VOLTAGE='4V',
 VALUE='22UF',
 PRIM_FILE='./archive_libs/logical/q_cap/chips/chips.prt';

PART_NAME
 PC642 'Q_CAP_C0805-22UF,4V,20%,X6S,CHA':;

SECTION_NUMBER 1
 '@S9S_MB_2U_LIB.S9S_MB_2U(SCH_1):PAGE265_I28@PURE_QUANTA.Q_CAP(CHIPS)':
 C_PATH='@s9s_mb_2u_lib.s9s_mb_2u(sch_1):page265_i28@pure_quanta.q_cap(chips)',
 P_PATH='@s9s_mb_2u_lib.s9s_mb_2u(sch_1):page279_i28@pure_quanta.q_cap(chips)',
 PATH='I28',
 DRAWING='@S9S_MB_2U_LIB.S9S_MB_2U(SCH_1):PAGE265',
 PHYS_PAGE='279',
 XY='(-2825,1725)',
 ROT='0',
 VER='1',
 PACK_TYPE='C0805',
 LOCATION='PC642',
 CDS_LIB='pure_quanta',
 CDS_PART_NAME='Q_CAP_C0805-22UF,4V,20%,X6S,CHA',
 TOLERANCE='20%',
 MATERIAL='X6S',
 VOLTAGE='4V',
 VALUE='22UF',
 PRIM_FILE='./archive_libs/logical/q_cap/chips/chips.prt';

PART_NAME
 PC644 'Q_CAP_C0402-1UF,25V,10%,X6S,CHA':;

SECTION_NUMBER 1
 '@S9S_MB_2U_LIB.S9S_MB_2U(SCH_1):PAGE285_I1@PURE_QUANTA.Q_CAP(CHIPS)':
 C_PATH='@s9s_mb_2u_lib.s9s_mb_2u(sch_1):page285_i1@pure_quanta.q_cap(chips)',
 P_PATH='@s9s_mb_2u_lib.s9s_mb_2u(sch_1):page299_i1@pure_quanta.q_cap(chips)',
 PATH='I1',
 DRAWING='@S9S_MB_2U_LIB.S9S_MB_2U(SCH_1):PAGE285',
 BOM_COST='VR_PCH',
 PHYS_PAGE='299',
 XY='(-10525,2200)',
 ROT='0',
 VER='1',
 PACK_TYPE='C0402',
 LOCATION='PC644',
 SEC='1',
 CDS_LIB='pure_quanta',
 CDS_PART_NAME='Q_CAP_C0402-1UF,25V,10%,X6S,CHA',
 SEC_TYPE='C0402',
 TOLERANCE='10%',
 MATERIAL='X6S',
 VOLTAGE='25V',
 VALUE='1UF',
 PRIM_FILE='./archive_libs/logical/q_cap/chips/chips.prt';

PART_NAME
 PC720_P0_1 'Q_CAP_C0805-22UF,16V,20%,X6S,CA':;

SECTION_NUMBER 1
 '@S9S_MB_2U_LIB.S9S_MB_2U(SCH_1):PAGE257_I73@PURE_QUANTA.Q_CAP(CHIPS)':
 C_PATH='@s9s_mb_2u_lib.s9s_mb_2u(sch_1):page257_i73@pure_quanta.q_cap(chips)',
 P_PATH='@s9s_mb_2u_lib.s9s_mb_2u(sch_1):page271_i73@pure_quanta.q_cap(chips)',
 PATH='I73',
 DRAWING='@S9S_MB_2U_LIB.S9S_MB_2U(SCH_1):PAGE257',
 PHYS_PAGE='271',
 XY='(-300,6125)',
 ROT='0',
 VER='1',
 PACK_TYPE='C0805',
 LOCATION='PC720_P0_1',
 CDS_LIB='pure_quanta',
 CDS_PART_NAME='Q_CAP_C0805-22UF,16V,20%,X6S,CA',
 TOLERANCE='20%',
 MATERIAL='X6S',
 VOLTAGE='16V',
 VALUE='22UF',
 PRIM_FILE='./archive_libs/logical/q_cap/chips/chips.prt';

PART_NAME
 PC721_P0_2 'Q_CAP_C0805-22UF,16V,20%,X6S,CA':;

SECTION_NUMBER 1
 '@S9S_MB_2U_LIB.S9S_MB_2U(SCH_1):PAGE257_I55@PURE_QUANTA.Q_CAP(CHIPS)':
 C_PATH='@s9s_mb_2u_lib.s9s_mb_2u(sch_1):page257_i55@pure_quanta.q_cap(chips)',
 P_PATH='@s9s_mb_2u_lib.s9s_mb_2u(sch_1):page271_i55@pure_quanta.q_cap(chips)',
 PATH='I55',
 DRAWING='@S9S_MB_2U_LIB.S9S_MB_2U(SCH_1):PAGE257',
 PHYS_PAGE='271',
 XY='(-250,3300)',
 ROT='0',
 VER='1',
 PACK_TYPE='C0805',
 LOCATION='PC721_P0_2',
 CDS_LIB='pure_quanta',
 CDS_PART_NAME='Q_CAP_C0805-22UF,16V,20%,X6S,CA',
 TOLERANCE='20%',
 MATERIAL='X6S',
 VOLTAGE='16V',
 VALUE='22UF',
 PRIM_FILE='./archive_libs/logical/q_cap/chips/chips.prt';

PART_NAME
 PC722_P0_3 'Q_CAP_C0805-22UF,16V,20%,X6S,CA':;

SECTION_NUMBER 1
 '@S9S_MB_2U_LIB.S9S_MB_2U(SCH_1):PAGE258_I53@PURE_QUANTA.Q_CAP(CHIPS)':
 C_PATH='@s9s_mb_2u_lib.s9s_mb_2u(sch_1):page258_i53@pure_quanta.q_cap(chips)',
 P_PATH='@s9s_mb_2u_lib.s9s_mb_2u(sch_1):page272_i53@pure_quanta.q_cap(chips)',
 PATH='I53',
 DRAWING='@S9S_MB_2U_LIB.S9S_MB_2U(SCH_1):PAGE258',
 PHYS_PAGE='272',
 XY='(-6725,5800)',
 ROT='0',
 VER='1',
 PACK_TYPE='C0805',
 LOCATION='PC722_P0_3',
 CDS_LIB='pure_quanta',
 CDS_PART_NAME='Q_CAP_C0805-22UF,16V,20%,X6S,CA',
 TOLERANCE='20%',
 MATERIAL='X6S',
 VOLTAGE='16V',
 VALUE='22UF',
 PRIM_FILE='./archive_libs/logical/q_cap/chips/chips.prt';

PART_NAME
 PC723_P0_4 'Q_CAP_C0805-22UF,16V,20%,X6S,CA':;

SECTION_NUMBER 1
 '@S9S_MB_2U_LIB.S9S_MB_2U(SCH_1):PAGE258_I41@PURE_QUANTA.Q_CAP(CHIPS)':
 C_PATH='@s9s_mb_2u_lib.s9s_mb_2u(sch_1):page258_i41@pure_quanta.q_cap(chips)',
 P_PATH='@s9s_mb_2u_lib.s9s_mb_2u(sch_1):page272_i41@pure_quanta.q_cap(chips)',
 PATH='I41',
 DRAWING='@S9S_MB_2U_LIB.S9S_MB_2U(SCH_1):PAGE258',
 PHYS_PAGE='272',
 XY='(-6725,3000)',
 ROT='0',
 VER='1',
 PACK_TYPE='C0805',
 LOCATION='PC723_P0_4',
 CDS_LIB='pure_quanta',
 CDS_PART_NAME='Q_CAP_C0805-22UF,16V,20%,X6S,CA',
 TOLERANCE='20%',
 MATERIAL='X6S',
 VOLTAGE='16V',
 VALUE='22UF',
 PRIM_FILE='./archive_libs/logical/q_cap/chips/chips.prt';

PART_NAME
 PC724_P1_1 'Q_CAP_C0805-22UF,16V,20%,X6S,CA':;

SECTION_NUMBER 1
 '@S9S_MB_2U_LIB.S9S_MB_2U(SCH_1):PAGE275_I58@PURE_QUANTA.Q_CAP(CHIPS)':
 C_PATH='@s9s_mb_2u_lib.s9s_mb_2u(sch_1):page275_i58@pure_quanta.q_cap(chips)',
 P_PATH='@s9s_mb_2u_lib.s9s_mb_2u(sch_1):page289_i58@pure_quanta.q_cap(chips)',
 PATH='I58',
 DRAWING='@S9S_MB_2U_LIB.S9S_MB_2U(SCH_1):PAGE275',
 PHYS_PAGE='289',
 XY='(-6275,5575)',
 ROT='0',
 VER='1',
 PACK_TYPE='C0805',
 LOCATION='PC724_P1_1',
 CDS_LIB='pure_quanta',
 CDS_PART_NAME='Q_CAP_C0805-22UF,16V,20%,X6S,CA',
 TOLERANCE='20%',
 MATERIAL='X6S',
 VOLTAGE='16V',
 VALUE='22UF',
 PRIM_FILE='./archive_libs/logical/q_cap/chips/chips.prt';

PART_NAME
 PC725_P1_2 'Q_CAP_C0805-22UF,16V,20%,X6S,CA':;

SECTION_NUMBER 1
 '@S9S_MB_2U_LIB.S9S_MB_2U(SCH_1):PAGE275_I46@PURE_QUANTA.Q_CAP(CHIPS)':
 C_PATH='@s9s_mb_2u_lib.s9s_mb_2u(sch_1):page275_i46@pure_quanta.q_cap(chips)',
 P_PATH='@s9s_mb_2u_lib.s9s_mb_2u(sch_1):page289_i46@pure_quanta.q_cap(chips)',
 PATH='I46',
 DRAWING='@S9S_MB_2U_LIB.S9S_MB_2U(SCH_1):PAGE275',
 PHYS_PAGE='289',
 XY='(-6275,2775)',
 ROT='0',
 VER='1',
 PACK_TYPE='C0805',
 LOCATION='PC725_P1_2',
 CDS_LIB='pure_quanta',
 CDS_PART_NAME='Q_CAP_C0805-22UF,16V,20%,X6S,CA',
 TOLERANCE='20%',
 MATERIAL='X6S',
 VOLTAGE='16V',
 VALUE='22UF',
 PRIM_FILE='./archive_libs/logical/q_cap/chips/chips.prt';

PART_NAME
 PC726_P1_3 'Q_CAP_C0805-22UF,16V,20%,X6S,CA':;

SECTION_NUMBER 1
 '@S9S_MB_2U_LIB.S9S_MB_2U(SCH_1):PAGE276_I60@PURE_QUANTA.Q_CAP(CHIPS)':
 C_PATH='@s9s_mb_2u_lib.s9s_mb_2u(sch_1):page276_i60@pure_quanta.q_cap(chips)',
 P_PATH='@s9s_mb_2u_lib.s9s_mb_2u(sch_1):page290_i60@pure_quanta.q_cap(chips)',
 PATH='I60',
 DRAWING='@S9S_MB_2U_LIB.S9S_MB_2U(SCH_1):PAGE276',
 PHYS_PAGE='290',
 XY='(-3350,7525)',
 ROT='0',
 VER='1',
 PACK_TYPE='C0805',
 LOCATION='PC726_P1_3',
 CDS_LIB='pure_quanta',
 CDS_PART_NAME='Q_CAP_C0805-22UF,16V,20%,X6S,CA',
 TOLERANCE='20%',
 MATERIAL='X6S',
 VOLTAGE='16V',
 VALUE='22UF',
 PRIM_FILE='./archive_libs/logical/q_cap/chips/chips.prt';

PART_NAME
 PC727_P1_4 'Q_CAP_C0805-22UF,16V,20%,X6S,CA':;

SECTION_NUMBER 1
 '@S9S_MB_2U_LIB.S9S_MB_2U(SCH_1):PAGE276_I52@PURE_QUANTA.Q_CAP(CHIPS)':
 C_PATH='@s9s_mb_2u_lib.s9s_mb_2u(sch_1):page276_i52@pure_quanta.q_cap(chips)',
 P_PATH='@s9s_mb_2u_lib.s9s_mb_2u(sch_1):page290_i52@pure_quanta.q_cap(chips)',
 PATH='I52',
 DRAWING='@S9S_MB_2U_LIB.S9S_MB_2U(SCH_1):PAGE276',
 PHYS_PAGE='290',
 XY='(-3350,4725)',
 ROT='0',
 VER='1',
 PACK_TYPE='C0805',
 LOCATION='PC727_P1_4',
 CDS_LIB='pure_quanta',
 CDS_PART_NAME='Q_CAP_C0805-22UF,16V,20%,X6S,CA',
 TOLERANCE='20%',
 MATERIAL='X6S',
 VOLTAGE='16V',
 VALUE='22UF',
 PRIM_FILE='./archive_libs/logical/q_cap/chips/chips.prt';

PART_NAME
 PC813 'Q_CAP_C0402-1UF,16V,10%,X6S,CHA':;

SECTION_NUMBER 1
 '@S9S_MB_2U_LIB.S9S_MB_2U(SCH_1):PAGE264_I51@PURE_QUANTA.Q_CAP(CHIPS)':
 C_PATH='@s9s_mb_2u_lib.s9s_mb_2u(sch_1):page264_i51@pure_quanta.q_cap(chips)',
 P_PATH='@s9s_mb_2u_lib.s9s_mb_2u(sch_1):page278_i51@pure_quanta.q_cap(chips)',
 PATH='I51',
 DRAWING='@S9S_MB_2U_LIB.S9S_MB_2U(SCH_1):PAGE264',
 PHYS_PAGE='278',
 XY='(-8575,3550)',
 ROT='0',
 VER='2',
 PACK_TYPE='C0402',
 LOCATION='PC813',
 CDS_LIB='pure_quanta',
 CDS_PART_NAME='Q_CAP_C0402-1UF,16V,10%,X6S,CHA',
 TOLERANCE='10%',
 MATERIAL='X6S',
 VOLTAGE='16V',
 VALUE='1UF',
 PRIM_FILE='./archive_libs/logical/q_cap/chips/chips.prt';

PART_NAME
 PC814 'Q_CAP_C0402-1UF,16V,10%,X6S,CHA':;

SECTION_NUMBER 1
 '@S9S_MB_2U_LIB.S9S_MB_2U(SCH_1):PAGE282_I51@PURE_QUANTA.Q_CAP(CHIPS)':
 C_PATH='@s9s_mb_2u_lib.s9s_mb_2u(sch_1):page282_i51@pure_quanta.q_cap(chips)',
 P_PATH='@s9s_mb_2u_lib.s9s_mb_2u(sch_1):page296_i51@pure_quanta.q_cap(chips)',
 PATH='I51',
 DRAWING='@S9S_MB_2U_LIB.S9S_MB_2U(SCH_1):PAGE282',
 PHYS_PAGE='296',
 XY='(-4125,50)',
 ROT='0',
 VER='2',
 PACK_TYPE='C0402',
 LOCATION='PC814',
 CDS_LIB='pure_quanta',
 CDS_PART_NAME='Q_CAP_C0402-1UF,16V,10%,X6S,CHA',
 TOLERANCE='10%',
 MATERIAL='X6S',
 VOLTAGE='16V',
 VALUE='1UF',
 PRIM_FILE='./archive_libs/logical/q_cap/chips/chips.prt';

PART_NAME
 PC831 'Q_CAP_C0805-22UF,16V,20%,X6S,CA':;

SECTION_NUMBER 1
 '@S9S_MB_2U_LIB.S9S_MB_2U(SCH_1):PAGE267_I7@PURE_QUANTA.Q_CAP(CHIPS)':
 C_PATH='@s9s_mb_2u_lib.s9s_mb_2u(sch_1):page267_i7@pure_quanta.q_cap(chips)',
 P_PATH='@s9s_mb_2u_lib.s9s_mb_2u(sch_1):page281_i7@pure_quanta.q_cap(chips)',
 PATH='I7',
 DRAWING='@S9S_MB_2U_LIB.S9S_MB_2U(SCH_1):PAGE267',
 BOM_COST='VR_PCH',
 PHYS_PAGE='281',
 XY='(-11425,4350)',
 ROT='0',
 VER='1',
 PACK_TYPE='C0805',
 LOCATION='PC831',
 CDS_LIB='pure_quanta',
 CDS_PART_NAME='Q_CAP_C0805-22UF,16V,20%,X6S,CA',
 TOLERANCE='20%',
 MATERIAL='X6S',
 VOLTAGE='16V',
 VALUE='22UF',
 PRIM_FILE='./archive_libs/logical/q_cap/chips/chips.prt';

PART_NAME
 PC1171 'Q_CAP_C0402-2.2UF,10V,10%,X6S,A':;

SECTION_NUMBER 1
 '@S9S_MB_2U_LIB.S9S_MB_2U(SCH_1):PAGE258_I23@PURE_QUANTA.Q_CAP(CHIPS)':
 C_PATH='@s9s_mb_2u_lib.s9s_mb_2u(sch_1):page258_i23@pure_quanta.q_cap(chips)',
 P_PATH='@s9s_mb_2u_lib.s9s_mb_2u(sch_1):page272_i23@pure_quanta.q_cap(chips)',
 PATH='I23',
 DRAWING='@S9S_MB_2U_LIB.S9S_MB_2U(SCH_1):PAGE258',
 PHYS_PAGE='272',
 XY='(-10700,5350)',
 ROT='0',
 VER='1',
 PACK_TYPE='C0402',
 LOCATION='PC1171',
 CDS_LIB='pure_quanta',
 CDS_PART_NAME='Q_CAP_C0402-2.2UF,10V,10%,X6S,A',
 TOLERANCE='10%',
 MATERIAL='X6S',
 VOLTAGE='10V',
 VALUE='2.2UF',
 PRIM_FILE='./archive_libs/logical/q_cap/chips/chips.prt';

PART_NAME
 PC1172 'Q_CAP_C0402-2.2UF,10V,10%,X6S,A':;

SECTION_NUMBER 1
 '@S9S_MB_2U_LIB.S9S_MB_2U(SCH_1):PAGE258_I13@PURE_QUANTA.Q_CAP(CHIPS)':
 C_PATH='@s9s_mb_2u_lib.s9s_mb_2u(sch_1):page258_i13@pure_quanta.q_cap(chips)',
 P_PATH='@s9s_mb_2u_lib.s9s_mb_2u(sch_1):page272_i13@pure_quanta.q_cap(chips)',
 PATH='I13',
 DRAWING='@S9S_MB_2U_LIB.S9S_MB_2U(SCH_1):PAGE258',
 PHYS_PAGE='272',
 XY='(-10700,2550)',
 ROT='0',
 VER='1',
 PACK_TYPE='C0402',
 LOCATION='PC1172',
 CDS_LIB='pure_quanta',
 CDS_PART_NAME='Q_CAP_C0402-2.2UF,10V,10%,X6S,A',
 TOLERANCE='10%',
 MATERIAL='X6S',
 VOLTAGE='10V',
 VALUE='2.2UF',
 PRIM_FILE='./archive_libs/logical/q_cap/chips/chips.prt';

PART_NAME
 PC1173 'Q_CAP_C0402-1UF,16V,10%,X6S,CHA':;

SECTION_NUMBER 1
 '@S9S_MB_2U_LIB.S9S_MB_2U(SCH_1):PAGE252_I87@PURE_QUANTA.Q_CAP(CHIPS)':
 C_PATH='@s9s_mb_2u_lib.s9s_mb_2u(sch_1):page252_i87@pure_quanta.q_cap(chips)',
 P_PATH='@s9s_mb_2u_lib.s9s_mb_2u(sch_1):page266_i87@pure_quanta.q_cap(chips)',
 PATH='I87',
 DRAWING='@S9S_MB_2U_LIB.S9S_MB_2U(SCH_1):PAGE252',
 PHYS_PAGE='266',
 XY='(-1100,5875)',
 ROT='0',
 VER='1',
 PACK_TYPE='C0402',
 LOCATION='PC1173',
 CDS_LIB='pure_quanta',
 CDS_PART_NAME='Q_CAP_C0402-1UF,16V,10%,X6S,CHA',
 TOLERANCE='10%',
 MATERIAL='X6S',
 VOLTAGE='16V',
 VALUE='1UF',
 PRIM_FILE='./archive_libs/logical/q_cap/chips/chips.prt';

PART_NAME
 PC1173_P0_3 'Q_CAP_0402-3300PF,50V,10%,X7R,A':;

SECTION_NUMBER 1
 '@S9S_MB_2U_LIB.S9S_MB_2U(SCH_1):PAGE258_I44@PURE_QUANTA.Q_CAP(CHIPS)':
 C_PATH='@s9s_mb_2u_lib.s9s_mb_2u(sch_1):page258_i44@pure_quanta.q_cap(chips)',
 P_PATH='@s9s_mb_2u_lib.s9s_mb_2u(sch_1):page272_i44@pure_quanta.q_cap(chips)',
 PATH='I44',
 DRAWING='@S9S_MB_2U_LIB.S9S_MB_2U(SCH_1):PAGE258',
 PHYS_PAGE='272',
 XY='(-8375,5800)',
 ROT='0',
 VER='1',
 PACK_TYPE='0402',
 LOCATION='PC1173_P0_3',
 CDS_LIB='pure_quanta',
 CDS_PART_NAME='Q_CAP_0402-3300PF,50V,10%,X7R,A',
 TOLERANCE='10%',
 MATERIAL='X7R',
 VOLTAGE='50V',
 VALUE='3300PF',
 PRIM_FILE='./archive_libs/logical/q_cap/chips/chips.prt';

PART_NAME
 PC1174_P0_4 'Q_CAP_0402-3300PF,50V,10%,X7R,A':;

SECTION_NUMBER 1
 '@S9S_MB_2U_LIB.S9S_MB_2U(SCH_1):PAGE258_I31@PURE_QUANTA.Q_CAP(CHIPS)':
 C_PATH='@s9s_mb_2u_lib.s9s_mb_2u(sch_1):page258_i31@pure_quanta.q_cap(chips)',
 P_PATH='@s9s_mb_2u_lib.s9s_mb_2u(sch_1):page272_i31@pure_quanta.q_cap(chips)',
 PATH='I31',
 DRAWING='@S9S_MB_2U_LIB.S9S_MB_2U(SCH_1):PAGE258',
 PHYS_PAGE='272',
 XY='(-8375,3000)',
 ROT='0',
 VER='1',
 PACK_TYPE='0402',
 LOCATION='PC1174_P0_4',
 CDS_LIB='pure_quanta',
 CDS_PART_NAME='Q_CAP_0402-3300PF,50V,10%,X7R,A',
 TOLERANCE='10%',
 MATERIAL='X7R',
 VOLTAGE='50V',
 VALUE='3300PF',
 PRIM_FILE='./archive_libs/logical/q_cap/chips/chips.prt';

PART_NAME
 PC1175_P0_3 'Q_CAP_C0402-1UF,16V,10%,X6S,CHA':;

SECTION_NUMBER 1
 '@S9S_MB_2U_LIB.S9S_MB_2U(SCH_1):PAGE258_I46@PURE_QUANTA.Q_CAP(CHIPS)':
 C_PATH='@s9s_mb_2u_lib.s9s_mb_2u(sch_1):page258_i46@pure_quanta.q_cap(chips)',
 P_PATH='@s9s_mb_2u_lib.s9s_mb_2u(sch_1):page272_i46@pure_quanta.q_cap(chips)',
 PATH='I46',
 DRAWING='@S9S_MB_2U_LIB.S9S_MB_2U(SCH_1):PAGE258',
 PHYS_PAGE='272',
 XY='(-7975,5800)',
 ROT='0',
 VER='1',
 PACK_TYPE='C0402',
 LOCATION='PC1175_P0_3',
 CDS_LIB='pure_quanta',
 CDS_PART_NAME='Q_CAP_C0402-1UF,16V,10%,X6S,CHA',
 TOLERANCE='10%',
 MATERIAL='X6S',
 VOLTAGE='16V',
 VALUE='1UF',
 PRIM_FILE='./archive_libs/logical/q_cap/chips/chips.prt';

PART_NAME
 PC1176_P0_4 'Q_CAP_C0402-1UF,16V,10%,X6S,CHA':;

SECTION_NUMBER 1
 '@S9S_MB_2U_LIB.S9S_MB_2U(SCH_1):PAGE258_I34@PURE_QUANTA.Q_CAP(CHIPS)':
 C_PATH='@s9s_mb_2u_lib.s9s_mb_2u(sch_1):page258_i34@pure_quanta.q_cap(chips)',
 P_PATH='@s9s_mb_2u_lib.s9s_mb_2u(sch_1):page272_i34@pure_quanta.q_cap(chips)',
 PATH='I34',
 DRAWING='@S9S_MB_2U_LIB.S9S_MB_2U(SCH_1):PAGE258',
 PHYS_PAGE='272',
 XY='(-7975,3000)',
 ROT='0',
 VER='1',
 PACK_TYPE='C0402',
 LOCATION='PC1176_P0_4',
 CDS_LIB='pure_quanta',
 CDS_PART_NAME='Q_CAP_C0402-1UF,16V,10%,X6S,CHA',
 TOLERANCE='10%',
 MATERIAL='X6S',
 VOLTAGE='16V',
 VALUE='1UF',
 PRIM_FILE='./archive_libs/logical/q_cap/chips/chips.prt';

PART_NAME
 PC1177 'Q_CAP_C0402-100NF,50V,10%,X7R,A':;

SECTION_NUMBER 1
 '@S9S_MB_2U_LIB.S9S_MB_2U(SCH_1):PAGE258_I49@PURE_QUANTA.Q_CAP(CHIPS)':
 C_PATH='@s9s_mb_2u_lib.s9s_mb_2u(sch_1):page258_i49@pure_quanta.q_cap(chips)',
 P_PATH='@s9s_mb_2u_lib.s9s_mb_2u(sch_1):page272_i49@pure_quanta.q_cap(chips)',
 PATH='I49',
 DRAWING='@S9S_MB_2U_LIB.S9S_MB_2U(SCH_1):PAGE258',
 PHYS_PAGE='272',
 XY='(-6750,5175)',
 ROT='2',
 VER='1',
 PACK_TYPE='C0402',
 LOCATION='PC1177',
 CDS_LIB='pure_quanta',
 CDS_PART_NAME='Q_CAP_C0402-100NF,50V,10%,X7R,A',
 TOLERANCE='10%',
 MATERIAL='X7R',
 VOLTAGE='50V',
 VALUE='100NF',
 PRIM_FILE='./archive_libs/logical/q_cap/chips/chips.prt';

PART_NAME
 PC1178 'Q_CAP_C0402-100NF,50V,10%,X7R,A':;

SECTION_NUMBER 1
 '@S9S_MB_2U_LIB.S9S_MB_2U(SCH_1):PAGE258_I37@PURE_QUANTA.Q_CAP(CHIPS)':
 C_PATH='@s9s_mb_2u_lib.s9s_mb_2u(sch_1):page258_i37@pure_quanta.q_cap(chips)',
 P_PATH='@s9s_mb_2u_lib.s9s_mb_2u(sch_1):page272_i37@pure_quanta.q_cap(chips)',
 PATH='I37',
 DRAWING='@S9S_MB_2U_LIB.S9S_MB_2U(SCH_1):PAGE258',
 PHYS_PAGE='272',
 XY='(-6750,2375)',
 ROT='2',
 VER='1',
 PACK_TYPE='C0402',
 LOCATION='PC1178',
 CDS_LIB='pure_quanta',
 CDS_PART_NAME='Q_CAP_C0402-100NF,50V,10%,X7R,A',
 TOLERANCE='10%',
 MATERIAL='X7R',
 VOLTAGE='50V',
 VALUE='100NF',
 PRIM_FILE='./archive_libs/logical/q_cap/chips/chips.prt';

PART_NAME
 PC1179_P0_3 'Q_CAP_C0805-22UF,16V,20%,X6S,CA':;

SECTION_NUMBER 1
 '@S9S_MB_2U_LIB.S9S_MB_2U(SCH_1):PAGE258_I47@PURE_QUANTA.Q_CAP(CHIPS)':
 C_PATH='@s9s_mb_2u_lib.s9s_mb_2u(sch_1):page258_i47@pure_quanta.q_cap(chips)',
 P_PATH='@s9s_mb_2u_lib.s9s_mb_2u(sch_1):page272_i47@pure_quanta.q_cap(chips)',
 PATH='I47',
 DRAWING='@S9S_MB_2U_LIB.S9S_MB_2U(SCH_1):PAGE258',
 PHYS_PAGE='272',
 XY='(-7575,5800)',
 ROT='0',
 VER='1',
 PACK_TYPE='C0805',
 LOCATION='PC1179_P0_3',
 CDS_LIB='pure_quanta',
 CDS_PART_NAME='Q_CAP_C0805-22UF,16V,20%,X6S,CA',
 TOLERANCE='20%',
 MATERIAL='X6S',
 VOLTAGE='16V',
 VALUE='22UF',
 PRIM_FILE='./archive_libs/logical/q_cap/chips/chips.prt';

PART_NAME
 PC1180_P0_4 'Q_CAP_C0805-22UF,16V,20%,X6S,CA':;

SECTION_NUMBER 1
 '@S9S_MB_2U_LIB.S9S_MB_2U(SCH_1):PAGE258_I35@PURE_QUANTA.Q_CAP(CHIPS)':
 C_PATH='@s9s_mb_2u_lib.s9s_mb_2u(sch_1):page258_i35@pure_quanta.q_cap(chips)',
 P_PATH='@s9s_mb_2u_lib.s9s_mb_2u(sch_1):page272_i35@pure_quanta.q_cap(chips)',
 PATH='I35',
 DRAWING='@S9S_MB_2U_LIB.S9S_MB_2U(SCH_1):PAGE258',
 PHYS_PAGE='272',
 XY='(-7575,3000)',
 ROT='0',
 VER='1',
 PACK_TYPE='C0805',
 LOCATION='PC1180_P0_4',
 CDS_LIB='pure_quanta',
 CDS_PART_NAME='Q_CAP_C0805-22UF,16V,20%,X6S,CA',
 TOLERANCE='20%',
 MATERIAL='X6S',
 VOLTAGE='16V',
 VALUE='22UF',
 PRIM_FILE='./archive_libs/logical/q_cap/chips/chips.prt';

PART_NAME
 PC1181_P0_3 'Q_CAP_C0805-22UF,16V,20%,X6S,CA':;

SECTION_NUMBER 1
 '@S9S_MB_2U_LIB.S9S_MB_2U(SCH_1):PAGE258_I48@PURE_QUANTA.Q_CAP(CHIPS)':
 C_PATH='@s9s_mb_2u_lib.s9s_mb_2u(sch_1):page258_i48@pure_quanta.q_cap(chips)',
 P_PATH='@s9s_mb_2u_lib.s9s_mb_2u(sch_1):page272_i48@pure_quanta.q_cap(chips)',
 PATH='I48',
 DRAWING='@S9S_MB_2U_LIB.S9S_MB_2U(SCH_1):PAGE258',
 PHYS_PAGE='272',
 XY='(-7175,5800)',
 ROT='0',
 VER='1',
 PACK_TYPE='C0805',
 LOCATION='PC1181_P0_3',
 CDS_LIB='pure_quanta',
 CDS_PART_NAME='Q_CAP_C0805-22UF,16V,20%,X6S,CA',
 TOLERANCE='20%',
 MATERIAL='X6S',
 VOLTAGE='16V',
 VALUE='22UF',
 PRIM_FILE='./archive_libs/logical/q_cap/chips/chips.prt';

PART_NAME
 PC1182_P0_4 'Q_CAP_C0805-22UF,16V,20%,X6S,CA':;

SECTION_NUMBER 1
 '@S9S_MB_2U_LIB.S9S_MB_2U(SCH_1):PAGE258_I36@PURE_QUANTA.Q_CAP(CHIPS)':
 C_PATH='@s9s_mb_2u_lib.s9s_mb_2u(sch_1):page258_i36@pure_quanta.q_cap(chips)',
 P_PATH='@s9s_mb_2u_lib.s9s_mb_2u(sch_1):page272_i36@pure_quanta.q_cap(chips)',
 PATH='I36',
 DRAWING='@S9S_MB_2U_LIB.S9S_MB_2U(SCH_1):PAGE258',
 PHYS_PAGE='272',
 XY='(-7175,3000)',
 ROT='0',
 VER='1',
 PACK_TYPE='C0805',
 LOCATION='PC1182_P0_4',
 CDS_LIB='pure_quanta',
 CDS_PART_NAME='Q_CAP_C0805-22UF,16V,20%,X6S,CA',
 TOLERANCE='20%',
 MATERIAL='X6S',
 VOLTAGE='16V',
 VALUE='22UF',
 PRIM_FILE='./archive_libs/logical/q_cap/chips/chips.prt';

PART_NAME
 PC1183 'Q_CAPP_THLF-560UF,2.5V,20%,OSCA':;

SECTION_NUMBER 1
 '@S9S_MB_2U_LIB.S9S_MB_2U(SCH_1):PAGE258_I64@PURE_QUANTA.Q_CAPP(CHIPS)':
 C_PATH='@s9s_mb_2u_lib.s9s_mb_2u(sch_1):page258_i64@pure_quanta.q_capp(chips)',
 P_PATH='@s9s_mb_2u_lib.s9s_mb_2u(sch_1):page272_i64@pure_quanta.q_capp(chips)',
 PATH='I64',
 DRAWING='@S9S_MB_2U_LIB.S9S_MB_2U(SCH_1):PAGE258',
 PHYS_PAGE='272',
 XY='(-5025,3500)',
 ROT='0',
 VER='1',
 PACK_TYPE='THLF',
 LOCATION='PC1183',
 CDS_LIB='pure_quanta',
 CDS_PART_NAME='Q_CAPP_THLF-560UF,2.5V,20%,OSCA',
 TOLERANCE='20%',
 MATERIAL='OSCON',
 VOLTAGE='2.5V',
 VALUE='560UF',
 PRIM_FILE='./archive_libs/logical/q_capp/chips/chips.prt';

PART_NAME
 PC1183_P0_3 'Q_CAP_C0402-1UF,16V,10%,X6S,CHA':;

SECTION_NUMBER 1
 '@S9S_MB_2U_LIB.S9S_MB_2U(SCH_1):PAGE258_I55@PURE_QUANTA.Q_CAP(CHIPS)':
 C_PATH='@s9s_mb_2u_lib.s9s_mb_2u(sch_1):page258_i55@pure_quanta.q_cap(chips)',
 P_PATH='@s9s_mb_2u_lib.s9s_mb_2u(sch_1):page272_i55@pure_quanta.q_cap(chips)',
 PATH='I55',
 DRAWING='@S9S_MB_2U_LIB.S9S_MB_2U(SCH_1):PAGE258',
 PHYS_PAGE='272',
 XY='(-5425,4700)',
 ROT='0',
 VER='1',
 PACK_TYPE='C0402',
 LOCATION='PC1183_P0_3',
 CDS_LIB='pure_quanta',
 CDS_PART_NAME='Q_CAP_C0402-1UF,16V,10%,X6S,CHA',
 TOLERANCE='10%',
 MATERIAL='X6S',
 VOLTAGE='16V',
 VALUE='1UF',
 PRIM_FILE='./archive_libs/logical/q_cap/chips/chips.prt';

PART_NAME
 PC1183_P0_4 'Q_CAP_C0402-100NF,50V,10%,X7R,A':;

SECTION_NUMBER 1
 '@S9S_MB_2U_LIB.S9S_MB_2U(SCH_1):PAGE258_I40@PURE_QUANTA.Q_CAP(CHIPS)':
 C_PATH='@s9s_mb_2u_lib.s9s_mb_2u(sch_1):page258_i40@pure_quanta.q_cap(chips)',
 P_PATH='@s9s_mb_2u_lib.s9s_mb_2u(sch_1):page272_i40@pure_quanta.q_cap(chips)',
 PATH='I40',
 DRAWING='@S9S_MB_2U_LIB.S9S_MB_2U(SCH_1):PAGE258',
 PHYS_PAGE='272',
 XY='(-5450,1900)',
 ROT='0',
 VER='1',
 PACK_TYPE='C0402',
 LOCATION='PC1183_P0_4',
 CDS_LIB='pure_quanta',
 CDS_PART_NAME='Q_CAP_C0402-100NF,50V,10%,X7R,A',
 TOLERANCE='10%',
 MATERIAL='X7R',
 VOLTAGE='50V',
 VALUE='100NF',
 PRIM_FILE='./archive_libs/logical/q_cap/chips/chips.prt';

PART_NAME
 PC1185 'Q_CAPP_THLF-560UF,2.5V,20%,OSCA':;

SECTION_NUMBER 1
 '@S9S_MB_2U_LIB.S9S_MB_2U(SCH_1):PAGE258_I65@PURE_QUANTA.Q_CAPP(CHIPS)':
 C_PATH='@s9s_mb_2u_lib.s9s_mb_2u(sch_1):page258_i65@pure_quanta.q_capp(chips)',
 P_PATH='@s9s_mb_2u_lib.s9s_mb_2u(sch_1):page272_i65@pure_quanta.q_capp(chips)',
 PATH='I65',
 DRAWING='@S9S_MB_2U_LIB.S9S_MB_2U(SCH_1):PAGE258',
 PHYS_PAGE='272',
 XY='(-4500,3500)',
 ROT='0',
 VER='1',
 PACK_TYPE='THLF',
 LOCATION='PC1185',
 CDS_LIB='pure_quanta',
 CDS_PART_NAME='Q_CAPP_THLF-560UF,2.5V,20%,OSCA',
 TOLERANCE='20%',
 MATERIAL='OSCON',
 VOLTAGE='2.5V',
 VALUE='560UF',
 PRIM_FILE='./archive_libs/logical/q_capp/chips/chips.prt';

PART_NAME
 PC1185_P0_3 'Q_CAP_C0805-22UF,4V,20%,X6S,CHA':;

SECTION_NUMBER 1
 '@S9S_MB_2U_LIB.S9S_MB_2U(SCH_1):PAGE258_I72@PURE_QUANTA.Q_CAP(CHIPS)':
 C_PATH='@s9s_mb_2u_lib.s9s_mb_2u(sch_1):page258_i72@pure_quanta.q_cap(chips)',
 P_PATH='@s9s_mb_2u_lib.s9s_mb_2u(sch_1):page272_i72@pure_quanta.q_cap(chips)',
 PATH='I72',
 DRAWING='@S9S_MB_2U_LIB.S9S_MB_2U(SCH_1):PAGE258',
 PHYS_PAGE='272',
 XY='(-5000,4700)',
 ROT='0',
 VER='1',
 PACK_TYPE='C0805',
 LOCATION='PC1185_P0_3',
 CDS_LIB='pure_quanta',
 CDS_PART_NAME='Q_CAP_C0805-22UF,4V,20%,X6S,CHA',
 TOLERANCE='20%',
 MATERIAL='X6S',
 VOLTAGE='4V',
 VALUE='22UF',
 PRIM_FILE='./archive_libs/logical/q_cap/chips/chips.prt';

PART_NAME
 PC1186 'Q_CAPP_THLF-560UF,2.5V,20%,OSCA':;

SECTION_NUMBER 1
 '@S9S_MB_2U_LIB.S9S_MB_2U(SCH_1):PAGE258_I68@PURE_QUANTA.Q_CAPP(CHIPS)':
 C_PATH='@s9s_mb_2u_lib.s9s_mb_2u(sch_1):page258_i68@pure_quanta.q_capp(chips)',
 P_PATH='@s9s_mb_2u_lib.s9s_mb_2u(sch_1):page272_i68@pure_quanta.q_capp(chips)',
 PATH='I68',
 DRAWING='@S9S_MB_2U_LIB.S9S_MB_2U(SCH_1):PAGE258',
 PHYS_PAGE='272',
 XY='(-3975,3500)',
 ROT='0',
 VER='1',
 PACK_TYPE='THLF',
 LOCATION='PC1186',
 CDS_LIB='pure_quanta',
 CDS_PART_NAME='Q_CAPP_THLF-560UF,2.5V,20%,OSCA',
 TOLERANCE='20%',
 MATERIAL='OSCON',
 VOLTAGE='2.5V',
 VALUE='560UF',
 PRIM_FILE='./archive_libs/logical/q_capp/chips/chips.prt';

PART_NAME
 PC1186_P0_4 'Q_CAP_C0805-22UF,4V,20%,X6S,CHA':;

SECTION_NUMBER 1
 '@S9S_MB_2U_LIB.S9S_MB_2U(SCH_1):PAGE258_I60@PURE_QUANTA.Q_CAP(CHIPS)':
 C_PATH='@s9s_mb_2u_lib.s9s_mb_2u(sch_1):page258_i60@pure_quanta.q_cap(chips)',
 P_PATH='@s9s_mb_2u_lib.s9s_mb_2u(sch_1):page272_i60@pure_quanta.q_cap(chips)',
 PATH='I60',
 DRAWING='@S9S_MB_2U_LIB.S9S_MB_2U(SCH_1):PAGE258',
 PHYS_PAGE='272',
 XY='(-5000,1900)',
 ROT='0',
 VER='1',
 PACK_TYPE='C0805',
 LOCATION='PC1186_P0_4',
 CDS_LIB='pure_quanta',
 CDS_PART_NAME='Q_CAP_C0805-22UF,4V,20%,X6S,CHA',
 TOLERANCE='20%',
 MATERIAL='X6S',
 VOLTAGE='4V',
 VALUE='22UF',
 PRIM_FILE='./archive_libs/logical/q_cap/chips/chips.prt';

PART_NAME
 PC1187 'Q_CAPP_SMLF-330UF,2.5V,+10/-35B':;

SECTION_NUMBER 1
 '@S9S_MB_2U_LIB.S9S_MB_2U(SCH_1):PAGE258_I69@PURE_QUANTA.Q_CAPP(CHIPS)':
 C_PATH='@s9s_mb_2u_lib.s9s_mb_2u(sch_1):page258_i69@pure_quanta.q_capp(chips)',
 P_PATH='@s9s_mb_2u_lib.s9s_mb_2u(sch_1):page272_i69@pure_quanta.q_capp(chips)',
 PATH='I69',
 DRAWING='@S9S_MB_2U_LIB.S9S_MB_2U(SCH_1):PAGE258',
 PHYS_PAGE='272',
 XY='(-3475,3500)',
 ROT='0',
 VER='1',
 PACK_TYPE='SMLF',
 LOCATION='PC1187',
 CDS_LIB='pure_quanta',
 CDS_PART_NAME='Q_CAPP_SMLF-330UF,2.5V,+10/-35B',
 TOLERANCE='+10/-35%',
 MATERIAL='SPCAP',
 VOLTAGE='2.5V',
 VALUE='330UF',
 PRIM_FILE='./archive_libs/logical/q_capp/chips/chips.prt';

PART_NAME
 PC1187_P0_3 'Q_CAP_C0805-22UF,4V,20%,X6S,CHA':;

SECTION_NUMBER 1
 '@S9S_MB_2U_LIB.S9S_MB_2U(SCH_1):PAGE258_I73@PURE_QUANTA.Q_CAP(CHIPS)':
 C_PATH='@s9s_mb_2u_lib.s9s_mb_2u(sch_1):page258_i73@pure_quanta.q_cap(chips)',
 P_PATH='@s9s_mb_2u_lib.s9s_mb_2u(sch_1):page272_i73@pure_quanta.q_cap(chips)',
 PATH='I73',
 DRAWING='@S9S_MB_2U_LIB.S9S_MB_2U(SCH_1):PAGE258',
 PHYS_PAGE='272',
 XY='(-4575,4700)',
 ROT='0',
 VER='1',
 PACK_TYPE='C0805',
 LOCATION='PC1187_P0_3',
 CDS_LIB='pure_quanta',
 CDS_PART_NAME='Q_CAP_C0805-22UF,4V,20%,X6S,CHA',
 TOLERANCE='20%',
 MATERIAL='X6S',
 VOLTAGE='4V',
 VALUE='22UF',
 PRIM_FILE='./archive_libs/logical/q_cap/chips/chips.prt';

PART_NAME
 PC1188_P0_4 'Q_CAP_C0805-22UF,4V,20%,X6S,CHA':;

SECTION_NUMBER 1
 '@S9S_MB_2U_LIB.S9S_MB_2U(SCH_1):PAGE258_I61@PURE_QUANTA.Q_CAP(CHIPS)':
 C_PATH='@s9s_mb_2u_lib.s9s_mb_2u(sch_1):page258_i61@pure_quanta.q_cap(chips)',
 P_PATH='@s9s_mb_2u_lib.s9s_mb_2u(sch_1):page272_i61@pure_quanta.q_cap(chips)',
 PATH='I61',
 DRAWING='@S9S_MB_2U_LIB.S9S_MB_2U(SCH_1):PAGE258',
 PHYS_PAGE='272',
 XY='(-4575,1900)',
 ROT='0',
 VER='1',
 PACK_TYPE='C0805',
 LOCATION='PC1188_P0_4',
 CDS_LIB='pure_quanta',
 CDS_PART_NAME='Q_CAP_C0805-22UF,4V,20%,X6S,CHA',
 TOLERANCE='20%',
 MATERIAL='X6S',
 VOLTAGE='4V',
 VALUE='22UF',
 PRIM_FILE='./archive_libs/logical/q_cap/chips/chips.prt';

PART_NAME
 PC1189 'Q_CAPP_THLF-270UF,16V,20%,OSCOA':;

SECTION_NUMBER 1
 '@S9S_MB_2U_LIB.S9S_MB_2U(SCH_1):PAGE258_I80@PURE_QUANTA.Q_CAPP(CHIPS)':
 C_PATH='@s9s_mb_2u_lib.s9s_mb_2u(sch_1):page258_i80@pure_quanta.q_capp(chips)',
 P_PATH='@s9s_mb_2u_lib.s9s_mb_2u(sch_1):page272_i80@pure_quanta.q_capp(chips)',
 PATH='I80',
 DRAWING='@S9S_MB_2U_LIB.S9S_MB_2U(SCH_1):PAGE258',
 PHYS_PAGE='272',
 XY='(-3500,5550)',
 ROT='0',
 VER='1',
 PACK_TYPE='THLF',
 LOCATION='PC1189',
 CDS_LIB='pure_quanta',
 CDS_PART_NAME='Q_CAPP_THLF-270UF,16V,20%,OSCOA',
 TOLERANCE='20%',
 MATERIAL='OSCON',
 VOLTAGE='16V',
 VALUE='270UF',
 PRIM_FILE='./archive_libs/logical/q_capp/chips/chips.prt';

PART_NAME
 PC1191 'Q_CAP_C0402-2.2UF,10V,10%,X6S,A':;

SECTION_NUMBER 1
 '@S9S_MB_2U_LIB.S9S_MB_2U(SCH_1):PAGE276_I27@PURE_QUANTA.Q_CAP(CHIPS)':
 C_PATH='@s9s_mb_2u_lib.s9s_mb_2u(sch_1):page276_i27@pure_quanta.q_cap(chips)',
 P_PATH='@s9s_mb_2u_lib.s9s_mb_2u(sch_1):page290_i27@pure_quanta.q_cap(chips)',
 PATH='I27',
 DRAWING='@S9S_MB_2U_LIB.S9S_MB_2U(SCH_1):PAGE276',
 PHYS_PAGE='290',
 XY='(-7325,7075)',
 ROT='0',
 VER='1',
 PACK_TYPE='C0402',
 LOCATION='PC1191',
 CDS_LIB='pure_quanta',
 CDS_PART_NAME='Q_CAP_C0402-2.2UF,10V,10%,X6S,A',
 TOLERANCE='10%',
 MATERIAL='X6S',
 VOLTAGE='10V',
 VALUE='2.2UF',
 PRIM_FILE='./archive_libs/logical/q_cap/chips/chips.prt';

PART_NAME
 PC1192 'Q_CAP_C0402-2.2UF,10V,10%,X6S,A':;

SECTION_NUMBER 1
 '@S9S_MB_2U_LIB.S9S_MB_2U(SCH_1):PAGE276_I12@PURE_QUANTA.Q_CAP(CHIPS)':
 C_PATH='@s9s_mb_2u_lib.s9s_mb_2u(sch_1):page276_i12@pure_quanta.q_cap(chips)',
 P_PATH='@s9s_mb_2u_lib.s9s_mb_2u(sch_1):page290_i12@pure_quanta.q_cap(chips)',
 PATH='I12',
 DRAWING='@S9S_MB_2U_LIB.S9S_MB_2U(SCH_1):PAGE276',
 PHYS_PAGE='290',
 XY='(-7325,4275)',
 ROT='0',
 VER='1',
 PACK_TYPE='C0402',
 LOCATION='PC1192',
 CDS_LIB='pure_quanta',
 CDS_PART_NAME='Q_CAP_C0402-2.2UF,10V,10%,X6S,A',
 TOLERANCE='10%',
 MATERIAL='X6S',
 VOLTAGE='10V',
 VALUE='2.2UF',
 PRIM_FILE='./archive_libs/logical/q_cap/chips/chips.prt';

PART_NAME
 PC1193 'Q_CAP_C0402-1UF,16V,10%,X6S,CHA':;

SECTION_NUMBER 1
 '@S9S_MB_2U_LIB.S9S_MB_2U(SCH_1):PAGE278_I96@PURE_QUANTA.Q_CAP(CHIPS)':
 C_PATH='@s9s_mb_2u_lib.s9s_mb_2u(sch_1):page278_i96@pure_quanta.q_cap(chips)',
 P_PATH='@s9s_mb_2u_lib.s9s_mb_2u(sch_1):page292_i96@pure_quanta.q_cap(chips)',
 PATH='I96',
 DRAWING='@S9S_MB_2U_LIB.S9S_MB_2U(SCH_1):PAGE278',
 PHYS_PAGE='292',
 XY='(5200,8475)',
 ROT='0',
 VER='1',
 PACK_TYPE='C0402',
 LOCATION='PC1193',
 CDS_LIB='pure_quanta',
 CDS_PART_NAME='Q_CAP_C0402-1UF,16V,10%,X6S,CHA',
 TOLERANCE='10%',
 MATERIAL='X6S',
 VOLTAGE='16V',
 VALUE='1UF',
 PRIM_FILE='./archive_libs/logical/q_cap/chips/chips.prt';

PART_NAME
 PC1193_P1_3 'Q_CAP_0402-3300PF,50V,10%,X7R,A':;

SECTION_NUMBER 1
 '@S9S_MB_2U_LIB.S9S_MB_2U(SCH_1):PAGE276_I38@PURE_QUANTA.Q_CAP(CHIPS)':
 C_PATH='@s9s_mb_2u_lib.s9s_mb_2u(sch_1):page276_i38@pure_quanta.q_cap(chips)',
 P_PATH='@s9s_mb_2u_lib.s9s_mb_2u(sch_1):page290_i38@pure_quanta.q_cap(chips)',
 PATH='I38',
 DRAWING='@S9S_MB_2U_LIB.S9S_MB_2U(SCH_1):PAGE276',
 PHYS_PAGE='290',
 XY='(-5000,7525)',
 ROT='0',
 VER='1',
 PACK_TYPE='0402',
 LOCATION='PC1193_P1_3',
 CDS_LIB='pure_quanta',
 CDS_PART_NAME='Q_CAP_0402-3300PF,50V,10%,X7R,A',
 TOLERANCE='10%',
 MATERIAL='X7R',
 VOLTAGE='50V',
 VALUE='3300PF',
 PRIM_FILE='./archive_libs/logical/q_cap/chips/chips.prt';

PART_NAME
 PC1194 'Q_CAP_C0402-1UF,16V,10%,X6S,CHA':;

SECTION_NUMBER 1
 '@S9S_MB_2U_LIB.S9S_MB_2U(SCH_1):PAGE270_I121@PURE_QUANTA.Q_CAP(CHIPS)':
 C_PATH='@s9s_mb_2u_lib.s9s_mb_2u(sch_1):page270_i121@pure_quanta.q_cap(chips)',
 P_PATH='@s9s_mb_2u_lib.s9s_mb_2u(sch_1):page284_i121@pure_quanta.q_cap(chips)',
 PATH='I121',
 DRAWING='@S9S_MB_2U_LIB.S9S_MB_2U(SCH_1):PAGE270',
 PHYS_PAGE='284',
 XY='(1850,2350)',
 ROT='0',
 VER='1',
 PACK_TYPE='C0402',
 LOCATION='PC1194',
 CDS_LIB='pure_quanta',
 CDS_PART_NAME='Q_CAP_C0402-1UF,16V,10%,X6S,CHA',
 TOLERANCE='10%',
 MATERIAL='X6S',
 VOLTAGE='16V',
 VALUE='1UF',
 PRIM_FILE='./archive_libs/logical/q_cap/chips/chips.prt';

PART_NAME
 PC1194_P1_4 'Q_CAP_0402-3300PF,50V,10%,X7R,A':;

SECTION_NUMBER 1
 '@S9S_MB_2U_LIB.S9S_MB_2U(SCH_1):PAGE276_I33@PURE_QUANTA.Q_CAP(CHIPS)':
 C_PATH='@s9s_mb_2u_lib.s9s_mb_2u(sch_1):page276_i33@pure_quanta.q_cap(chips)',
 P_PATH='@s9s_mb_2u_lib.s9s_mb_2u(sch_1):page290_i33@pure_quanta.q_cap(chips)',
 PATH='I33',
 DRAWING='@S9S_MB_2U_LIB.S9S_MB_2U(SCH_1):PAGE276',
 PHYS_PAGE='290',
 XY='(-5000,4725)',
 ROT='0',
 VER='1',
 PACK_TYPE='0402',
 LOCATION='PC1194_P1_4',
 CDS_LIB='pure_quanta',
 CDS_PART_NAME='Q_CAP_0402-3300PF,50V,10%,X7R,A',
 TOLERANCE='10%',
 MATERIAL='X7R',
 VOLTAGE='50V',
 VALUE='3300PF',
 PRIM_FILE='./archive_libs/logical/q_cap/chips/chips.prt';

PART_NAME
 PC1195_P1_3 'Q_CAP_C0402-1UF,16V,10%,X6S,CHA':;

SECTION_NUMBER 1
 '@S9S_MB_2U_LIB.S9S_MB_2U(SCH_1):PAGE276_I39@PURE_QUANTA.Q_CAP(CHIPS)':
 C_PATH='@s9s_mb_2u_lib.s9s_mb_2u(sch_1):page276_i39@pure_quanta.q_cap(chips)',
 P_PATH='@s9s_mb_2u_lib.s9s_mb_2u(sch_1):page290_i39@pure_quanta.q_cap(chips)',
 PATH='I39',
 DRAWING='@S9S_MB_2U_LIB.S9S_MB_2U(SCH_1):PAGE276',
 PHYS_PAGE='290',
 XY='(-4600,7525)',
 ROT='0',
 VER='1',
 PACK_TYPE='C0402',
 LOCATION='PC1195_P1_3',
 CDS_LIB='pure_quanta',
 CDS_PART_NAME='Q_CAP_C0402-1UF,16V,10%,X6S,CHA',
 TOLERANCE='10%',
 MATERIAL='X6S',
 VOLTAGE='16V',
 VALUE='1UF',
 PRIM_FILE='./archive_libs/logical/q_cap/chips/chips.prt';

PART_NAME
 PC1196 'Q_CAP_C0402-1UF,16V,10%,X6S,CHA':;

SECTION_NUMBER 1
 '@S9S_MB_2U_LIB.S9S_MB_2U(SCH_1):PAGE264_I71@PURE_QUANTA.Q_CAP(CHIPS)':
 C_PATH='@s9s_mb_2u_lib.s9s_mb_2u(sch_1):page264_i71@pure_quanta.q_cap(chips)',
 P_PATH='@s9s_mb_2u_lib.s9s_mb_2u(sch_1):page278_i71@pure_quanta.q_cap(chips)',
 PATH='I71',
 DRAWING='@S9S_MB_2U_LIB.S9S_MB_2U(SCH_1):PAGE264',
 PHYS_PAGE='278',
 XY='(-5825,8275)',
 ROT='0',
 VER='1',
 PACK_TYPE='C0402',
 LOCATION='PC1196',
 CDS_LIB='pure_quanta',
 CDS_PART_NAME='Q_CAP_C0402-1UF,16V,10%,X6S,CHA',
 TOLERANCE='10%',
 MATERIAL='X6S',
 VOLTAGE='16V',
 VALUE='1UF',
 PRIM_FILE='./archive_libs/logical/q_cap/chips/chips.prt';

PART_NAME
 PC1196_P1_4 'Q_CAP_C0402-1UF,16V,10%,X6S,CHA':;

SECTION_NUMBER 1
 '@S9S_MB_2U_LIB.S9S_MB_2U(SCH_1):PAGE276_I35@PURE_QUANTA.Q_CAP(CHIPS)':
 C_PATH='@s9s_mb_2u_lib.s9s_mb_2u(sch_1):page276_i35@pure_quanta.q_cap(chips)',
 P_PATH='@s9s_mb_2u_lib.s9s_mb_2u(sch_1):page290_i35@pure_quanta.q_cap(chips)',
 PATH='I35',
 DRAWING='@S9S_MB_2U_LIB.S9S_MB_2U(SCH_1):PAGE276',
 PHYS_PAGE='290',
 XY='(-4600,4725)',
 ROT='0',
 VER='1',
 PACK_TYPE='C0402',
 LOCATION='PC1196_P1_4',
 CDS_LIB='pure_quanta',
 CDS_PART_NAME='Q_CAP_C0402-1UF,16V,10%,X6S,CHA',
 TOLERANCE='10%',
 MATERIAL='X6S',
 VOLTAGE='16V',
 VALUE='1UF',
 PRIM_FILE='./archive_libs/logical/q_cap/chips/chips.prt';

PART_NAME
 PC1197 'Q_CAP_C0402-100NF,50V,10%,X7R,A':;

SECTION_NUMBER 1
 '@S9S_MB_2U_LIB.S9S_MB_2U(SCH_1):PAGE276_I58@PURE_QUANTA.Q_CAP(CHIPS)':
 C_PATH='@s9s_mb_2u_lib.s9s_mb_2u(sch_1):page276_i58@pure_quanta.q_cap(chips)',
 P_PATH='@s9s_mb_2u_lib.s9s_mb_2u(sch_1):page290_i58@pure_quanta.q_cap(chips)',
 PATH='I58',
 DRAWING='@S9S_MB_2U_LIB.S9S_MB_2U(SCH_1):PAGE276',
 PHYS_PAGE='290',
 XY='(-3375,6900)',
 ROT='2',
 VER='1',
 PACK_TYPE='C0402',
 LOCATION='PC1197',
 CDS_LIB='pure_quanta',
 CDS_PART_NAME='Q_CAP_C0402-100NF,50V,10%,X7R,A',
 TOLERANCE='10%',
 MATERIAL='X7R',
 VOLTAGE='50V',
 VALUE='100NF',
 PRIM_FILE='./archive_libs/logical/q_cap/chips/chips.prt';

PART_NAME
 PC1198 'Q_CAP_C0402-100NF,50V,10%,X7R,A':;

SECTION_NUMBER 1
 '@S9S_MB_2U_LIB.S9S_MB_2U(SCH_1):PAGE276_I45@PURE_QUANTA.Q_CAP(CHIPS)':
 C_PATH='@s9s_mb_2u_lib.s9s_mb_2u(sch_1):page276_i45@pure_quanta.q_cap(chips)',
 P_PATH='@s9s_mb_2u_lib.s9s_mb_2u(sch_1):page290_i45@pure_quanta.q_cap(chips)',
 PATH='I45',
 DRAWING='@S9S_MB_2U_LIB.S9S_MB_2U(SCH_1):PAGE276',
 PHYS_PAGE='290',
 XY='(-3375,4100)',
 ROT='2',
 VER='1',
 PACK_TYPE='C0402',
 LOCATION='PC1198',
 CDS_LIB='pure_quanta',
 CDS_PART_NAME='Q_CAP_C0402-100NF,50V,10%,X7R,A',
 TOLERANCE='10%',
 MATERIAL='X7R',
 VOLTAGE='50V',
 VALUE='100NF',
 PRIM_FILE='./archive_libs/logical/q_cap/chips/chips.prt';

PART_NAME
 PC1199_P1_3 'Q_CAP_C0805-22UF,16V,20%,X6S,CA':;

SECTION_NUMBER 1
 '@S9S_MB_2U_LIB.S9S_MB_2U(SCH_1):PAGE276_I41@PURE_QUANTA.Q_CAP(CHIPS)':
 C_PATH='@s9s_mb_2u_lib.s9s_mb_2u(sch_1):page276_i41@pure_quanta.q_cap(chips)',
 P_PATH='@s9s_mb_2u_lib.s9s_mb_2u(sch_1):page290_i41@pure_quanta.q_cap(chips)',
 PATH='I41',
 DRAWING='@S9S_MB_2U_LIB.S9S_MB_2U(SCH_1):PAGE276',
 PHYS_PAGE='290',
 XY='(-4200,7525)',
 ROT='0',
 VER='1',
 PACK_TYPE='C0805',
 LOCATION='PC1199_P1_3',
 CDS_LIB='pure_quanta',
 CDS_PART_NAME='Q_CAP_C0805-22UF,16V,20%,X6S,CA',
 TOLERANCE='20%',
 MATERIAL='X6S',
 VOLTAGE='16V',
 VALUE='22UF',
 PRIM_FILE='./archive_libs/logical/q_cap/chips/chips.prt';

PART_NAME
 PC1200_P1_4 'Q_CAP_C0805-22UF,16V,20%,X6S,CA':;

SECTION_NUMBER 1
 '@S9S_MB_2U_LIB.S9S_MB_2U(SCH_1):PAGE276_I36@PURE_QUANTA.Q_CAP(CHIPS)':
 C_PATH='@s9s_mb_2u_lib.s9s_mb_2u(sch_1):page276_i36@pure_quanta.q_cap(chips)',
 P_PATH='@s9s_mb_2u_lib.s9s_mb_2u(sch_1):page290_i36@pure_quanta.q_cap(chips)',
 PATH='I36',
 DRAWING='@S9S_MB_2U_LIB.S9S_MB_2U(SCH_1):PAGE276',
 PHYS_PAGE='290',
 XY='(-4200,4725)',
 ROT='0',
 VER='1',
 PACK_TYPE='C0805',
 LOCATION='PC1200_P1_4',
 CDS_LIB='pure_quanta',
 CDS_PART_NAME='Q_CAP_C0805-22UF,16V,20%,X6S,CA',
 TOLERANCE='20%',
 MATERIAL='X6S',
 VOLTAGE='16V',
 VALUE='22UF',
 PRIM_FILE='./archive_libs/logical/q_cap/chips/chips.prt';

PART_NAME
 PC1201 'Q_CAPP_THLF-560UF,2.5V,20%,OSCA':;

SECTION_NUMBER 1
 '@S9S_MB_2U_LIB.S9S_MB_2U(SCH_1):PAGE276_I55@PURE_QUANTA.Q_CAPP(CHIPS)':
 C_PATH='@s9s_mb_2u_lib.s9s_mb_2u(sch_1):page276_i55@pure_quanta.q_capp(chips)',
 P_PATH='@s9s_mb_2u_lib.s9s_mb_2u(sch_1):page290_i55@pure_quanta.q_capp(chips)',
 PATH='I55',
 DRAWING='@S9S_MB_2U_LIB.S9S_MB_2U(SCH_1):PAGE276',
 PHYS_PAGE='290',
 XY='(-1625,5175)',
 ROT='0',
 VER='1',
 PACK_TYPE='THLF',
 LOCATION='PC1201',
 CDS_LIB='pure_quanta',
 CDS_PART_NAME='Q_CAPP_THLF-560UF,2.5V,20%,OSCA',
 TOLERANCE='20%',
 MATERIAL='OSCON',
 VOLTAGE='2.5V',
 VALUE='560UF',
 PRIM_FILE='./archive_libs/logical/q_capp/chips/chips.prt';

PART_NAME
 PC1201_P1_3 'Q_CAP_C0805-22UF,16V,20%,X6S,CA':;

SECTION_NUMBER 1
 '@S9S_MB_2U_LIB.S9S_MB_2U(SCH_1):PAGE276_I42@PURE_QUANTA.Q_CAP(CHIPS)':
 C_PATH='@s9s_mb_2u_lib.s9s_mb_2u(sch_1):page276_i42@pure_quanta.q_cap(chips)',
 P_PATH='@s9s_mb_2u_lib.s9s_mb_2u(sch_1):page290_i42@pure_quanta.q_cap(chips)',
 PATH='I42',
 DRAWING='@S9S_MB_2U_LIB.S9S_MB_2U(SCH_1):PAGE276',
 PHYS_PAGE='290',
 XY='(-3800,7525)',
 ROT='0',
 VER='1',
 PACK_TYPE='C0805',
 LOCATION='PC1201_P1_3',
 CDS_LIB='pure_quanta',
 CDS_PART_NAME='Q_CAP_C0805-22UF,16V,20%,X6S,CA',
 TOLERANCE='20%',
 MATERIAL='X6S',
 VOLTAGE='16V',
 VALUE='22UF',
 PRIM_FILE='./archive_libs/logical/q_cap/chips/chips.prt';

PART_NAME
 PC1202_P1_4 'Q_CAP_C0805-22UF,16V,20%,X6S,CA':;

SECTION_NUMBER 1
 '@S9S_MB_2U_LIB.S9S_MB_2U(SCH_1):PAGE276_I37@PURE_QUANTA.Q_CAP(CHIPS)':
 C_PATH='@s9s_mb_2u_lib.s9s_mb_2u(sch_1):page276_i37@pure_quanta.q_cap(chips)',
 P_PATH='@s9s_mb_2u_lib.s9s_mb_2u(sch_1):page290_i37@pure_quanta.q_cap(chips)',
 PATH='I37',
 DRAWING='@S9S_MB_2U_LIB.S9S_MB_2U(SCH_1):PAGE276',
 PHYS_PAGE='290',
 XY='(-3800,4725)',
 ROT='0',
 VER='1',
 PACK_TYPE='C0805',
 LOCATION='PC1202_P1_4',
 CDS_LIB='pure_quanta',
 CDS_PART_NAME='Q_CAP_C0805-22UF,16V,20%,X6S,CA',
 TOLERANCE='20%',
 MATERIAL='X6S',
 VOLTAGE='16V',
 VALUE='22UF',
 PRIM_FILE='./archive_libs/logical/q_cap/chips/chips.prt';

PART_NAME
 PC1203 'Q_CAPP_THLF-560UF,2.5V,20%,OSCA':;

SECTION_NUMBER 1
 '@S9S_MB_2U_LIB.S9S_MB_2U(SCH_1):PAGE276_I67@PURE_QUANTA.Q_CAPP(CHIPS)':
 C_PATH='@s9s_mb_2u_lib.s9s_mb_2u(sch_1):page276_i67@pure_quanta.q_capp(chips)',
 P_PATH='@s9s_mb_2u_lib.s9s_mb_2u(sch_1):page290_i67@pure_quanta.q_capp(chips)',
 PATH='I67',
 DRAWING='@S9S_MB_2U_LIB.S9S_MB_2U(SCH_1):PAGE276',
 PHYS_PAGE='290',
 XY='(-1100,5175)',
 ROT='0',
 VER='1',
 PACK_TYPE='THLF',
 LOCATION='PC1203',
 CDS_LIB='pure_quanta',
 CDS_PART_NAME='Q_CAPP_THLF-560UF,2.5V,20%,OSCA',
 TOLERANCE='20%',
 MATERIAL='OSCON',
 VOLTAGE='2.5V',
 VALUE='560UF',
 PRIM_FILE='./archive_libs/logical/q_capp/chips/chips.prt';

PART_NAME
 PC1203_P1_4 'Q_CAP_C0402-100NF,50V,10%,X7R,A':;

SECTION_NUMBER 1
 '@S9S_MB_2U_LIB.S9S_MB_2U(SCH_1):PAGE276_I47@PURE_QUANTA.Q_CAP(CHIPS)':
 C_PATH='@s9s_mb_2u_lib.s9s_mb_2u(sch_1):page276_i47@pure_quanta.q_cap(chips)',
 P_PATH='@s9s_mb_2u_lib.s9s_mb_2u(sch_1):page290_i47@pure_quanta.q_cap(chips)',
 PATH='I47',
 DRAWING='@S9S_MB_2U_LIB.S9S_MB_2U(SCH_1):PAGE276',
 PHYS_PAGE='290',
 XY='(-2150,3625)',
 ROT='0',
 VER='1',
 PACK_TYPE='C0402',
 LOCATION='PC1203_P1_4',
 CDS_LIB='pure_quanta',
 CDS_PART_NAME='Q_CAP_C0402-100NF,50V,10%,X7R,A',
 TOLERANCE='10%',
 MATERIAL='X7R',
 VOLTAGE='50V',
 VALUE='100NF',
 PRIM_FILE='./archive_libs/logical/q_cap/chips/chips.prt';

PART_NAME
 PC1204 'Q_CAPP_THLF-560UF,2.5V,20%,OSCA':;

SECTION_NUMBER 1
 '@S9S_MB_2U_LIB.S9S_MB_2U(SCH_1):PAGE276_I70@PURE_QUANTA.Q_CAPP(CHIPS)':
 C_PATH='@s9s_mb_2u_lib.s9s_mb_2u(sch_1):page276_i70@pure_quanta.q_capp(chips)',
 P_PATH='@s9s_mb_2u_lib.s9s_mb_2u(sch_1):page290_i70@pure_quanta.q_capp(chips)',
 PATH='I70',
 DRAWING='@S9S_MB_2U_LIB.S9S_MB_2U(SCH_1):PAGE276',
 PHYS_PAGE='290',
 XY='(-575,5175)',
 ROT='0',
 VER='1',
 PACK_TYPE='THLF',
 LOCATION='PC1204',
 CDS_LIB='pure_quanta',
 CDS_PART_NAME='Q_CAPP_THLF-560UF,2.5V,20%,OSCA',
 TOLERANCE='20%',
 MATERIAL='OSCON',
 VOLTAGE='2.5V',
 VALUE='560UF',
 PRIM_FILE='./archive_libs/logical/q_capp/chips/chips.prt';

PART_NAME
 PC1204_P1_3 'Q_CAP_C0402-1UF,16V,10%,X6S,CHA':;

SECTION_NUMBER 1
 '@S9S_MB_2U_LIB.S9S_MB_2U(SCH_1):PAGE276_I56@PURE_QUANTA.Q_CAP(CHIPS)':
 C_PATH='@s9s_mb_2u_lib.s9s_mb_2u(sch_1):page276_i56@pure_quanta.q_cap(chips)',
 P_PATH='@s9s_mb_2u_lib.s9s_mb_2u(sch_1):page290_i56@pure_quanta.q_cap(chips)',
 PATH='I56',
 DRAWING='@S9S_MB_2U_LIB.S9S_MB_2U(SCH_1):PAGE276',
 PHYS_PAGE='290',
 XY='(-2050,6425)',
 ROT='0',
 VER='1',
 PACK_TYPE='C0402',
 LOCATION='PC1204_P1_3',
 CDS_LIB='pure_quanta',
 CDS_PART_NAME='Q_CAP_C0402-1UF,16V,10%,X6S,CHA',
 TOLERANCE='10%',
 MATERIAL='X6S',
 VOLTAGE='16V',
 VALUE='1UF',
 PRIM_FILE='./archive_libs/logical/q_cap/chips/chips.prt';

PART_NAME
 PC1205 'Q_CAPP_SMLF-330UF,2.5V,+10/-35B':;

SECTION_NUMBER 1
 '@S9S_MB_2U_LIB.S9S_MB_2U(SCH_1):PAGE276_I72@PURE_QUANTA.Q_CAPP(CHIPS)':
 C_PATH='@s9s_mb_2u_lib.s9s_mb_2u(sch_1):page276_i72@pure_quanta.q_capp(chips)',
 P_PATH='@s9s_mb_2u_lib.s9s_mb_2u(sch_1):page290_i72@pure_quanta.q_capp(chips)',
 PATH='I72',
 DRAWING='@S9S_MB_2U_LIB.S9S_MB_2U(SCH_1):PAGE276',
 PHYS_PAGE='290',
 XY='(-75,5175)',
 ROT='0',
 VER='1',
 PACK_TYPE='SMLF',
 LOCATION='PC1205',
 CDS_LIB='pure_quanta',
 CDS_PART_NAME='Q_CAPP_SMLF-330UF,2.5V,+10/-35B',
 TOLERANCE='+10/-35%',
 MATERIAL='SPCAP',
 VOLTAGE='2.5V',
 VALUE='330UF',
 PRIM_FILE='./archive_libs/logical/q_capp/chips/chips.prt';

PART_NAME
 PC1206 'Q_CAP_C0805-22UF,4V,20%,X6S,CHA':;

SECTION_NUMBER 1
 '@S9S_MB_2U_LIB.S9S_MB_2U(SCH_1):PAGE268_I47@PURE_QUANTA.Q_CAP(CHIPS)':
 C_PATH='@s9s_mb_2u_lib.s9s_mb_2u(sch_1):page268_i47@pure_quanta.q_cap(chips)',
 P_PATH='@s9s_mb_2u_lib.s9s_mb_2u(sch_1):page282_i47@pure_quanta.q_cap(chips)',
 PATH='I47',
 DRAWING='@S9S_MB_2U_LIB.S9S_MB_2U(SCH_1):PAGE268',
 BOM_COST='VR_PCH',
 PHYS_PAGE='282',
 XY='(-1900,9650)',
 ROT='0',
 VER='1',
 PACK_TYPE='C0805',
 LOCATION='PC1206',
 CDS_LIB='pure_quanta',
 CDS_PART_NAME='Q_CAP_C0805-22UF,4V,20%,X6S,CHA',
 TOLERANCE='20%',
 MATERIAL='X6S',
 VOLTAGE='4V',
 VALUE='22UF',
 PRIM_FILE='./archive_libs/logical/q_cap/chips/chips.prt';

PART_NAME
 PC1206_P1_3 'Q_CAP_C0805-22UF,4V,20%,X6S,CHA':;

SECTION_NUMBER 1
 '@S9S_MB_2U_LIB.S9S_MB_2U(SCH_1):PAGE276_I66@PURE_QUANTA.Q_CAP(CHIPS)':
 C_PATH='@s9s_mb_2u_lib.s9s_mb_2u(sch_1):page276_i66@pure_quanta.q_cap(chips)',
 P_PATH='@s9s_mb_2u_lib.s9s_mb_2u(sch_1):page290_i66@pure_quanta.q_cap(chips)',
 PATH='I66',
 DRAWING='@S9S_MB_2U_LIB.S9S_MB_2U(SCH_1):PAGE276',
 PHYS_PAGE='290',
 XY='(-1625,6425)',
 ROT='0',
 VER='1',
 PACK_TYPE='C0805',
 LOCATION='PC1206_P1_3',
 CDS_LIB='pure_quanta',
 CDS_PART_NAME='Q_CAP_C0805-22UF,4V,20%,X6S,CHA',
 TOLERANCE='20%',
 MATERIAL='X6S',
 VOLTAGE='4V',
 VALUE='22UF',
 PRIM_FILE='./archive_libs/logical/q_cap/chips/chips.prt';

PART_NAME
 PC1207 'Q_CAP_C0805-22UF,4V,20%,X6S,CHA':;

SECTION_NUMBER 1
 '@S9S_MB_2U_LIB.S9S_MB_2U(SCH_1):PAGE286_I45@PURE_QUANTA.Q_CAP(CHIPS)':
 C_PATH='@s9s_mb_2u_lib.s9s_mb_2u(sch_1):page286_i45@pure_quanta.q_cap(chips)',
 P_PATH='@s9s_mb_2u_lib.s9s_mb_2u(sch_1):page300_i45@pure_quanta.q_cap(chips)',
 PATH='I45',
 DRAWING='@S9S_MB_2U_LIB.S9S_MB_2U(SCH_1):PAGE286',
 BOM_COST='VR_PCH',
 PHYS_PAGE='300',
 XY='(9250,7025)',
 ROT='0',
 VER='1',
 PACK_TYPE='C0805',
 LOCATION='PC1207',
 CDS_LIB='pure_quanta',
 CDS_PART_NAME='Q_CAP_C0805-22UF,4V,20%,X6S,CHA',
 TOLERANCE='20%',
 MATERIAL='X6S',
 VOLTAGE='4V',
 VALUE='22UF',
 PRIM_FILE='./archive_libs/logical/q_cap/chips/chips.prt';

PART_NAME
 PC1207_P1_4 'Q_CAP_C0805-22UF,4V,20%,X6S,CHA':;

SECTION_NUMBER 1
 '@S9S_MB_2U_LIB.S9S_MB_2U(SCH_1):PAGE276_I48@PURE_QUANTA.Q_CAP(CHIPS)':
 C_PATH='@s9s_mb_2u_lib.s9s_mb_2u(sch_1):page276_i48@pure_quanta.q_cap(chips)',
 P_PATH='@s9s_mb_2u_lib.s9s_mb_2u(sch_1):page290_i48@pure_quanta.q_cap(chips)',
 PATH='I48',
 DRAWING='@S9S_MB_2U_LIB.S9S_MB_2U(SCH_1):PAGE276',
 PHYS_PAGE='290',
 XY='(-1625,3625)',
 ROT='0',
 VER='1',
 PACK_TYPE='C0805',
 LOCATION='PC1207_P1_4',
 CDS_LIB='pure_quanta',
 CDS_PART_NAME='Q_CAP_C0805-22UF,4V,20%,X6S,CHA',
 TOLERANCE='20%',
 MATERIAL='X6S',
 VOLTAGE='4V',
 VALUE='22UF',
 PRIM_FILE='./archive_libs/logical/q_cap/chips/chips.prt';

PART_NAME
 PC1208_P1_3 'Q_CAP_C0805-22UF,4V,20%,X6S,CHA':;

SECTION_NUMBER 1
 '@S9S_MB_2U_LIB.S9S_MB_2U(SCH_1):PAGE276_I68@PURE_QUANTA.Q_CAP(CHIPS)':
 C_PATH='@s9s_mb_2u_lib.s9s_mb_2u(sch_1):page276_i68@pure_quanta.q_cap(chips)',
 P_PATH='@s9s_mb_2u_lib.s9s_mb_2u(sch_1):page290_i68@pure_quanta.q_cap(chips)',
 PATH='I68',
 DRAWING='@S9S_MB_2U_LIB.S9S_MB_2U(SCH_1):PAGE276',
 PHYS_PAGE='290',
 XY='(-1200,6425)',
 ROT='0',
 VER='1',
 PACK_TYPE='C0805',
 LOCATION='PC1208_P1_3',
 CDS_LIB='pure_quanta',
 CDS_PART_NAME='Q_CAP_C0805-22UF,4V,20%,X6S,CHA',
 TOLERANCE='20%',
 MATERIAL='X6S',
 VOLTAGE='4V',
 VALUE='22UF',
 PRIM_FILE='./archive_libs/logical/q_cap/chips/chips.prt';

PART_NAME
 PC1209_P1_4 'Q_CAP_C0805-22UF,4V,20%,X6S,CHA':;

SECTION_NUMBER 1
 '@S9S_MB_2U_LIB.S9S_MB_2U(SCH_1):PAGE276_I50@PURE_QUANTA.Q_CAP(CHIPS)':
 C_PATH='@s9s_mb_2u_lib.s9s_mb_2u(sch_1):page276_i50@pure_quanta.q_cap(chips)',
 P_PATH='@s9s_mb_2u_lib.s9s_mb_2u(sch_1):page290_i50@pure_quanta.q_cap(chips)',
 PATH='I50',
 DRAWING='@S9S_MB_2U_LIB.S9S_MB_2U(SCH_1):PAGE276',
 PHYS_PAGE='290',
 XY='(-1200,3625)',
 ROT='0',
 VER='1',
 PACK_TYPE='C0805',
 LOCATION='PC1209_P1_4',
 CDS_LIB='pure_quanta',
 CDS_PART_NAME='Q_CAP_C0805-22UF,4V,20%,X6S,CHA',
 TOLERANCE='20%',
 MATERIAL='X6S',
 VOLTAGE='4V',
 VALUE='22UF',
 PRIM_FILE='./archive_libs/logical/q_cap/chips/chips.prt';

PART_NAME
 PC1210 'Q_CAPP_THLF-270UF,16V,20%,OSCOA':;

SECTION_NUMBER 1
 '@S9S_MB_2U_LIB.S9S_MB_2U(SCH_1):PAGE276_I81@PURE_QUANTA.Q_CAPP(CHIPS)':
 C_PATH='@s9s_mb_2u_lib.s9s_mb_2u(sch_1):page276_i81@pure_quanta.q_capp(chips)',
 P_PATH='@s9s_mb_2u_lib.s9s_mb_2u(sch_1):page290_i81@pure_quanta.q_capp(chips)',
 PATH='I81',
 DRAWING='@S9S_MB_2U_LIB.S9S_MB_2U(SCH_1):PAGE276',
 PHYS_PAGE='290',
 XY='(-150,7275)',
 ROT='0',
 VER='1',
 PACK_TYPE='THLF',
 LOCATION='PC1210',
 CDS_LIB='pure_quanta',
 CDS_PART_NAME='Q_CAPP_THLF-270UF,16V,20%,OSCOA',
 TOLERANCE='20%',
 MATERIAL='OSCON',
 VOLTAGE='16V',
 VALUE='270UF',
 PRIM_FILE='./archive_libs/logical/q_capp/chips/chips.prt';

PART_NAME
 PC1211_P0_1 'Q_CAP_C0402-2.2UF,10V,10%,X6S,A':;

SECTION_NUMBER 1
 '@S9S_MB_2U_LIB.S9S_MB_2U(SCH_1):PAGE257_I42@PURE_QUANTA.Q_CAP(CHIPS)':
 C_PATH='@s9s_mb_2u_lib.s9s_mb_2u(sch_1):page257_i42@pure_quanta.q_cap(chips)',
 P_PATH='@s9s_mb_2u_lib.s9s_mb_2u(sch_1):page271_i42@pure_quanta.q_cap(chips)',
 PATH='I42',
 DRAWING='@S9S_MB_2U_LIB.S9S_MB_2U(SCH_1):PAGE257',
 PHYS_PAGE='271',
 XY='(-3725,6050)',
 ROT='0',
 VER='1',
 PACK_TYPE='C0402',
 LOCATION='PC1211_P0_1',
 CDS_LIB='pure_quanta',
 CDS_PART_NAME='Q_CAP_C0402-2.2UF,10V,10%,X6S,A',
 TOLERANCE='10%',
 MATERIAL='X6S',
 VOLTAGE='10V',
 VALUE='2.2UF',
 PRIM_FILE='./archive_libs/logical/q_cap/chips/chips.prt';

PART_NAME
 PC1212_P0_2 'Q_CAP_C0402-2.2UF,10V,10%,X6S,A':;

SECTION_NUMBER 1
 '@S9S_MB_2U_LIB.S9S_MB_2U(SCH_1):PAGE257_I21@PURE_QUANTA.Q_CAP(CHIPS)':
 C_PATH='@s9s_mb_2u_lib.s9s_mb_2u(sch_1):page257_i21@pure_quanta.q_cap(chips)',
 P_PATH='@s9s_mb_2u_lib.s9s_mb_2u(sch_1):page271_i21@pure_quanta.q_cap(chips)',
 PATH='I21',
 DRAWING='@S9S_MB_2U_LIB.S9S_MB_2U(SCH_1):PAGE257',
 PHYS_PAGE='271',
 XY='(-3725,3250)',
 ROT='0',
 VER='1',
 PACK_TYPE='C0402',
 LOCATION='PC1212_P0_2',
 CDS_LIB='pure_quanta',
 CDS_PART_NAME='Q_CAP_C0402-2.2UF,10V,10%,X6S,A',
 TOLERANCE='10%',
 MATERIAL='X6S',
 VOLTAGE='10V',
 VALUE='2.2UF',
 PRIM_FILE='./archive_libs/logical/q_cap/chips/chips.prt';

PART_NAME
 PC1213_P0_3 'Q_CAP_C0402-2.2UF,10V,10%,X6S,A':;

SECTION_NUMBER 1
 '@S9S_MB_2U_LIB.S9S_MB_2U(SCH_1):PAGE258_I28@PURE_QUANTA.Q_CAP(CHIPS)':
 C_PATH='@s9s_mb_2u_lib.s9s_mb_2u(sch_1):page258_i28@pure_quanta.q_cap(chips)',
 P_PATH='@s9s_mb_2u_lib.s9s_mb_2u(sch_1):page272_i28@pure_quanta.q_cap(chips)',
 PATH='I28',
 DRAWING='@S9S_MB_2U_LIB.S9S_MB_2U(SCH_1):PAGE258',
 PHYS_PAGE='272',
 XY='(-10175,5750)',
 ROT='0',
 VER='1',
 PACK_TYPE='C0402',
 LOCATION='PC1213_P0_3',
 CDS_LIB='pure_quanta',
 CDS_PART_NAME='Q_CAP_C0402-2.2UF,10V,10%,X6S,A',
 TOLERANCE='10%',
 MATERIAL='X6S',
 VOLTAGE='10V',
 VALUE='2.2UF',
 PRIM_FILE='./archive_libs/logical/q_cap/chips/chips.prt';

PART_NAME
 PC1214_P0_4 'Q_CAP_C0402-2.2UF,10V,10%,X6S,A':;

SECTION_NUMBER 1
 '@S9S_MB_2U_LIB.S9S_MB_2U(SCH_1):PAGE258_I18@PURE_QUANTA.Q_CAP(CHIPS)':
 C_PATH='@s9s_mb_2u_lib.s9s_mb_2u(sch_1):page258_i18@pure_quanta.q_cap(chips)',
 P_PATH='@s9s_mb_2u_lib.s9s_mb_2u(sch_1):page272_i18@pure_quanta.q_cap(chips)',
 PATH='I18',
 DRAWING='@S9S_MB_2U_LIB.S9S_MB_2U(SCH_1):PAGE258',
 PHYS_PAGE='272',
 XY='(-10175,2950)',
 ROT='0',
 VER='1',
 PACK_TYPE='C0402',
 LOCATION='PC1214_P0_4',
 CDS_LIB='pure_quanta',
 CDS_PART_NAME='Q_CAP_C0402-2.2UF,10V,10%,X6S,A',
 TOLERANCE='10%',
 MATERIAL='X6S',
 VOLTAGE='10V',
 VALUE='2.2UF',
 PRIM_FILE='./archive_libs/logical/q_cap/chips/chips.prt';

PART_NAME
 PC1215 'Q_CAPP_SMLF-100UF,16V,20%,OSCOA':;

SECTION_NUMBER 1
 '@S9S_MB_2U_LIB.S9S_MB_2U(SCH_1):PAGE248_I23@PURE_QUANTA.Q_CAPP(CHIPS)':
 C_PATH='@s9s_mb_2u_lib.s9s_mb_2u(sch_1):page248_i23@pure_quanta.q_capp(chips)',
 P_PATH='@s9s_mb_2u_lib.s9s_mb_2u(sch_1):page262_i23@pure_quanta.q_capp(chips)',
 PATH='I23',
 DRAWING='@S9S_MB_2U_LIB.S9S_MB_2U(SCH_1):PAGE248',
 BOM_COST='VR_SYSTEM ',
 PHYS_PAGE='262',
 XY='(-4325,375)',
 ROT='0',
 VER='1',
 PACK_TYPE='SMLF',
 CDS_LIB='pure_quanta',
 CDS_PART_NAME='Q_CAPP_SMLF-100UF,16V,20%,OSCOA',
 TOLERANCE='20%',
 MATERIAL='OSCON',
 VOLTAGE='16V',
 VALUE='100UF',
 PRIM_FILE='./archive_libs/logical/q_capp/chips/chips.prt';

PART_NAME
 PC1216 'Q_CAP_C0805-22UF,16V,20%,X6S,CA':;

SECTION_NUMBER 1
 '@S9S_MB_2U_LIB.S9S_MB_2U(SCH_1):PAGE248_I25@PURE_QUANTA.Q_CAP(CHIPS)':
 C_PATH='@s9s_mb_2u_lib.s9s_mb_2u(sch_1):page248_i25@pure_quanta.q_cap(chips)',
 P_PATH='@s9s_mb_2u_lib.s9s_mb_2u(sch_1):page262_i25@pure_quanta.q_cap(chips)',
 PATH='I25',
 DRAWING='@S9S_MB_2U_LIB.S9S_MB_2U(SCH_1):PAGE248',
 BOM_COST='VR_PCH',
 PHYS_PAGE='262',
 XY='(-3725,375)',
 ROT='0',
 VER='1',
 PACK_TYPE='C0805',
 LOCATION='PC1216',
 CDS_LIB='pure_quanta',
 CDS_PART_NAME='Q_CAP_C0805-22UF,16V,20%,X6S,CA',
 TOLERANCE='20%',
 MATERIAL='X6S',
 VOLTAGE='16V',
 VALUE='22UF',
 PRIM_FILE='./archive_libs/logical/q_cap/chips/chips.prt';

PART_NAME
 PC1217 'Q_CAP_C0805-22UF,16V,20%,X6S,CA':;

SECTION_NUMBER 1
 '@S9S_MB_2U_LIB.S9S_MB_2U(SCH_1):PAGE248_I28@PURE_QUANTA.Q_CAP(CHIPS)':
 C_PATH='@s9s_mb_2u_lib.s9s_mb_2u(sch_1):page248_i28@pure_quanta.q_cap(chips)',
 P_PATH='@s9s_mb_2u_lib.s9s_mb_2u(sch_1):page262_i28@pure_quanta.q_cap(chips)',
 PATH='I28',
 DRAWING='@S9S_MB_2U_LIB.S9S_MB_2U(SCH_1):PAGE248',
 BOM_COST='VR_PCH',
 PHYS_PAGE='262',
 XY='(-3275,375)',
 ROT='0',
 VER='1',
 PACK_TYPE='C0805',
 LOCATION='PC1217',
 CDS_LIB='pure_quanta',
 CDS_PART_NAME='Q_CAP_C0805-22UF,16V,20%,X6S,CA',
 TOLERANCE='20%',
 MATERIAL='X6S',
 VOLTAGE='16V',
 VALUE='22UF',
 PRIM_FILE='./archive_libs/logical/q_cap/chips/chips.prt';

PART_NAME
 PC1218 'Q_CAP_C0805-22UF,16V,20%,X6S,CA':;

SECTION_NUMBER 1
 '@S9S_MB_2U_LIB.S9S_MB_2U(SCH_1):PAGE248_I29@PURE_QUANTA.Q_CAP(CHIPS)':
 C_PATH='@s9s_mb_2u_lib.s9s_mb_2u(sch_1):page248_i29@pure_quanta.q_cap(chips)',
 P_PATH='@s9s_mb_2u_lib.s9s_mb_2u(sch_1):page262_i29@pure_quanta.q_cap(chips)',
 PATH='I29',
 DRAWING='@S9S_MB_2U_LIB.S9S_MB_2U(SCH_1):PAGE248',
 BOM_COST='VR_PCH',
 PHYS_PAGE='262',
 XY='(-2850,375)',
 ROT='0',
 VER='1',
 PACK_TYPE='C0805',
 LOCATION='PC1218',
 CDS_LIB='pure_quanta',
 CDS_PART_NAME='Q_CAP_C0805-22UF,16V,20%,X6S,CA',
 TOLERANCE='20%',
 MATERIAL='X6S',
 VOLTAGE='16V',
 VALUE='22UF',
 PRIM_FILE='./archive_libs/logical/q_cap/chips/chips.prt';

PART_NAME
 PC1219 'Q_CAP_C0402-1UF,16V,10%,X6S,CHA':;

SECTION_NUMBER 1
 '@S9S_MB_2U_LIB.S9S_MB_2U(SCH_1):PAGE248_I30@PURE_QUANTA.Q_CAP(CHIPS)':
 C_PATH='@s9s_mb_2u_lib.s9s_mb_2u(sch_1):page248_i30@pure_quanta.q_cap(chips)',
 P_PATH='@s9s_mb_2u_lib.s9s_mb_2u(sch_1):page262_i30@pure_quanta.q_cap(chips)',
 PATH='I30',
 DRAWING='@S9S_MB_2U_LIB.S9S_MB_2U(SCH_1):PAGE248',
 PHYS_PAGE='262',
 XY='(-2425,375)',
 ROT='0',
 VER='1',
 PACK_TYPE='C0402',
 LOCATION='PC1219',
 CDS_LIB='pure_quanta',
 CDS_PART_NAME='Q_CAP_C0402-1UF,16V,10%,X6S,CHA',
 TOLERANCE='10%',
 MATERIAL='X6S',
 VOLTAGE='16V',
 VALUE='1UF',
 PRIM_FILE='./archive_libs/logical/q_cap/chips/chips.prt';

PART_NAME
 PC1221 'Q_CAP_0402-0.1UF,25V,10%,X7R,CA':;

SECTION_NUMBER 1
 '@S9S_MB_2U_LIB.S9S_MB_2U(SCH_1):PAGE248_I16@PURE_QUANTA.Q_CAP(CHIPS)':
 C_PATH='@s9s_mb_2u_lib.s9s_mb_2u(sch_1):page248_i16@pure_quanta.q_cap(chips)',
 P_PATH='@s9s_mb_2u_lib.s9s_mb_2u(sch_1):page262_i16@pure_quanta.q_cap(chips)',
 PATH='I16',
 DRAWING='@S9S_MB_2U_LIB.S9S_MB_2U(SCH_1):PAGE248',
 PHYS_PAGE='262',
 XY='(175,-1275)',
 ROT='0',
 VER='1',
 PACK_TYPE='0402',
 LOCATION='PC1221',
 CDS_LIB='pure_quanta',
 CDS_PART_NAME='Q_CAP_0402-0.1UF,25V,10%,X7R,CA',
 TOLERANCE='10%',
 MATERIAL='X7R',
 VOLTAGE='25V',
 VALUE='0.1UF',
 PRIM_FILE='./archive_libs/logical/q_cap/chips/chips.prt';

PART_NAME
 PC1222 'Q_CAP_C0402-0.22UF,25V,10%,X7RA':;

SECTION_NUMBER 1
 '@S9S_MB_2U_LIB.S9S_MB_2U(SCH_1):PAGE248_I31@PURE_QUANTA.Q_CAP(CHIPS)':
 C_PATH='@s9s_mb_2u_lib.s9s_mb_2u(sch_1):page248_i31@pure_quanta.q_cap(chips)',
 P_PATH='@s9s_mb_2u_lib.s9s_mb_2u(sch_1):page262_i31@pure_quanta.q_cap(chips)',
 PATH='I31',
 DRAWING='@S9S_MB_2U_LIB.S9S_MB_2U(SCH_1):PAGE248',
 PHYS_PAGE='262',
 XY='(350,-125)',
 ROT='0',
 VER='1',
 PACK_TYPE='C0402',
 LOCATION='PC1222',
 CDS_LIB='pure_quanta',
 CDS_PART_NAME='Q_CAP_C0402-0.22UF,25V,10%,X7RA',
 TOLERANCE='10%',
 MATERIAL='X7R',
 VOLTAGE='25V',
 VALUE='0.22UF',
 PRIM_FILE='./archive_libs/logical/q_cap/chips/chips.prt';

PART_NAME
 PC1223 'Q_CAP_0402-680PF,50V,10%,X7R,TA':;

SECTION_NUMBER 1
 '@S9S_MB_2U_LIB.S9S_MB_2U(SCH_1):PAGE248_I35@PURE_QUANTA.Q_CAP(CHIPS)':
 C_PATH='@s9s_mb_2u_lib.s9s_mb_2u(sch_1):page248_i35@pure_quanta.q_cap(chips)',
 P_PATH='@s9s_mb_2u_lib.s9s_mb_2u(sch_1):page262_i35@pure_quanta.q_cap(chips)',
 PATH='I35',
 DRAWING='@S9S_MB_2U_LIB.S9S_MB_2U(SCH_1):PAGE248',
 PHYS_PAGE='262',
 XY='(1650,-1275)',
 ROT='0',
 VER='2',
 PACK_TYPE='0402',
 LOCATION='PC1223',
 CDS_LIB='pure_quanta',
 CDS_PART_NAME='Q_CAP_0402-680PF,50V,10%,X7R,TA',
 TOLERANCE='10%',
 MATERIAL='X7R',
 VOLTAGE='50V',
 VALUE='680PF',
 PRIM_FILE='./archive_libs/logical/q_cap/chips/chips.prt';

PART_NAME
 PC1224 'Q_CAP_0402-0.1UF,25V,10%,X7R,CA':;

SECTION_NUMBER 1
 '@S9S_MB_2U_LIB.S9S_MB_2U(SCH_1):PAGE248_I38@PURE_QUANTA.Q_CAP(CHIPS)':
 C_PATH='@s9s_mb_2u_lib.s9s_mb_2u(sch_1):page248_i38@pure_quanta.q_cap(chips)',
 P_PATH='@s9s_mb_2u_lib.s9s_mb_2u(sch_1):page262_i38@pure_quanta.q_cap(chips)',
 PATH='I38',
 DRAWING='@S9S_MB_2U_LIB.S9S_MB_2U(SCH_1):PAGE248',
 PHYS_PAGE='262',
 XY='(2225,-550)',
 ROT='0',
 VER='1',
 PACK_TYPE='0402',
 LOCATION='PC1224',
 CDS_LIB='pure_quanta',
 CDS_PART_NAME='Q_CAP_0402-0.1UF,25V,10%,X7R,CA',
 TOLERANCE='10%',
 MATERIAL='X7R',
 VOLTAGE='25V',
 VALUE='0.1UF',
 PRIM_FILE='./archive_libs/logical/q_cap/chips/chips.prt';

PART_NAME
 PC1225 'Q_CAP_C0805-47UF,4V,20%,X6S,CHA':;

SECTION_NUMBER 1
 '@S9S_MB_2U_LIB.S9S_MB_2U(SCH_1):PAGE248_I44@PURE_QUANTA.Q_CAP(CHIPS)':
 C_PATH='@s9s_mb_2u_lib.s9s_mb_2u(sch_1):page248_i44@pure_quanta.q_cap(chips)',
 P_PATH='@s9s_mb_2u_lib.s9s_mb_2u(sch_1):page262_i44@pure_quanta.q_cap(chips)',
 PATH='I44',
 DRAWING='@S9S_MB_2U_LIB.S9S_MB_2U(SCH_1):PAGE248',
 BOM_COST='VR_PCH',
 PHYS_PAGE='262',
 XY='(2650,-550)',
 ROT='0',
 VER='1',
 PACK_TYPE='C0805',
 LOCATION='PC1225',
 CDS_LIB='pure_quanta',
 CDS_PART_NAME='Q_CAP_C0805-47UF,4V,20%,X6S,CHA',
 TOLERANCE='20%',
 MATERIAL='X6S',
 VOLTAGE='4V',
 VALUE='47UF',
 PRIM_FILE='./archive_libs/logical/q_cap/chips/chips.prt';

PART_NAME
 PC1226 'Q_CAP_C0805-47UF,4V,20%,X6S,CHA':;

SECTION_NUMBER 1
 '@S9S_MB_2U_LIB.S9S_MB_2U(SCH_1):PAGE248_I45@PURE_QUANTA.Q_CAP(CHIPS)':
 C_PATH='@s9s_mb_2u_lib.s9s_mb_2u(sch_1):page248_i45@pure_quanta.q_cap(chips)',
 P_PATH='@s9s_mb_2u_lib.s9s_mb_2u(sch_1):page262_i45@pure_quanta.q_cap(chips)',
 PATH='I45',
 DRAWING='@S9S_MB_2U_LIB.S9S_MB_2U(SCH_1):PAGE248',
 BOM_COST='VR_PCH',
 PHYS_PAGE='262',
 XY='(3025,-550)',
 ROT='0',
 VER='1',
 PACK_TYPE='C0805',
 LOCATION='PC1226',
 CDS_LIB='pure_quanta',
 CDS_PART_NAME='Q_CAP_C0805-47UF,4V,20%,X6S,CHA',
 TOLERANCE='20%',
 MATERIAL='X6S',
 VOLTAGE='4V',
 VALUE='47UF',
 PRIM_FILE='./archive_libs/logical/q_cap/chips/chips.prt';

PART_NAME
 PC1227 'Q_CAPP_THLF-560UF,2.5V,20%,OSCA':;

SECTION_NUMBER 1
 '@S9S_MB_2U_LIB.S9S_MB_2U(SCH_1):PAGE248_I41@PURE_QUANTA.Q_CAPP(CHIPS)':
 C_PATH='@s9s_mb_2u_lib.s9s_mb_2u(sch_1):page248_i41@pure_quanta.q_capp(chips)',
 P_PATH='@s9s_mb_2u_lib.s9s_mb_2u(sch_1):page262_i41@pure_quanta.q_capp(chips)',
 PATH='I41',
 DRAWING='@S9S_MB_2U_LIB.S9S_MB_2U(SCH_1):PAGE248',
 OSCON='OSCON',
 BOM_COST='VR_PCH',
 PHYS_PAGE='262',
 XY='(3275,-2500)',
 ROT='0',
 VER='1',
 PACK_TYPE='THLF',
 LOCATION='PC1227',
 CDS_LIB='pure_quanta',
 CDS_PART_NAME='Q_CAPP_THLF-560UF,2.5V,20%,OSCA',
 TOLERANCE='20%',
 MATERIAL='OSCON',
 VOLTAGE='2.5V',
 VALUE='560UF',
 PRIM_FILE='./archive_libs/logical/q_capp/chips/chips.prt';

PART_NAME
 PC1229 'Q_CAPP_SMLF-330UF,2V,35%,SPCAPA':;

SECTION_NUMBER 1
 '@S9S_MB_2U_LIB.S9S_MB_2U(SCH_1):PAGE248_I47@PURE_QUANTA.Q_CAPP(CHIPS)':
 C_PATH='@s9s_mb_2u_lib.s9s_mb_2u(sch_1):page248_i47@pure_quanta.q_capp(chips)',
 P_PATH='@s9s_mb_2u_lib.s9s_mb_2u(sch_1):page262_i47@pure_quanta.q_capp(chips)',
 PATH='I47',
 DRAWING='@S9S_MB_2U_LIB.S9S_MB_2U(SCH_1):PAGE248',
 BOM_COST='VR_PCH',
 PHYS_PAGE='262',
 XY='(3450,-550)',
 ROT='0',
 VER='1',
 PACK_TYPE='SMLF',
 LOCATION='PC1229',
 CDS_LIB='pure_quanta',
 CDS_PART_NAME='Q_CAPP_SMLF-330UF,2V,35%,SPCAPA',
 TOLERANCE='35%',
 MATERIAL='SPCAP',
 VOLTAGE='2V',
 VALUE='330UF',
 PRIM_FILE='./archive_libs/logical/q_capp/chips/chips.prt';

PART_NAME
 PC1230 'Q_CAPP_THLF-560UF,2.5V,20%,OSCA':;

SECTION_NUMBER 1
 '@S9S_MB_2U_LIB.S9S_MB_2U(SCH_1):PAGE248_I48@PURE_QUANTA.Q_CAPP(CHIPS)':
 C_PATH='@s9s_mb_2u_lib.s9s_mb_2u(sch_1):page248_i48@pure_quanta.q_capp(chips)',
 P_PATH='@s9s_mb_2u_lib.s9s_mb_2u(sch_1):page262_i48@pure_quanta.q_capp(chips)',
 PATH='I48',
 DRAWING='@S9S_MB_2U_LIB.S9S_MB_2U(SCH_1):PAGE248',
 OSCON='OSCON',
 BOM_COST='VR_PCH',
 PHYS_PAGE='262',
 XY='(3675,-2500)',
 ROT='0',
 VER='1',
 PACK_TYPE='THLF',
 LOCATION='PC1230',
 CDS_LIB='pure_quanta',
 CDS_PART_NAME='Q_CAPP_THLF-560UF,2.5V,20%,OSCA',
 TOLERANCE='20%',
 MATERIAL='OSCON',
 VOLTAGE='2.5V',
 VALUE='560UF',
 PRIM_FILE='./archive_libs/logical/q_capp/chips/chips.prt';

PART_NAME
 PC1232 'Q_CAP_C0805-10UF,16V,10%,X6S,CB':;

SECTION_NUMBER 1
 '@S9S_MB_2U_LIB.S9S_MB_2U(SCH_1):PAGE249_I19@PURE_QUANTA.Q_CAP(CHIPS)':
 C_PATH='@s9s_mb_2u_lib.s9s_mb_2u(sch_1):page249_i19@pure_quanta.q_cap(chips)',
 P_PATH='@s9s_mb_2u_lib.s9s_mb_2u(sch_1):page263_i19@pure_quanta.q_cap(chips)',
 PATH='I19',
 DRAWING='@S9S_MB_2U_LIB.S9S_MB_2U(SCH_1):PAGE249',
 PHYS_PAGE='263',
 XY='(-5475,7050)',
 ROT='0',
 VER='1',
 PACK_TYPE='C0805',
 LOCATION='PC1232',
 CDS_LIB='pure_quanta',
 CDS_PART_NAME='Q_CAP_C0805-10UF,16V,10%,X6S,CC',
 TOLERANCE='10%',
 MATERIAL='X6S',
 VOLTAGE='16V',
 VALUE='10UF',
 PRIM_FILE='./archive_libs/logical/q_cap/chips/chips.prt';

PART_NAME
 PC1233 'Q_CAP_C0805-10UF,16V,10%,X6S,CB':;

SECTION_NUMBER 1
 '@S9S_MB_2U_LIB.S9S_MB_2U(SCH_1):PAGE249_I20@PURE_QUANTA.Q_CAP(CHIPS)':
 C_PATH='@s9s_mb_2u_lib.s9s_mb_2u(sch_1):page249_i20@pure_quanta.q_cap(chips)',
 P_PATH='@s9s_mb_2u_lib.s9s_mb_2u(sch_1):page263_i20@pure_quanta.q_cap(chips)',
 PATH='I20',
 DRAWING='@S9S_MB_2U_LIB.S9S_MB_2U(SCH_1):PAGE249',
 PHYS_PAGE='263',
 XY='(-5025,7050)',
 ROT='0',
 VER='1',
 PACK_TYPE='C0805',
 LOCATION='PC1233',
 CDS_LIB='pure_quanta',
 CDS_PART_NAME='Q_CAP_C0805-10UF,16V,10%,X6S,CC',
 TOLERANCE='10%',
 MATERIAL='X6S',
 VOLTAGE='16V',
 VALUE='10UF',
 PRIM_FILE='./archive_libs/logical/q_cap/chips/chips.prt';

PART_NAME
 PC1234 'Q_CAP_C0402-100NF,50V,10%,X7R,A':;

SECTION_NUMBER 1
 '@S9S_MB_2U_LIB.S9S_MB_2U(SCH_1):PAGE249_I21@PURE_QUANTA.Q_CAP(CHIPS)':
 C_PATH='@s9s_mb_2u_lib.s9s_mb_2u(sch_1):page249_i21@pure_quanta.q_cap(chips)',
 P_PATH='@s9s_mb_2u_lib.s9s_mb_2u(sch_1):page263_i21@pure_quanta.q_cap(chips)',
 PATH='I21',
 DRAWING='@S9S_MB_2U_LIB.S9S_MB_2U(SCH_1):PAGE249',
 PHYS_PAGE='263',
 XY='(-4600,7050)',
 ROT='0',
 VER='1',
 PACK_TYPE='C0402',
 LOCATION='PC1234',
 CDS_LIB='pure_quanta',
 CDS_PART_NAME='Q_CAP_C0402-100NF,50V,10%,X7R,A',
 TOLERANCE='10%',
 MATERIAL='X7R',
 VOLTAGE='50V',
 VALUE='100NF',
 PRIM_FILE='./archive_libs/logical/q_cap/chips/chips.prt';

PART_NAME
 PC1235 'Q_CAP_C0402-0.22UF,25V,10%,X7RA':;

SECTION_NUMBER 1
 '@S9S_MB_2U_LIB.S9S_MB_2U(SCH_1):PAGE249_I30@PURE_QUANTA.Q_CAP(CHIPS)':
 C_PATH='@s9s_mb_2u_lib.s9s_mb_2u(sch_1):page249_i30@pure_quanta.q_cap(chips)',
 P_PATH='@s9s_mb_2u_lib.s9s_mb_2u(sch_1):page263_i30@pure_quanta.q_cap(chips)',
 PATH='I30',
 DRAWING='@S9S_MB_2U_LIB.S9S_MB_2U(SCH_1):PAGE249',
 PHYS_PAGE='263',
 XY='(-1875,6475)',
 ROT='0',
 VER='1',
 PACK_TYPE='C0402',
 LOCATION='PC1235',
 CDS_LIB='pure_quanta',
 CDS_PART_NAME='Q_CAP_C0402-0.22UF,25V,10%,X7RA',
 TOLERANCE='10%',
 MATERIAL='X7R',
 VOLTAGE='25V',
 VALUE='0.22UF',
 PRIM_FILE='./archive_libs/logical/q_cap/chips/chips.prt';

PART_NAME
 PC1236 'Q_CAP_C0402-100NF,50V,10%,X7R,A':;

SECTION_NUMBER 1
 '@S9S_MB_2U_LIB.S9S_MB_2U(SCH_1):PAGE249_I28@PURE_QUANTA.Q_CAP(CHIPS)':
 C_PATH='@s9s_mb_2u_lib.s9s_mb_2u(sch_1):page249_i28@pure_quanta.q_cap(chips)',
 P_PATH='@s9s_mb_2u_lib.s9s_mb_2u(sch_1):page263_i28@pure_quanta.q_cap(chips)',
 PATH='I28',
 DRAWING='@S9S_MB_2U_LIB.S9S_MB_2U(SCH_1):PAGE249',
 PHYS_PAGE='263',
 XY='(-925,6050)',
 ROT='0',
 VER='1',
 PACK_TYPE='C0402',
 LOCATION='PC1236',
 CDS_LIB='pure_quanta',
 CDS_PART_NAME='Q_CAP_C0402-100NF,50V,10%,X7R,A',
 TOLERANCE='10%',
 MATERIAL='X7R',
 VOLTAGE='50V',
 VALUE='100NF',
 PRIM_FILE='./archive_libs/logical/q_cap/chips/chips.prt';

PART_NAME
 PC1237 'Q_CAP_C0805-22UF,4V,20%,X6S,CHA':;

SECTION_NUMBER 1
 '@S9S_MB_2U_LIB.S9S_MB_2U(SCH_1):PAGE249_I29@PURE_QUANTA.Q_CAP(CHIPS)':
 C_PATH='@s9s_mb_2u_lib.s9s_mb_2u(sch_1):page249_i29@pure_quanta.q_cap(chips)',
 P_PATH='@s9s_mb_2u_lib.s9s_mb_2u(sch_1):page263_i29@pure_quanta.q_cap(chips)',
 PATH='I29',
 DRAWING='@S9S_MB_2U_LIB.S9S_MB_2U(SCH_1):PAGE249',
 BOM_COST='VR_PCH',
 PHYS_PAGE='263',
 XY='(-525,6050)',
 ROT='0',
 VER='1',
 PACK_TYPE='C0805',
 LOCATION='PC1237',
 CDS_LIB='pure_quanta',
 CDS_PART_NAME='Q_CAP_C0805-22UF,4V,20%,X6S,CHA',
 TOLERANCE='20%',
 MATERIAL='X6S',
 VOLTAGE='4V',
 VALUE='22UF',
 PRIM_FILE='./archive_libs/logical/q_cap/chips/chips.prt';

PART_NAME
 PC1238 'Q_CAP_C0805-22UF,4V,20%,X6S,CHA':;

SECTION_NUMBER 1
 '@S9S_MB_2U_LIB.S9S_MB_2U(SCH_1):PAGE249_I37@PURE_QUANTA.Q_CAP(CHIPS)':
 C_PATH='@s9s_mb_2u_lib.s9s_mb_2u(sch_1):page249_i37@pure_quanta.q_cap(chips)',
 P_PATH='@s9s_mb_2u_lib.s9s_mb_2u(sch_1):page263_i37@pure_quanta.q_cap(chips)',
 PATH='I37',
 DRAWING='@S9S_MB_2U_LIB.S9S_MB_2U(SCH_1):PAGE249',
 BOM_COST='VR_PCH',
 PHYS_PAGE='263',
 XY='(-150,6050)',
 ROT='0',
 VER='1',
 PACK_TYPE='C0805',
 LOCATION='PC1238',
 CDS_LIB='pure_quanta',
 CDS_PART_NAME='Q_CAP_C0805-22UF,4V,20%,X6S,CHA',
 TOLERANCE='20%',
 MATERIAL='X6S',
 VOLTAGE='4V',
 VALUE='22UF',
 PRIM_FILE='./archive_libs/logical/q_cap/chips/chips.prt';

PART_NAME
 PC1239 'Q_CAP_C0805-22UF,4V,20%,X6S,CHA':;

SECTION_NUMBER 1
 '@S9S_MB_2U_LIB.S9S_MB_2U(SCH_1):PAGE249_I38@PURE_QUANTA.Q_CAP(CHIPS)':
 C_PATH='@s9s_mb_2u_lib.s9s_mb_2u(sch_1):page249_i38@pure_quanta.q_cap(chips)',
 P_PATH='@s9s_mb_2u_lib.s9s_mb_2u(sch_1):page263_i38@pure_quanta.q_cap(chips)',
 PATH='I38',
 DRAWING='@S9S_MB_2U_LIB.S9S_MB_2U(SCH_1):PAGE249',
 BOM_COST='VR_PCH',
 PHYS_PAGE='263',
 XY='(225,6050)',
 ROT='0',
 VER='1',
 PACK_TYPE='C0805',
 LOCATION='PC1239',
 CDS_LIB='pure_quanta',
 CDS_PART_NAME='Q_CAP_C0805-22UF,4V,20%,X6S,CHA',
 TOLERANCE='20%',
 MATERIAL='X6S',
 VOLTAGE='4V',
 VALUE='22UF',
 PRIM_FILE='./archive_libs/logical/q_cap/chips/chips.prt';

PART_NAME
 PC1240 'Q_CAP_C0805-22UF,4V,20%,X6S,CHA':;

SECTION_NUMBER 1
 '@S9S_MB_2U_LIB.S9S_MB_2U(SCH_1):PAGE249_I39@PURE_QUANTA.Q_CAP(CHIPS)':
 C_PATH='@s9s_mb_2u_lib.s9s_mb_2u(sch_1):page249_i39@pure_quanta.q_cap(chips)',
 P_PATH='@s9s_mb_2u_lib.s9s_mb_2u(sch_1):page263_i39@pure_quanta.q_cap(chips)',
 PATH='I39',
 DRAWING='@S9S_MB_2U_LIB.S9S_MB_2U(SCH_1):PAGE249',
 BOM_COST='VR_PCH',
 PHYS_PAGE='263',
 XY='(600,6050)',
 ROT='0',
 VER='1',
 PACK_TYPE='C0805',
 LOCATION='PC1240',
 CDS_LIB='pure_quanta',
 CDS_PART_NAME='Q_CAP_C0805-22UF,4V,20%,X6S,CHA',
 TOLERANCE='20%',
 MATERIAL='X6S',
 VOLTAGE='4V',
 VALUE='22UF',
 PRIM_FILE='./archive_libs/logical/q_cap/chips/chips.prt';

PART_NAME
 PC1241 'Q_CAP_C0805-22UF,4V,20%,X6S,CHA':;

SECTION_NUMBER 1
 '@S9S_MB_2U_LIB.S9S_MB_2U(SCH_1):PAGE249_I41@PURE_QUANTA.Q_CAP(CHIPS)':
 C_PATH='@s9s_mb_2u_lib.s9s_mb_2u(sch_1):page249_i41@pure_quanta.q_cap(chips)',
 P_PATH='@s9s_mb_2u_lib.s9s_mb_2u(sch_1):page263_i41@pure_quanta.q_cap(chips)',
 PATH='I41',
 DRAWING='@S9S_MB_2U_LIB.S9S_MB_2U(SCH_1):PAGE249',
 BOM_COST='VR_PCH',
 PHYS_PAGE='263',
 XY='(975,6050)',
 ROT='0',
 VER='1',
 PACK_TYPE='C0805',
 LOCATION='PC1241',
 CDS_LIB='pure_quanta',
 CDS_PART_NAME='Q_CAP_C0805-22UF,4V,20%,X6S,CHA',
 TOLERANCE='20%',
 MATERIAL='X6S',
 VOLTAGE='4V',
 VALUE='22UF',
 PRIM_FILE='./archive_libs/logical/q_cap/chips/chips.prt';

PART_NAME
 PC1242_P1_1 'Q_CAP_C0402-2.2UF,10V,10%,X6S,A':;

SECTION_NUMBER 1
 '@S9S_MB_2U_LIB.S9S_MB_2U(SCH_1):PAGE275_I31@PURE_QUANTA.Q_CAP(CHIPS)':
 C_PATH='@s9s_mb_2u_lib.s9s_mb_2u(sch_1):page275_i31@pure_quanta.q_cap(chips)',
 P_PATH='@s9s_mb_2u_lib.s9s_mb_2u(sch_1):page289_i31@pure_quanta.q_cap(chips)',
 PATH='I31',
 DRAWING='@S9S_MB_2U_LIB.S9S_MB_2U(SCH_1):PAGE275',
 PHYS_PAGE='289',
 XY='(-9725,5525)',
 ROT='0',
 VER='1',
 PACK_TYPE='C0402',
 LOCATION='PC1242_P1_1',
 CDS_LIB='pure_quanta',
 CDS_PART_NAME='Q_CAP_C0402-2.2UF,10V,10%,X6S,A',
 TOLERANCE='10%',
 MATERIAL='X6S',
 VOLTAGE='10V',
 VALUE='2.2UF',
 PRIM_FILE='./archive_libs/logical/q_cap/chips/chips.prt';

PART_NAME
 PC1243_P1_2 'Q_CAP_C0402-2.2UF,10V,10%,X6S,A':;

SECTION_NUMBER 1
 '@S9S_MB_2U_LIB.S9S_MB_2U(SCH_1):PAGE275_I16@PURE_QUANTA.Q_CAP(CHIPS)':
 C_PATH='@s9s_mb_2u_lib.s9s_mb_2u(sch_1):page275_i16@pure_quanta.q_cap(chips)',
 P_PATH='@s9s_mb_2u_lib.s9s_mb_2u(sch_1):page289_i16@pure_quanta.q_cap(chips)',
 PATH='I16',
 DRAWING='@S9S_MB_2U_LIB.S9S_MB_2U(SCH_1):PAGE275',
 PHYS_PAGE='289',
 XY='(-9725,2725)',
 ROT='0',
 VER='1',
 PACK_TYPE='C0402',
 LOCATION='PC1243_P1_2',
 CDS_LIB='pure_quanta',
 CDS_PART_NAME='Q_CAP_C0402-2.2UF,10V,10%,X6S,A',
 TOLERANCE='10%',
 MATERIAL='X6S',
 VOLTAGE='10V',
 VALUE='2.2UF',
 PRIM_FILE='./archive_libs/logical/q_cap/chips/chips.prt';

PART_NAME
 PC1244_P1_3 'Q_CAP_C0402-2.2UF,10V,10%,X6S,A':;

SECTION_NUMBER 1
 '@S9S_MB_2U_LIB.S9S_MB_2U(SCH_1):PAGE276_I31@PURE_QUANTA.Q_CAP(CHIPS)':
 C_PATH='@s9s_mb_2u_lib.s9s_mb_2u(sch_1):page276_i31@pure_quanta.q_cap(chips)',
 P_PATH='@s9s_mb_2u_lib.s9s_mb_2u(sch_1):page290_i31@pure_quanta.q_cap(chips)',
 PATH='I31',
 DRAWING='@S9S_MB_2U_LIB.S9S_MB_2U(SCH_1):PAGE276',
 PHYS_PAGE='290',
 XY='(-6800,7475)',
 ROT='0',
 VER='1',
 PACK_TYPE='C0402',
 LOCATION='PC1244_P1_3',
 CDS_LIB='pure_quanta',
 CDS_PART_NAME='Q_CAP_C0402-2.2UF,10V,10%,X6S,A',
 TOLERANCE='10%',
 MATERIAL='X6S',
 VOLTAGE='10V',
 VALUE='2.2UF',
 PRIM_FILE='./archive_libs/logical/q_cap/chips/chips.prt';

PART_NAME
 PC1245_P1_4 'Q_CAP_C0402-2.2UF,10V,10%,X6S,A':;

SECTION_NUMBER 1
 '@S9S_MB_2U_LIB.S9S_MB_2U(SCH_1):PAGE276_I20@PURE_QUANTA.Q_CAP(CHIPS)':
 C_PATH='@s9s_mb_2u_lib.s9s_mb_2u(sch_1):page276_i20@pure_quanta.q_cap(chips)',
 P_PATH='@s9s_mb_2u_lib.s9s_mb_2u(sch_1):page290_i20@pure_quanta.q_cap(chips)',
 PATH='I20',
 DRAWING='@S9S_MB_2U_LIB.S9S_MB_2U(SCH_1):PAGE276',
 PHYS_PAGE='290',
 XY='(-6800,4675)',
 ROT='0',
 VER='1',
 PACK_TYPE='C0402',
 LOCATION='PC1245_P1_4',
 CDS_LIB='pure_quanta',
 CDS_PART_NAME='Q_CAP_C0402-2.2UF,10V,10%,X6S,A',
 TOLERANCE='10%',
 MATERIAL='X6S',
 VOLTAGE='10V',
 VALUE='2.2UF',
 PRIM_FILE='./archive_libs/logical/q_cap/chips/chips.prt';

PART_NAME
 PC1247 'Q_CAP_C0805-22UF,16V,20%,X6S,CA':;

SECTION_NUMBER 1
 '@S9S_MB_2U_LIB.S9S_MB_2U(SCH_1):PAGE267_I10@PURE_QUANTA.Q_CAP(CHIPS)':
 C_PATH='@s9s_mb_2u_lib.s9s_mb_2u(sch_1):page267_i10@pure_quanta.q_cap(chips)',
 P_PATH='@s9s_mb_2u_lib.s9s_mb_2u(sch_1):page281_i10@pure_quanta.q_cap(chips)',
 PATH='I10',
 DRAWING='@S9S_MB_2U_LIB.S9S_MB_2U(SCH_1):PAGE267',
 BOM_COST='VR_PCH',
 PHYS_PAGE='281',
 XY='(-10975,4350)',
 ROT='0',
 VER='1',
 PACK_TYPE='C0805',
 LOCATION='PC1247',
 CDS_LIB='pure_quanta',
 CDS_PART_NAME='Q_CAP_C0805-22UF,16V,20%,X6S,CA',
 TOLERANCE='20%',
 MATERIAL='X6S',
 VOLTAGE='16V',
 VALUE='22UF',
 PRIM_FILE='./archive_libs/logical/q_cap/chips/chips.prt';

PART_NAME
 PC1248 'Q_CAP_C0805-22UF,16V,20%,X6S,CA':;

SECTION_NUMBER 1
 '@S9S_MB_2U_LIB.S9S_MB_2U(SCH_1):PAGE267_I16@PURE_QUANTA.Q_CAP(CHIPS)':
 C_PATH='@s9s_mb_2u_lib.s9s_mb_2u(sch_1):page267_i16@pure_quanta.q_cap(chips)',
 P_PATH='@s9s_mb_2u_lib.s9s_mb_2u(sch_1):page281_i16@pure_quanta.q_cap(chips)',
 PATH='I16',
 DRAWING='@S9S_MB_2U_LIB.S9S_MB_2U(SCH_1):PAGE267',
 BOM_COST='VR_PCH',
 PHYS_PAGE='281',
 XY='(-10550,4350)',
 ROT='0',
 VER='1',
 PACK_TYPE='C0805',
 LOCATION='PC1248',
 CDS_LIB='pure_quanta',
 CDS_PART_NAME='Q_CAP_C0805-22UF,16V,20%,X6S,CA',
 TOLERANCE='20%',
 MATERIAL='X6S',
 VOLTAGE='16V',
 VALUE='22UF',
 PRIM_FILE='./archive_libs/logical/q_cap/chips/chips.prt';

PART_NAME
 PC1249 'Q_CAP_C0402-1UF,16V,10%,X6S,CHA':;

SECTION_NUMBER 1
 '@S9S_MB_2U_LIB.S9S_MB_2U(SCH_1):PAGE267_I17@PURE_QUANTA.Q_CAP(CHIPS)':
 C_PATH='@s9s_mb_2u_lib.s9s_mb_2u(sch_1):page267_i17@pure_quanta.q_cap(chips)',
 P_PATH='@s9s_mb_2u_lib.s9s_mb_2u(sch_1):page281_i17@pure_quanta.q_cap(chips)',
 PATH='I17',
 DRAWING='@S9S_MB_2U_LIB.S9S_MB_2U(SCH_1):PAGE267',
 PHYS_PAGE='281',
 XY='(-10125,4350)',
 ROT='0',
 VER='1',
 PACK_TYPE='C0402',
 LOCATION='PC1249',
 CDS_LIB='pure_quanta',
 CDS_PART_NAME='Q_CAP_C0402-1UF,16V,10%,X6S,CHA',
 TOLERANCE='10%',
 MATERIAL='X6S',
 VOLTAGE='16V',
 VALUE='1UF',
 PRIM_FILE='./archive_libs/logical/q_cap/chips/chips.prt';

PART_NAME
 PC1251 'Q_CAP_0402-0.1UF,25V,10%,X7R,CA':;

SECTION_NUMBER 1
 '@S9S_MB_2U_LIB.S9S_MB_2U(SCH_1):PAGE267_I25@PURE_QUANTA.Q_CAP(CHIPS)':
 C_PATH='@s9s_mb_2u_lib.s9s_mb_2u(sch_1):page267_i25@pure_quanta.q_cap(chips)',
 P_PATH='@s9s_mb_2u_lib.s9s_mb_2u(sch_1):page281_i25@pure_quanta.q_cap(chips)',
 PATH='I25',
 DRAWING='@S9S_MB_2U_LIB.S9S_MB_2U(SCH_1):PAGE267',
 PHYS_PAGE='281',
 XY='(-7500,2475)',
 ROT='0',
 VER='1',
 PACK_TYPE='0402',
 LOCATION='PC1251',
 CDS_LIB='pure_quanta',
 CDS_PART_NAME='Q_CAP_0402-0.1UF,25V,10%,X7R,CA',
 TOLERANCE='10%',
 MATERIAL='X7R',
 VOLTAGE='25V',
 VALUE='0.1UF',
 PRIM_FILE='./archive_libs/logical/q_cap/chips/chips.prt';

PART_NAME
 PC1252 'Q_CAP_C0402-0.22UF,25V,10%,X7RA':;

SECTION_NUMBER 1
 '@S9S_MB_2U_LIB.S9S_MB_2U(SCH_1):PAGE267_I27@PURE_QUANTA.Q_CAP(CHIPS)':
 C_PATH='@s9s_mb_2u_lib.s9s_mb_2u(sch_1):page267_i27@pure_quanta.q_cap(chips)',
 P_PATH='@s9s_mb_2u_lib.s9s_mb_2u(sch_1):page281_i27@pure_quanta.q_cap(chips)',
 PATH='I27',
 DRAWING='@S9S_MB_2U_LIB.S9S_MB_2U(SCH_1):PAGE267',
 PHYS_PAGE='281',
 XY='(-7350,3850)',
 ROT='0',
 VER='1',
 PACK_TYPE='C0402',
 LOCATION='PC1252',
 CDS_LIB='pure_quanta',
 CDS_PART_NAME='Q_CAP_C0402-0.22UF,25V,10%,X7RA',
 TOLERANCE='10%',
 MATERIAL='X7R',
 VOLTAGE='25V',
 VALUE='0.22UF',
 PRIM_FILE='./archive_libs/logical/q_cap/chips/chips.prt';

PART_NAME
 PC1253 'Q_CAP_C0402-680PF,50V,10%,X7R,A':;

SECTION_NUMBER 1
 '@S9S_MB_2U_LIB.S9S_MB_2U(SCH_1):PAGE267_I35@PURE_QUANTA.Q_CAP(CHIPS)':
 C_PATH='@s9s_mb_2u_lib.s9s_mb_2u(sch_1):page267_i35@pure_quanta.q_cap(chips)',
 P_PATH='@s9s_mb_2u_lib.s9s_mb_2u(sch_1):page281_i35@pure_quanta.q_cap(chips)',
 PATH='I35',
 DRAWING='@S9S_MB_2U_LIB.S9S_MB_2U(SCH_1):PAGE267',
 PHYS_PAGE='281',
 XY='(-6350,2700)',
 ROT='0',
 VER='2',
 PACK_TYPE='C0402',
 LOCATION='PC1253',
 CDS_LIB='pure_quanta',
 CDS_PART_NAME='Q_CAP_C0402-680PF,50V,10%,X7R,A',
 TOLERANCE='10%',
 MATERIAL='X7R',
 VOLTAGE='50V',
 VALUE='680PF',
 PRIM_FILE='./archive_libs/logical/q_cap/chips/chips.prt';

PART_NAME
 PC1254 'Q_CAP_0402-0.1UF,25V,10%,X7R,CA':;

SECTION_NUMBER 1
 '@S9S_MB_2U_LIB.S9S_MB_2U(SCH_1):PAGE267_I38@PURE_QUANTA.Q_CAP(CHIPS)':
 C_PATH='@s9s_mb_2u_lib.s9s_mb_2u(sch_1):page267_i38@pure_quanta.q_cap(chips)',
 P_PATH='@s9s_mb_2u_lib.s9s_mb_2u(sch_1):page281_i38@pure_quanta.q_cap(chips)',
 PATH='I38',
 DRAWING='@S9S_MB_2U_LIB.S9S_MB_2U(SCH_1):PAGE267',
 PHYS_PAGE='281',
 XY='(-5900,3425)',
 ROT='0',
 VER='1',
 PACK_TYPE='0402',
 LOCATION='PC1254',
 CDS_LIB='pure_quanta',
 CDS_PART_NAME='Q_CAP_0402-0.1UF,25V,10%,X7R,CA',
 TOLERANCE='10%',
 MATERIAL='X7R',
 VOLTAGE='25V',
 VALUE='0.1UF',
 PRIM_FILE='./archive_libs/logical/q_cap/chips/chips.prt';

PART_NAME
 PC1255 'Q_CAP_C0805-22UF,4V,20%,X6S,CHA':;

SECTION_NUMBER 1
 '@S9S_MB_2U_LIB.S9S_MB_2U(SCH_1):PAGE267_I42@PURE_QUANTA.Q_CAP(CHIPS)':
 C_PATH='@s9s_mb_2u_lib.s9s_mb_2u(sch_1):page267_i42@pure_quanta.q_cap(chips)',
 P_PATH='@s9s_mb_2u_lib.s9s_mb_2u(sch_1):page281_i42@pure_quanta.q_cap(chips)',
 PATH='I42',
 DRAWING='@S9S_MB_2U_LIB.S9S_MB_2U(SCH_1):PAGE267',
 BOM_COST='VR_PCH',
 PHYS_PAGE='281',
 XY='(-5475,3425)',
 ROT='0',
 VER='1',
 PACK_TYPE='C0805',
 LOCATION='PC1255',
 CDS_LIB='pure_quanta',
 CDS_PART_NAME='Q_CAP_C0805-22UF,4V,20%,X6S,CHA',
 TOLERANCE='20%',
 MATERIAL='X6S',
 VOLTAGE='4V',
 VALUE='22UF',
 PRIM_FILE='./archive_libs/logical/q_cap/chips/chips.prt';

PART_NAME
 PC1256 'Q_CAP_C0805-22UF,4V,20%,X6S,CHA':;

SECTION_NUMBER 1
 '@S9S_MB_2U_LIB.S9S_MB_2U(SCH_1):PAGE267_I43@PURE_QUANTA.Q_CAP(CHIPS)':
 C_PATH='@s9s_mb_2u_lib.s9s_mb_2u(sch_1):page267_i43@pure_quanta.q_cap(chips)',
 P_PATH='@s9s_mb_2u_lib.s9s_mb_2u(sch_1):page281_i43@pure_quanta.q_cap(chips)',
 PATH='I43',
 DRAWING='@S9S_MB_2U_LIB.S9S_MB_2U(SCH_1):PAGE267',
 BOM_COST='VR_PCH',
 PHYS_PAGE='281',
 XY='(-5100,3425)',
 ROT='0',
 VER='1',
 PACK_TYPE='C0805',
 LOCATION='PC1256',
 CDS_LIB='pure_quanta',
 CDS_PART_NAME='Q_CAP_C0805-22UF,4V,20%,X6S,CHA',
 TOLERANCE='20%',
 MATERIAL='X6S',
 VOLTAGE='4V',
 VALUE='22UF',
 PRIM_FILE='./archive_libs/logical/q_cap/chips/chips.prt';

PART_NAME
 PC1257 'Q_CAP_C0805-22UF,4V,20%,X6S,CHA':;

SECTION_NUMBER 1
 '@S9S_MB_2U_LIB.S9S_MB_2U(SCH_1):PAGE267_I44@PURE_QUANTA.Q_CAP(CHIPS)':
 C_PATH='@s9s_mb_2u_lib.s9s_mb_2u(sch_1):page267_i44@pure_quanta.q_cap(chips)',
 P_PATH='@s9s_mb_2u_lib.s9s_mb_2u(sch_1):page281_i44@pure_quanta.q_cap(chips)',
 PATH='I44',
 DRAWING='@S9S_MB_2U_LIB.S9S_MB_2U(SCH_1):PAGE267',
 BOM_COST='VR_PCH',
 PHYS_PAGE='281',
 XY='(-4725,3425)',
 ROT='0',
 VER='1',
 PACK_TYPE='C0805',
 LOCATION='PC1257',
 CDS_LIB='pure_quanta',
 CDS_PART_NAME='Q_CAP_C0805-22UF,4V,20%,X6S,CHA',
 TOLERANCE='20%',
 MATERIAL='X6S',
 VOLTAGE='4V',
 VALUE='22UF',
 PRIM_FILE='./archive_libs/logical/q_cap/chips/chips.prt';

PART_NAME
 PC1258 'Q_CAPP_THLF-560UF,6.3V,20%,OSCA':;

SECTION_NUMBER 1
 '@S9S_MB_2U_LIB.S9S_MB_2U(SCH_1):PAGE267_I49@PURE_QUANTA.Q_CAPP(CHIPS)':
 C_PATH='@s9s_mb_2u_lib.s9s_mb_2u(sch_1):page267_i49@pure_quanta.q_capp(chips)',
 P_PATH='@s9s_mb_2u_lib.s9s_mb_2u(sch_1):page281_i49@pure_quanta.q_capp(chips)',
 PATH='I49',
 DRAWING='@S9S_MB_2U_LIB.S9S_MB_2U(SCH_1):PAGE267',
 BOM_COST='VR_PCH',
 PHYS_PAGE='281',
 XY='(-4325,3425)',
 ROT='0',
 VER='1',
 PACK_TYPE='THLF',
 LOCATION='PC1258',
 CDS_LIB='pure_quanta',
 CDS_PART_NAME='Q_CAPP_THLF-560UF,6.3V,20%,OSCA',
 TOLERANCE='20%',
 MATERIAL='OSCON',
 VOLTAGE='6.3V',
 VALUE='560UF',
 PRIM_FILE='./archive_libs/logical/q_capp/chips/chips.prt';

PART_NAME
 PC1259 'Q_CAP_C0805-22UF,16V,20%,X6S,CA':;

SECTION_NUMBER 1
 '@S9S_MB_2U_LIB.S9S_MB_2U(SCH_1):PAGE285_I8@PURE_QUANTA.Q_CAP(CHIPS)':
 C_PATH='@s9s_mb_2u_lib.s9s_mb_2u(sch_1):page285_i8@pure_quanta.q_cap(chips)',
 P_PATH='@s9s_mb_2u_lib.s9s_mb_2u(sch_1):page299_i8@pure_quanta.q_cap(chips)',
 PATH='I8',
 DRAWING='@S9S_MB_2U_LIB.S9S_MB_2U(SCH_1):PAGE285',
 BOM_COST='VR_PCH',
 PHYS_PAGE='299',
 XY='(-10800,3900)',
 ROT='0',
 VER='1',
 PACK_TYPE='C0805',
 LOCATION='PC1259',
 CDS_LIB='pure_quanta',
 CDS_PART_NAME='Q_CAP_C0805-22UF,16V,20%,X6S,CA',
 TOLERANCE='20%',
 MATERIAL='X6S',
 VOLTAGE='16V',
 VALUE='22UF',
 PRIM_FILE='./archive_libs/logical/q_cap/chips/chips.prt';

PART_NAME
 PC1260 'Q_CAP_C0805-22UF,16V,20%,X6S,CA':;

SECTION_NUMBER 1
 '@S9S_MB_2U_LIB.S9S_MB_2U(SCH_1):PAGE285_I15@PURE_QUANTA.Q_CAP(CHIPS)':
 C_PATH='@s9s_mb_2u_lib.s9s_mb_2u(sch_1):page285_i15@pure_quanta.q_cap(chips)',
 P_PATH='@s9s_mb_2u_lib.s9s_mb_2u(sch_1):page299_i15@pure_quanta.q_cap(chips)',
 PATH='I15',
 DRAWING='@S9S_MB_2U_LIB.S9S_MB_2U(SCH_1):PAGE285',
 BOM_COST='VR_PCH',
 PHYS_PAGE='299',
 XY='(-10350,3900)',
 ROT='0',
 VER='1',
 PACK_TYPE='C0805',
 LOCATION='PC1260',
 CDS_LIB='pure_quanta',
 CDS_PART_NAME='Q_CAP_C0805-22UF,16V,20%,X6S,CA',
 TOLERANCE='20%',
 MATERIAL='X6S',
 VOLTAGE='16V',
 VALUE='22UF',
 PRIM_FILE='./archive_libs/logical/q_cap/chips/chips.prt';

PART_NAME
 PC1261 'Q_CAP_C0805-22UF,16V,20%,X6S,CA':;

SECTION_NUMBER 1
 '@S9S_MB_2U_LIB.S9S_MB_2U(SCH_1):PAGE285_I16@PURE_QUANTA.Q_CAP(CHIPS)':
 C_PATH='@s9s_mb_2u_lib.s9s_mb_2u(sch_1):page285_i16@pure_quanta.q_cap(chips)',
 P_PATH='@s9s_mb_2u_lib.s9s_mb_2u(sch_1):page299_i16@pure_quanta.q_cap(chips)',
 PATH='I16',
 DRAWING='@S9S_MB_2U_LIB.S9S_MB_2U(SCH_1):PAGE285',
 BOM_COST='VR_PCH',
 PHYS_PAGE='299',
 XY='(-9925,3900)',
 ROT='0',
 VER='1',
 PACK_TYPE='C0805',
 LOCATION='PC1261',
 CDS_LIB='pure_quanta',
 CDS_PART_NAME='Q_CAP_C0805-22UF,16V,20%,X6S,CA',
 TOLERANCE='20%',
 MATERIAL='X6S',
 VOLTAGE='16V',
 VALUE='22UF',
 PRIM_FILE='./archive_libs/logical/q_cap/chips/chips.prt';

PART_NAME
 PC1262 'Q_CAP_C0402-1UF,16V,10%,X6S,CHA':;

SECTION_NUMBER 1
 '@S9S_MB_2U_LIB.S9S_MB_2U(SCH_1):PAGE285_I17@PURE_QUANTA.Q_CAP(CHIPS)':
 C_PATH='@s9s_mb_2u_lib.s9s_mb_2u(sch_1):page285_i17@pure_quanta.q_cap(chips)',
 P_PATH='@s9s_mb_2u_lib.s9s_mb_2u(sch_1):page299_i17@pure_quanta.q_cap(chips)',
 PATH='I17',
 DRAWING='@S9S_MB_2U_LIB.S9S_MB_2U(SCH_1):PAGE285',
 PHYS_PAGE='299',
 XY='(-9500,3900)',
 ROT='0',
 VER='1',
 PACK_TYPE='C0402',
 LOCATION='PC1262',
 CDS_LIB='pure_quanta',
 CDS_PART_NAME='Q_CAP_C0402-1UF,16V,10%,X6S,CHA',
 TOLERANCE='10%',
 MATERIAL='X6S',
 VOLTAGE='16V',
 VALUE='1UF',
 PRIM_FILE='./archive_libs/logical/q_cap/chips/chips.prt';

PART_NAME
 PC1264 'Q_CAP_0402-0.1UF,25V,10%,X7R,CA':;

SECTION_NUMBER 1
 '@S9S_MB_2U_LIB.S9S_MB_2U(SCH_1):PAGE285_I24@PURE_QUANTA.Q_CAP(CHIPS)':
 C_PATH='@s9s_mb_2u_lib.s9s_mb_2u(sch_1):page285_i24@pure_quanta.q_cap(chips)',
 P_PATH='@s9s_mb_2u_lib.s9s_mb_2u(sch_1):page299_i24@pure_quanta.q_cap(chips)',
 PATH='I24',
 DRAWING='@S9S_MB_2U_LIB.S9S_MB_2U(SCH_1):PAGE285',
 PHYS_PAGE='299',
 XY='(-6850,2000)',
 ROT='0',
 VER='1',
 PACK_TYPE='0402',
 LOCATION='PC1264',
 CDS_LIB='pure_quanta',
 CDS_PART_NAME='Q_CAP_0402-0.1UF,25V,10%,X7R,CA',
 TOLERANCE='10%',
 MATERIAL='X7R',
 VOLTAGE='25V',
 VALUE='0.1UF',
 PRIM_FILE='./archive_libs/logical/q_cap/chips/chips.prt';

PART_NAME
 PC1265 'Q_CAP_C0402-0.22UF,25V,10%,X7RA':;

SECTION_NUMBER 1
 '@S9S_MB_2U_LIB.S9S_MB_2U(SCH_1):PAGE285_I26@PURE_QUANTA.Q_CAP(CHIPS)':
 C_PATH='@s9s_mb_2u_lib.s9s_mb_2u(sch_1):page285_i26@pure_quanta.q_cap(chips)',
 P_PATH='@s9s_mb_2u_lib.s9s_mb_2u(sch_1):page299_i26@pure_quanta.q_cap(chips)',
 PATH='I26',
 DRAWING='@S9S_MB_2U_LIB.S9S_MB_2U(SCH_1):PAGE285',
 PHYS_PAGE='299',
 XY='(-6725,3400)',
 ROT='0',
 VER='1',
 PACK_TYPE='C0402',
 LOCATION='PC1265',
 CDS_LIB='pure_quanta',
 CDS_PART_NAME='Q_CAP_C0402-0.22UF,25V,10%,X7RA',
 TOLERANCE='10%',
 MATERIAL='X7R',
 VOLTAGE='25V',
 VALUE='0.22UF',
 PRIM_FILE='./archive_libs/logical/q_cap/chips/chips.prt';

PART_NAME
 PC1266 'Q_CAP_0402-680PF,50V,10%,X7R,TA':;

SECTION_NUMBER 1
 '@S9S_MB_2U_LIB.S9S_MB_2U(SCH_1):PAGE285_I35@PURE_QUANTA.Q_CAP(CHIPS)':
 C_PATH='@s9s_mb_2u_lib.s9s_mb_2u(sch_1):page285_i35@pure_quanta.q_cap(chips)',
 P_PATH='@s9s_mb_2u_lib.s9s_mb_2u(sch_1):page299_i35@pure_quanta.q_cap(chips)',
 PATH='I35',
 DRAWING='@S9S_MB_2U_LIB.S9S_MB_2U(SCH_1):PAGE285',
 PHYS_PAGE='299',
 XY='(-5700,2250)',
 ROT='0',
 VER='2',
 PACK_TYPE='0402',
 LOCATION='PC1266',
 CDS_LIB='pure_quanta',
 CDS_PART_NAME='Q_CAP_0402-680PF,50V,10%,X7R,TA',
 TOLERANCE='10%',
 MATERIAL='X7R',
 VOLTAGE='50V',
 VALUE='680PF',
 PRIM_FILE='./archive_libs/logical/q_cap/chips/chips.prt';

PART_NAME
 PC1267 'Q_CAP_0402-0.1UF,25V,10%,X7R,CA':;

SECTION_NUMBER 1
 '@S9S_MB_2U_LIB.S9S_MB_2U(SCH_1):PAGE285_I39@PURE_QUANTA.Q_CAP(CHIPS)':
 C_PATH='@s9s_mb_2u_lib.s9s_mb_2u(sch_1):page285_i39@pure_quanta.q_cap(chips)',
 P_PATH='@s9s_mb_2u_lib.s9s_mb_2u(sch_1):page299_i39@pure_quanta.q_cap(chips)',
 PATH='I39',
 DRAWING='@S9S_MB_2U_LIB.S9S_MB_2U(SCH_1):PAGE285',
 PHYS_PAGE='299',
 XY='(-5275,2975)',
 ROT='0',
 VER='1',
 PACK_TYPE='0402',
 LOCATION='PC1267',
 CDS_LIB='pure_quanta',
 CDS_PART_NAME='Q_CAP_0402-0.1UF,25V,10%,X7R,CA',
 TOLERANCE='10%',
 MATERIAL='X7R',
 VOLTAGE='25V',
 VALUE='0.1UF',
 PRIM_FILE='./archive_libs/logical/q_cap/chips/chips.prt';

PART_NAME
 PC1268 'Q_CAP_C0805-22UF,4V,20%,X6S,CHA':;

SECTION_NUMBER 1
 '@S9S_MB_2U_LIB.S9S_MB_2U(SCH_1):PAGE285_I40@PURE_QUANTA.Q_CAP(CHIPS)':
 C_PATH='@s9s_mb_2u_lib.s9s_mb_2u(sch_1):page285_i40@pure_quanta.q_cap(chips)',
 P_PATH='@s9s_mb_2u_lib.s9s_mb_2u(sch_1):page299_i40@pure_quanta.q_cap(chips)',
 PATH='I40',
 DRAWING='@S9S_MB_2U_LIB.S9S_MB_2U(SCH_1):PAGE285',
 BOM_COST='VR_PCH',
 PHYS_PAGE='299',
 XY='(-4850,2975)',
 ROT='0',
 VER='1',
 PACK_TYPE='C0805',
 LOCATION='PC1268',
 CDS_LIB='pure_quanta',
 CDS_PART_NAME='Q_CAP_C0805-22UF,4V,20%,X6S,CHA',
 TOLERANCE='20%',
 MATERIAL='X6S',
 VOLTAGE='4V',
 VALUE='22UF',
 PRIM_FILE='./archive_libs/logical/q_cap/chips/chips.prt';

PART_NAME
 PC1269 'Q_CAP_C0805-22UF,4V,20%,X6S,CHA':;

SECTION_NUMBER 1
 '@S9S_MB_2U_LIB.S9S_MB_2U(SCH_1):PAGE285_I41@PURE_QUANTA.Q_CAP(CHIPS)':
 C_PATH='@s9s_mb_2u_lib.s9s_mb_2u(sch_1):page285_i41@pure_quanta.q_cap(chips)',
 P_PATH='@s9s_mb_2u_lib.s9s_mb_2u(sch_1):page299_i41@pure_quanta.q_cap(chips)',
 PATH='I41',
 DRAWING='@S9S_MB_2U_LIB.S9S_MB_2U(SCH_1):PAGE285',
 BOM_COST='VR_PCH',
 PHYS_PAGE='299',
 XY='(-4475,2975)',
 ROT='0',
 VER='1',
 PACK_TYPE='C0805',
 LOCATION='PC1269',
 CDS_LIB='pure_quanta',
 CDS_PART_NAME='Q_CAP_C0805-22UF,4V,20%,X6S,CHA',
 TOLERANCE='20%',
 MATERIAL='X6S',
 VOLTAGE='4V',
 VALUE='22UF',
 PRIM_FILE='./archive_libs/logical/q_cap/chips/chips.prt';

PART_NAME
 PC1270 'Q_CAP_C0805-22UF,4V,20%,X6S,CHA':;

SECTION_NUMBER 1
 '@S9S_MB_2U_LIB.S9S_MB_2U(SCH_1):PAGE285_I47@PURE_QUANTA.Q_CAP(CHIPS)':
 C_PATH='@s9s_mb_2u_lib.s9s_mb_2u(sch_1):page285_i47@pure_quanta.q_cap(chips)',
 P_PATH='@s9s_mb_2u_lib.s9s_mb_2u(sch_1):page299_i47@pure_quanta.q_cap(chips)',
 PATH='I47',
 DRAWING='@S9S_MB_2U_LIB.S9S_MB_2U(SCH_1):PAGE285',
 BOM_COST='VR_PCH',
 PHYS_PAGE='299',
 XY='(-4100,2975)',
 ROT='0',
 VER='1',
 PACK_TYPE='C0805',
 LOCATION='PC1270',
 CDS_LIB='pure_quanta',
 CDS_PART_NAME='Q_CAP_C0805-22UF,4V,20%,X6S,CHA',
 TOLERANCE='20%',
 MATERIAL='X6S',
 VOLTAGE='4V',
 VALUE='22UF',
 PRIM_FILE='./archive_libs/logical/q_cap/chips/chips.prt';

PART_NAME
 PC1271 'Q_CAP_0402-470PF,50V,10%,X7R,TA':;

SECTION_NUMBER 1
 '@S9S_MB_2U_LIB.S9S_MB_2U(SCH_1):PAGE260_I73@PURE_QUANTA.Q_CAP(CHIPS)':
 C_PATH='@s9s_mb_2u_lib.s9s_mb_2u(sch_1):page260_i73@pure_quanta.q_cap(chips)',
 P_PATH='@s9s_mb_2u_lib.s9s_mb_2u(sch_1):page274_i73@pure_quanta.q_cap(chips)',
 PATH='I73',
 DRAWING='@S9S_MB_2U_LIB.S9S_MB_2U(SCH_1):PAGE260',
 PHYS_PAGE='274',
 XY='(-5675,2825)',
 ROT='0',
 VER='2',
 PACK_TYPE='0402',
 LOCATION='PC1271',
 CDS_LIB='pure_quanta',
 CDS_PART_NAME='Q_CAP_0402-470PF,50V,10%,X7R,TA',
 TOLERANCE='10%',
 MATERIAL='X7R',
 VOLTAGE='50V',
 VALUE='470PF',
 PRIM_FILE='./archive_libs/logical/q_cap/chips/chips.prt';

PART_NAME
 PC1272 'Q_CAP_C0805-22UF,16V,20%,X6S,CA':;

SECTION_NUMBER 1
 '@S9S_MB_2U_LIB.S9S_MB_2U(SCH_1):PAGE268_I13@PURE_QUANTA.Q_CAP(CHIPS)':
 C_PATH='@s9s_mb_2u_lib.s9s_mb_2u(sch_1):page268_i13@pure_quanta.q_cap(chips)',
 P_PATH='@s9s_mb_2u_lib.s9s_mb_2u(sch_1):page282_i13@pure_quanta.q_cap(chips)',
 PATH='I13',
 DRAWING='@S9S_MB_2U_LIB.S9S_MB_2U(SCH_1):PAGE268',
 BOM_COST='VR_PCH',
 PHYS_PAGE='282',
 XY='(-8800,10575)',
 ROT='0',
 VER='1',
 PACK_TYPE='C0805',
 LOCATION='PC1272',
 CDS_LIB='pure_quanta',
 CDS_PART_NAME='Q_CAP_C0805-22UF,16V,20%,X6S,CA',
 TOLERANCE='20%',
 MATERIAL='X6S',
 VOLTAGE='16V',
 VALUE='22UF',
 PRIM_FILE='./archive_libs/logical/q_cap/chips/chips.prt';

PART_NAME
 PC1273 'Q_CAP_C0805-22UF,16V,20%,X6S,CA':;

SECTION_NUMBER 1
 '@S9S_MB_2U_LIB.S9S_MB_2U(SCH_1):PAGE268_I15@PURE_QUANTA.Q_CAP(CHIPS)':
 C_PATH='@s9s_mb_2u_lib.s9s_mb_2u(sch_1):page268_i15@pure_quanta.q_cap(chips)',
 P_PATH='@s9s_mb_2u_lib.s9s_mb_2u(sch_1):page282_i15@pure_quanta.q_cap(chips)',
 PATH='I15',
 DRAWING='@S9S_MB_2U_LIB.S9S_MB_2U(SCH_1):PAGE268',
 BOM_COST='VR_PCH',
 PHYS_PAGE='282',
 XY='(-8350,10575)',
 ROT='0',
 VER='1',
 PACK_TYPE='C0805',
 LOCATION='PC1273',
 CDS_LIB='pure_quanta',
 CDS_PART_NAME='Q_CAP_C0805-22UF,16V,20%,X6S,CA',
 TOLERANCE='20%',
 MATERIAL='X6S',
 VOLTAGE='16V',
 VALUE='22UF',
 PRIM_FILE='./archive_libs/logical/q_cap/chips/chips.prt';

PART_NAME
 PC1274 'Q_CAP_C0402-1UF,16V,10%,X6S,CHA':;

SECTION_NUMBER 1
 '@S9S_MB_2U_LIB.S9S_MB_2U(SCH_1):PAGE268_I23@PURE_QUANTA.Q_CAP(CHIPS)':
 C_PATH='@s9s_mb_2u_lib.s9s_mb_2u(sch_1):page268_i23@pure_quanta.q_cap(chips)',
 P_PATH='@s9s_mb_2u_lib.s9s_mb_2u(sch_1):page282_i23@pure_quanta.q_cap(chips)',
 PATH='I23',
 DRAWING='@S9S_MB_2U_LIB.S9S_MB_2U(SCH_1):PAGE268',
 PHYS_PAGE='282',
 XY='(-7800,10575)',
 ROT='0',
 VER='1',
 PACK_TYPE='C0402',
 LOCATION='PC1274',
 CDS_LIB='pure_quanta',
 CDS_PART_NAME='Q_CAP_C0402-1UF,16V,10%,X6S,CHA',
 TOLERANCE='10%',
 MATERIAL='X6S',
 VOLTAGE='16V',
 VALUE='1UF',
 PRIM_FILE='./archive_libs/logical/q_cap/chips/chips.prt';

PART_NAME
 PC1275 'Q_CAP_C0402-0.22UF,25V,10%,X7RA':;

SECTION_NUMBER 1
 '@S9S_MB_2U_LIB.S9S_MB_2U(SCH_1):PAGE268_I26@PURE_QUANTA.Q_CAP(CHIPS)':
 C_PATH='@s9s_mb_2u_lib.s9s_mb_2u(sch_1):page268_i26@pure_quanta.q_cap(chips)',
 P_PATH='@s9s_mb_2u_lib.s9s_mb_2u(sch_1):page282_i26@pure_quanta.q_cap(chips)',
 PATH='I26',
 DRAWING='@S9S_MB_2U_LIB.S9S_MB_2U(SCH_1):PAGE268',
 PHYS_PAGE='282',
 XY='(-5175,10000)',
 ROT='0',
 VER='1',
 PACK_TYPE='C0402',
 LOCATION='PC1275',
 CDS_LIB='pure_quanta',
 CDS_PART_NAME='Q_CAP_C0402-0.22UF,25V,10%,X7RA',
 TOLERANCE='10%',
 MATERIAL='X7R',
 VOLTAGE='25V',
 VALUE='0.22UF',
 PRIM_FILE='./archive_libs/logical/q_cap/chips/chips.prt';

PART_NAME
 PC1276 'Q_CAP_C0402-100NF,50V,10%,X7R,A':;

SECTION_NUMBER 1
 '@S9S_MB_2U_LIB.S9S_MB_2U(SCH_1):PAGE268_I37@PURE_QUANTA.Q_CAP(CHIPS)':
 C_PATH='@s9s_mb_2u_lib.s9s_mb_2u(sch_1):page268_i37@pure_quanta.q_cap(chips)',
 P_PATH='@s9s_mb_2u_lib.s9s_mb_2u(sch_1):page282_i37@pure_quanta.q_cap(chips)',
 PATH='I37',
 DRAWING='@S9S_MB_2U_LIB.S9S_MB_2U(SCH_1):PAGE268',
 PHYS_PAGE='282',
 XY='(-3425,9650)',
 ROT='0',
 VER='1',
 PACK_TYPE='C0402',
 LOCATION='PC1276',
 CDS_LIB='pure_quanta',
 CDS_PART_NAME='Q_CAP_C0402-100NF,50V,10%,X7R,A',
 TOLERANCE='10%',
 MATERIAL='X7R',
 VOLTAGE='50V',
 VALUE='100NF',
 PRIM_FILE='./archive_libs/logical/q_cap/chips/chips.prt';

PART_NAME
 PC1277 'Q_CAP_C0805-22UF,4V,20%,X6S,CHA':;

SECTION_NUMBER 1
 '@S9S_MB_2U_LIB.S9S_MB_2U(SCH_1):PAGE268_I38@PURE_QUANTA.Q_CAP(CHIPS)':
 C_PATH='@s9s_mb_2u_lib.s9s_mb_2u(sch_1):page268_i38@pure_quanta.q_cap(chips)',
 P_PATH='@s9s_mb_2u_lib.s9s_mb_2u(sch_1):page282_i38@pure_quanta.q_cap(chips)',
 PATH='I38',
 DRAWING='@S9S_MB_2U_LIB.S9S_MB_2U(SCH_1):PAGE268',
 BOM_COST='VR_PCH',
 PHYS_PAGE='282',
 XY='(-3050,9650)',
 ROT='0',
 VER='1',
 PACK_TYPE='C0805',
 LOCATION='PC1277',
 CDS_LIB='pure_quanta',
 CDS_PART_NAME='Q_CAP_C0805-22UF,4V,20%,X6S,CHA',
 TOLERANCE='20%',
 MATERIAL='X6S',
 VOLTAGE='4V',
 VALUE='22UF',
 PRIM_FILE='./archive_libs/logical/q_cap/chips/chips.prt';

PART_NAME
 PC1278 'Q_CAP_C0805-22UF,4V,20%,X6S,CHA':;

SECTION_NUMBER 1
 '@S9S_MB_2U_LIB.S9S_MB_2U(SCH_1):PAGE268_I42@PURE_QUANTA.Q_CAP(CHIPS)':
 C_PATH='@s9s_mb_2u_lib.s9s_mb_2u(sch_1):page268_i42@pure_quanta.q_cap(chips)',
 P_PATH='@s9s_mb_2u_lib.s9s_mb_2u(sch_1):page282_i42@pure_quanta.q_cap(chips)',
 PATH='I42',
 DRAWING='@S9S_MB_2U_LIB.S9S_MB_2U(SCH_1):PAGE268',
 BOM_COST='VR_PCH',
 PHYS_PAGE='282',
 XY='(-2675,9650)',
 ROT='0',
 VER='1',
 PACK_TYPE='C0805',
 LOCATION='PC1278',
 CDS_LIB='pure_quanta',
 CDS_PART_NAME='Q_CAP_C0805-22UF,4V,20%,X6S,CHA',
 TOLERANCE='20%',
 MATERIAL='X6S',
 VOLTAGE='4V',
 VALUE='22UF',
 PRIM_FILE='./archive_libs/logical/q_cap/chips/chips.prt';

PART_NAME
 PC1279 'Q_CAP_C0805-22UF,4V,20%,X6S,CHA':;

SECTION_NUMBER 1
 '@S9S_MB_2U_LIB.S9S_MB_2U(SCH_1):PAGE268_I43@PURE_QUANTA.Q_CAP(CHIPS)':
 C_PATH='@s9s_mb_2u_lib.s9s_mb_2u(sch_1):page268_i43@pure_quanta.q_cap(chips)',
 P_PATH='@s9s_mb_2u_lib.s9s_mb_2u(sch_1):page282_i43@pure_quanta.q_cap(chips)',
 PATH='I43',
 DRAWING='@S9S_MB_2U_LIB.S9S_MB_2U(SCH_1):PAGE268',
 BOM_COST='VR_PCH',
 PHYS_PAGE='282',
 XY='(-2300,9650)',
 ROT='0',
 VER='1',
 PACK_TYPE='C0805',
 LOCATION='PC1279',
 CDS_LIB='pure_quanta',
 CDS_PART_NAME='Q_CAP_C0805-22UF,4V,20%,X6S,CHA',
 TOLERANCE='20%',
 MATERIAL='X6S',
 VOLTAGE='4V',
 VALUE='22UF',
 PRIM_FILE='./archive_libs/logical/q_cap/chips/chips.prt';

PART_NAME
 PC1280 'Q_CAP_C0805-22UF,16V,20%,X6S,CA':;

SECTION_NUMBER 1
 '@S9S_MB_2U_LIB.S9S_MB_2U(SCH_1):PAGE286_I9@PURE_QUANTA.Q_CAP(CHIPS)':
 C_PATH='@s9s_mb_2u_lib.s9s_mb_2u(sch_1):page286_i9@pure_quanta.q_cap(chips)',
 P_PATH='@s9s_mb_2u_lib.s9s_mb_2u(sch_1):page300_i9@pure_quanta.q_cap(chips)',
 PATH='I9',
 DRAWING='@S9S_MB_2U_LIB.S9S_MB_2U(SCH_1):PAGE286',
 BOM_COST='VR_PCH',
 PHYS_PAGE='300',
 XY='(2450,7950)',
 ROT='0',
 VER='1',
 PACK_TYPE='C0805',
 LOCATION='PC1280',
 CDS_LIB='pure_quanta',
 CDS_PART_NAME='Q_CAP_C0805-22UF,16V,20%,X6S,CA',
 TOLERANCE='20%',
 MATERIAL='X6S',
 VOLTAGE='16V',
 VALUE='22UF',
 PRIM_FILE='./archive_libs/logical/q_cap/chips/chips.prt';

PART_NAME
 PC1281 'Q_CAP_C0805-22UF,16V,20%,X6S,CA':;

SECTION_NUMBER 1
 '@S9S_MB_2U_LIB.S9S_MB_2U(SCH_1):PAGE286_I14@PURE_QUANTA.Q_CAP(CHIPS)':
 C_PATH='@s9s_mb_2u_lib.s9s_mb_2u(sch_1):page286_i14@pure_quanta.q_cap(chips)',
 P_PATH='@s9s_mb_2u_lib.s9s_mb_2u(sch_1):page300_i14@pure_quanta.q_cap(chips)',
 PATH='I14',
 DRAWING='@S9S_MB_2U_LIB.S9S_MB_2U(SCH_1):PAGE286',
 BOM_COST='VR_PCH',
 PHYS_PAGE='300',
 XY='(2900,7950)',
 ROT='0',
 VER='1',
 PACK_TYPE='C0805',
 LOCATION='PC1281',
 CDS_LIB='pure_quanta',
 CDS_PART_NAME='Q_CAP_C0805-22UF,16V,20%,X6S,CA',
 TOLERANCE='20%',
 MATERIAL='X6S',
 VOLTAGE='16V',
 VALUE='22UF',
 PRIM_FILE='./archive_libs/logical/q_cap/chips/chips.prt';

PART_NAME
 PC1282 'Q_CAP_C0402-1UF,16V,10%,X6S,CHA':;

SECTION_NUMBER 1
 '@S9S_MB_2U_LIB.S9S_MB_2U(SCH_1):PAGE286_I16@PURE_QUANTA.Q_CAP(CHIPS)':
 C_PATH='@s9s_mb_2u_lib.s9s_mb_2u(sch_1):page286_i16@pure_quanta.q_cap(chips)',
 P_PATH='@s9s_mb_2u_lib.s9s_mb_2u(sch_1):page300_i16@pure_quanta.q_cap(chips)',
 PATH='I16',
 DRAWING='@S9S_MB_2U_LIB.S9S_MB_2U(SCH_1):PAGE286',
 PHYS_PAGE='300',
 XY='(3325,7950)',
 ROT='0',
 VER='1',
 PACK_TYPE='C0402',
 LOCATION='PC1282',
 CDS_LIB='pure_quanta',
 CDS_PART_NAME='Q_CAP_C0402-1UF,16V,10%,X6S,CHA',
 TOLERANCE='10%',
 MATERIAL='X6S',
 VOLTAGE='16V',
 VALUE='1UF',
 PRIM_FILE='./archive_libs/logical/q_cap/chips/chips.prt';

PART_NAME
 PC1283 'Q_CAP_C0402-0.22UF,25V,10%,X7RA':;

SECTION_NUMBER 1
 '@S9S_MB_2U_LIB.S9S_MB_2U(SCH_1):PAGE286_I24@PURE_QUANTA.Q_CAP(CHIPS)':
 C_PATH='@s9s_mb_2u_lib.s9s_mb_2u(sch_1):page286_i24@pure_quanta.q_cap(chips)',
 P_PATH='@s9s_mb_2u_lib.s9s_mb_2u(sch_1):page300_i24@pure_quanta.q_cap(chips)',
 PATH='I24',
 DRAWING='@S9S_MB_2U_LIB.S9S_MB_2U(SCH_1):PAGE286',
 PHYS_PAGE='300',
 XY='(6700,7375)',
 ROT='0',
 VER='1',
 PACK_TYPE='C0402',
 LOCATION='PC1283',
 CDS_LIB='pure_quanta',
 CDS_PART_NAME='Q_CAP_C0402-0.22UF,25V,10%,X7RA',
 TOLERANCE='10%',
 MATERIAL='X7R',
 VOLTAGE='25V',
 VALUE='0.22UF',
 PRIM_FILE='./archive_libs/logical/q_cap/chips/chips.prt';

PART_NAME
 PC1284 'Q_CAP_C0402-100NF,50V,10%,X7R,A':;

SECTION_NUMBER 1
 '@S9S_MB_2U_LIB.S9S_MB_2U(SCH_1):PAGE286_I28@PURE_QUANTA.Q_CAP(CHIPS)':
 C_PATH='@s9s_mb_2u_lib.s9s_mb_2u(sch_1):page286_i28@pure_quanta.q_cap(chips)',
 P_PATH='@s9s_mb_2u_lib.s9s_mb_2u(sch_1):page300_i28@pure_quanta.q_cap(chips)',
 PATH='I28',
 DRAWING='@S9S_MB_2U_LIB.S9S_MB_2U(SCH_1):PAGE286',
 PHYS_PAGE='300',
 XY='(7725,7025)',
 ROT='0',
 VER='1',
 PACK_TYPE='C0402',
 LOCATION='PC1284',
 CDS_LIB='pure_quanta',
 CDS_PART_NAME='Q_CAP_C0402-100NF,50V,10%,X7R,A',
 TOLERANCE='10%',
 MATERIAL='X7R',
 VOLTAGE='50V',
 VALUE='100NF',
 PRIM_FILE='./archive_libs/logical/q_cap/chips/chips.prt';

PART_NAME
 PC1285 'Q_CAP_C0805-22UF,4V,20%,X6S,CHA':;

SECTION_NUMBER 1
 '@S9S_MB_2U_LIB.S9S_MB_2U(SCH_1):PAGE286_I36@PURE_QUANTA.Q_CAP(CHIPS)':
 C_PATH='@s9s_mb_2u_lib.s9s_mb_2u(sch_1):page286_i36@pure_quanta.q_cap(chips)',
 P_PATH='@s9s_mb_2u_lib.s9s_mb_2u(sch_1):page300_i36@pure_quanta.q_cap(chips)',
 PATH='I36',
 DRAWING='@S9S_MB_2U_LIB.S9S_MB_2U(SCH_1):PAGE286',
 BOM_COST='VR_PCH',
 PHYS_PAGE='300',
 XY='(8125,7025)',
 ROT='0',
 VER='1',
 PACK_TYPE='C0805',
 LOCATION='PC1285',
 CDS_LIB='pure_quanta',
 CDS_PART_NAME='Q_CAP_C0805-22UF,4V,20%,X6S,CHA',
 TOLERANCE='20%',
 MATERIAL='X6S',
 VOLTAGE='4V',
 VALUE='22UF',
 PRIM_FILE='./archive_libs/logical/q_cap/chips/chips.prt';

PART_NAME
 PC1286 'Q_CAP_C0805-22UF,4V,20%,X6S,CHA':;

SECTION_NUMBER 1
 '@S9S_MB_2U_LIB.S9S_MB_2U(SCH_1):PAGE286_I38@PURE_QUANTA.Q_CAP(CHIPS)':
 C_PATH='@s9s_mb_2u_lib.s9s_mb_2u(sch_1):page286_i38@pure_quanta.q_cap(chips)',
 P_PATH='@s9s_mb_2u_lib.s9s_mb_2u(sch_1):page300_i38@pure_quanta.q_cap(chips)',
 PATH='I38',
 DRAWING='@S9S_MB_2U_LIB.S9S_MB_2U(SCH_1):PAGE286',
 BOM_COST='VR_PCH',
 PHYS_PAGE='300',
 XY='(8500,7025)',
 ROT='0',
 VER='1',
 PACK_TYPE='C0805',
 LOCATION='PC1286',
 CDS_LIB='pure_quanta',
 CDS_PART_NAME='Q_CAP_C0805-22UF,4V,20%,X6S,CHA',
 TOLERANCE='20%',
 MATERIAL='X6S',
 VOLTAGE='4V',
 VALUE='22UF',
 PRIM_FILE='./archive_libs/logical/q_cap/chips/chips.prt';

PART_NAME
 PC1287 'Q_CAP_C0805-22UF,4V,20%,X6S,CHA':;

SECTION_NUMBER 1
 '@S9S_MB_2U_LIB.S9S_MB_2U(SCH_1):PAGE286_I44@PURE_QUANTA.Q_CAP(CHIPS)':
 C_PATH='@s9s_mb_2u_lib.s9s_mb_2u(sch_1):page286_i44@pure_quanta.q_cap(chips)',
 P_PATH='@s9s_mb_2u_lib.s9s_mb_2u(sch_1):page300_i44@pure_quanta.q_cap(chips)',
 PATH='I44',
 DRAWING='@S9S_MB_2U_LIB.S9S_MB_2U(SCH_1):PAGE286',
 BOM_COST='VR_PCH',
 PHYS_PAGE='300',
 XY='(8875,7025)',
 ROT='0',
 VER='1',
 PACK_TYPE='C0805',
 LOCATION='PC1287',
 CDS_LIB='pure_quanta',
 CDS_PART_NAME='Q_CAP_C0805-22UF,4V,20%,X6S,CHA',
 TOLERANCE='20%',
 MATERIAL='X6S',
 VOLTAGE='4V',
 VALUE='22UF',
 PRIM_FILE='./archive_libs/logical/q_cap/chips/chips.prt';

PART_NAME
 PC1289 'Q_CAP_C0402-1UF,16V,10%,X6S,CHA':;

SECTION_NUMBER 1
 '@S9S_MB_2U_LIB.S9S_MB_2U(SCH_1):PAGE282_I74@PURE_QUANTA.Q_CAP(CHIPS)':
 C_PATH='@s9s_mb_2u_lib.s9s_mb_2u(sch_1):page282_i74@pure_quanta.q_cap(chips)',
 P_PATH='@s9s_mb_2u_lib.s9s_mb_2u(sch_1):page296_i74@pure_quanta.q_cap(chips)',
 PATH='I74',
 DRAWING='@S9S_MB_2U_LIB.S9S_MB_2U(SCH_1):PAGE282',
 PHYS_PAGE='296',
 XY='(-1300,4775)',
 ROT='0',
 VER='1',
 PACK_TYPE='C0402',
 LOCATION='PC1289',
 CDS_LIB='pure_quanta',
 CDS_PART_NAME='Q_CAP_C0402-1UF,16V,10%,X6S,CHA',
 TOLERANCE='10%',
 MATERIAL='X6S',
 VOLTAGE='16V',
 VALUE='1UF',
 PRIM_FILE='./archive_libs/logical/q_cap/chips/chips.prt';

PART_NAME
 PC1292 'Q_CAP_0402-470PF,50V,10%,X7R,TA':;

SECTION_NUMBER 1
 '@S9S_MB_2U_LIB.S9S_MB_2U(SCH_1):PAGE278_I69@PURE_QUANTA.Q_CAP(CHIPS)':
 C_PATH='@s9s_mb_2u_lib.s9s_mb_2u(sch_1):page278_i69@pure_quanta.q_cap(chips)',
 P_PATH='@s9s_mb_2u_lib.s9s_mb_2u(sch_1):page292_i69@pure_quanta.q_cap(chips)',
 PATH='I69',
 DRAWING='@S9S_MB_2U_LIB.S9S_MB_2U(SCH_1):PAGE278',
 PHYS_PAGE='292',
 XY='(4700,4400)',
 ROT='0',
 VER='2',
 PACK_TYPE='0402',
 LOCATION='PC1292',
 CDS_LIB='pure_quanta',
 CDS_PART_NAME='Q_CAP_0402-470PF,50V,10%,X7R,TA',
 TOLERANCE='10%',
 MATERIAL='X7R',
 VOLTAGE='50V',
 VALUE='470PF',
 PRIM_FILE='./archive_libs/logical/q_cap/chips/chips.prt';

PART_NAME
 PC1320 'Q_CAP_C0603-2.2UF,16V,20%,X7R,A':
 ROOM='NIC1_P12V_MPS_MAM_BOM3';

SECTION_NUMBER 1
 '@S9S_MB_2U_LIB.S9S_MB_2U(SCH_1):PAGE237_I95@PURE_QUANTA.Q_CAP(CHIPS)':
 C_PATH='@s9s_mb_2u_lib.s9s_mb_2u(sch_1):page237_i95@pure_quanta.q_cap(chips)',
 P_PATH='@s9s_mb_2u_lib.s9s_mb_2u(sch_1):page163_i95@pure_quanta.q_cap(chips)',
 PATH='I95',
 DRAWING='@S9S_MB_2U_LIB.S9S_MB_2U(SCH_1):PAGE237',
 ROOM1='NIC1_P12V_MPS_TIC_BOM4',
 PHYS_PAGE='163',
 XY='(-25,2650)',
 ROT='0',
 VER='1',
 PACK_TYPE='C0603',
 LOCATION='PC1320',
 CDS_LIB='pure_quanta',
 CDS_PART_NAME='Q_CAP_C0603-2.2UF,16V,20%,X7R,A',
 TOLERANCE='20%',
 MATERIAL='X7R',
 VOLTAGE='16V',
 ROOM='NIC1_P12V_MPS_MAM_BOM3',
 VALUE='2.2UF',
 PRIM_FILE='./archive_libs/logical/q_cap/chips/chips.prt';

PART_NAME
 PC1321 'Q_CAP_0402-0.068UF,16V,10%,EMPA':
 ROOM='NIC1_P3V3_BOM2';

SECTION_NUMBER 1
 '@S9S_MB_2U_LIB.S9S_MB_2U(SCH_1):PAGE237_I50@PURE_QUANTA.Q_CAP(CHIPS)':
 C_PATH='@s9s_mb_2u_lib.s9s_mb_2u(sch_1):page237_i50@pure_quanta.q_cap(chips)',
 P_PATH='@s9s_mb_2u_lib.s9s_mb_2u(sch_1):page163_i50@pure_quanta.q_cap(chips)',
 PATH='I50',
 DRAWING='@S9S_MB_2U_LIB.S9S_MB_2U(SCH_1):PAGE237',
 PHYS_PAGE='163',
 XY='(870,6108)',
 ROT='0',
 VER='1',
 PACK_TYPE='0402',
 LOCATION='PC1321',
 CDS_LIB='pure_quanta',
 CDS_PART_NAME='Q_CAP_0402-0.068UF,16V,10%,EMPA',
 TOLERANCE='10%',
 MATERIAL='EMPTY',
 VOLTAGE='16V',
 ROOM='NIC1_P3V3_BOM2',
 VALUE='0.068UF',
 PRIM_FILE='./archive_libs/logical/q_cap/chips/chips.prt';

PART_NAME
 PC1322 'Q_CAP_0402-100PF,50V,5%,EMPTY,A':
 ROOM='NIC1_P3V3_BOM2';

SECTION_NUMBER 1
 '@S9S_MB_2U_LIB.S9S_MB_2U(SCH_1):PAGE237_I54@PURE_QUANTA.Q_CAP(CHIPS)':
 C_PATH='@s9s_mb_2u_lib.s9s_mb_2u(sch_1):page237_i54@pure_quanta.q_cap(chips)',
 P_PATH='@s9s_mb_2u_lib.s9s_mb_2u(sch_1):page163_i54@pure_quanta.q_cap(chips)',
 PATH='I54',
 DRAWING='@S9S_MB_2U_LIB.S9S_MB_2U(SCH_1):PAGE237',
 PHYS_PAGE='163',
 XY='(2500,6150)',
 ROT='0',
 VER='1',
 PACK_TYPE='0402',
 LOCATION='PC1322',
 CDS_LIB='pure_quanta',
 CDS_PART_NAME='Q_CAP_0402-100PF,50V,5%,EMPTY,A',
 TOLERANCE='5%',
 MATERIAL='EMPTY',
 VOLTAGE='50V',
 ROOM='NIC1_P3V3_BOM2',
 VALUE='100PF',
 PRIM_FILE='./archive_libs/logical/q_cap/chips/chips.prt';

PART_NAME
 PC1338 'Q_CAP_0402-0.1UF,25V,10%,X7R,CA':;

SECTION_NUMBER 1
 '@S9S_MB_2U_LIB.S9S_MB_2U(SCH_1):PAGE271_I6@PURE_QUANTA.Q_CAP(CHIPS)':
 C_PATH='@s9s_mb_2u_lib.s9s_mb_2u(sch_1):page271_i6@pure_quanta.q_cap(chips)',
 P_PATH='@s9s_mb_2u_lib.s9s_mb_2u(sch_1):page285_i6@pure_quanta.q_cap(chips)',
 PATH='I6',
 DRAWING='@S9S_MB_2U_LIB.S9S_MB_2U(SCH_1):PAGE271',
 PHYS_PAGE='285',
 XY='(-3325,-1900)',
 ROT='0',
 VER='2',
 PACK_TYPE='0402',
 LOCATION='PC1338',
 CDS_LIB='pure_quanta',
 CDS_PART_NAME='Q_CAP_0402-0.1UF,25V,10%,X7R,CA',
 TOLERANCE='10%',
 MATERIAL='X7R',
 VOLTAGE='25V',
 VALUE='0.1UF',
 PRIM_FILE='./archive_libs/logical/q_cap/chips/chips.prt';

PART_NAME
 PC1339 'Q_CAP_0402-0.1UF,25V,10%,X7R,CA':;

SECTION_NUMBER 1
 '@S9S_MB_2U_LIB.S9S_MB_2U(SCH_1):PAGE271_I34@PURE_QUANTA.Q_CAP(CHIPS)':
 C_PATH='@s9s_mb_2u_lib.s9s_mb_2u(sch_1):page271_i34@pure_quanta.q_cap(chips)',
 P_PATH='@s9s_mb_2u_lib.s9s_mb_2u(sch_1):page285_i34@pure_quanta.q_cap(chips)',
 PATH='I34',
 DRAWING='@S9S_MB_2U_LIB.S9S_MB_2U(SCH_1):PAGE271',
 PHYS_PAGE='285',
 XY='(-3300,925)',
 ROT='0',
 VER='2',
 PACK_TYPE='0402',
 LOCATION='PC1339',
 CDS_LIB='pure_quanta',
 CDS_PART_NAME='Q_CAP_0402-0.1UF,25V,10%,X7R,CA',
 TOLERANCE='10%',
 MATERIAL='X7R',
 VOLTAGE='25V',
 VALUE='0.1UF',
 PRIM_FILE='./archive_libs/logical/q_cap/chips/chips.prt';

PART_NAME
 PC1340 'Q_CAP_0402-0.1UF,25V,10%,X7R,CA':;

SECTION_NUMBER 1
 '@S9S_MB_2U_LIB.S9S_MB_2U(SCH_1):PAGE254_I12@PURE_QUANTA.Q_CAP(CHIPS)':
 C_PATH='@s9s_mb_2u_lib.s9s_mb_2u(sch_1):page254_i12@pure_quanta.q_cap(chips)',
 P_PATH='@s9s_mb_2u_lib.s9s_mb_2u(sch_1):page268_i12@pure_quanta.q_cap(chips)',
 PATH='I12',
 DRAWING='@S9S_MB_2U_LIB.S9S_MB_2U(SCH_1):PAGE254',
 PHYS_PAGE='268',
 XY='(3325,1300)',
 ROT='0',
 VER='2',
 PACK_TYPE='0402',
 LOCATION='PC1340',
 CDS_LIB='pure_quanta',
 CDS_PART_NAME='Q_CAP_0402-0.1UF,25V,10%,X7R,CA',
 TOLERANCE='10%',
 MATERIAL='X7R',
 VOLTAGE='25V',
 VALUE='0.1UF',
 PRIM_FILE='./archive_libs/logical/q_cap/chips/chips.prt';

PART_NAME
 PC1341 'Q_CAP_0402-0.1UF,25V,10%,X7R,CA':;

SECTION_NUMBER 1
 '@S9S_MB_2U_LIB.S9S_MB_2U(SCH_1):PAGE254_I26@PURE_QUANTA.Q_CAP(CHIPS)':
 C_PATH='@s9s_mb_2u_lib.s9s_mb_2u(sch_1):page254_i26@pure_quanta.q_cap(chips)',
 P_PATH='@s9s_mb_2u_lib.s9s_mb_2u(sch_1):page268_i26@pure_quanta.q_cap(chips)',
 PATH='I26',
 DRAWING='@S9S_MB_2U_LIB.S9S_MB_2U(SCH_1):PAGE254',
 PHYS_PAGE='268',
 XY='(3350,4125)',
 ROT='0',
 VER='2',
 PACK_TYPE='0402',
 LOCATION='PC1341',
 CDS_LIB='pure_quanta',
 CDS_PART_NAME='Q_CAP_0402-0.1UF,25V,10%,X7R,CA',
 TOLERANCE='10%',
 MATERIAL='X7R',
 VOLTAGE='25V',
 VALUE='0.1UF',
 PRIM_FILE='./archive_libs/logical/q_cap/chips/chips.prt';

PART_NAME
 PC1342 'Q_CAP_0402-0.1UF,25V,10%,X7R,CA':;

SECTION_NUMBER 1
 '@S9S_MB_2U_LIB.S9S_MB_2U(SCH_1):PAGE255_I11@PURE_QUANTA.Q_CAP(CHIPS)':
 C_PATH='@s9s_mb_2u_lib.s9s_mb_2u(sch_1):page255_i11@pure_quanta.q_cap(chips)',
 P_PATH='@s9s_mb_2u_lib.s9s_mb_2u(sch_1):page269_i11@pure_quanta.q_cap(chips)',
 PATH='I11',
 DRAWING='@S9S_MB_2U_LIB.S9S_MB_2U(SCH_1):PAGE255',
 PHYS_PAGE='269',
 XY='(2400,1700)',
 ROT='0',
 VER='2',
 PACK_TYPE='0402',
 LOCATION='PC1342',
 CDS_LIB='pure_quanta',
 CDS_PART_NAME='Q_CAP_0402-0.1UF,25V,10%,X7R,CA',
 TOLERANCE='10%',
 MATERIAL='X7R',
 VOLTAGE='25V',
 VALUE='0.1UF',
 PRIM_FILE='./archive_libs/logical/q_cap/chips/chips.prt';

PART_NAME
 PC1343 'Q_CAP_0402-0.1UF,25V,10%,X7R,CA':;

SECTION_NUMBER 1
 '@S9S_MB_2U_LIB.S9S_MB_2U(SCH_1):PAGE255_I25@PURE_QUANTA.Q_CAP(CHIPS)':
 C_PATH='@s9s_mb_2u_lib.s9s_mb_2u(sch_1):page255_i25@pure_quanta.q_cap(chips)',
 P_PATH='@s9s_mb_2u_lib.s9s_mb_2u(sch_1):page269_i25@pure_quanta.q_cap(chips)',
 PATH='I25',
 DRAWING='@S9S_MB_2U_LIB.S9S_MB_2U(SCH_1):PAGE255',
 PHYS_PAGE='269',
 XY='(2425,4525)',
 ROT='0',
 VER='2',
 PACK_TYPE='0402',
 LOCATION='PC1343',
 CDS_LIB='pure_quanta',
 CDS_PART_NAME='Q_CAP_0402-0.1UF,25V,10%,X7R,CA',
 TOLERANCE='10%',
 MATERIAL='X7R',
 VOLTAGE='25V',
 VALUE='0.1UF',
 PRIM_FILE='./archive_libs/logical/q_cap/chips/chips.prt';

PART_NAME
 PC1344 'Q_CAP_0402-0.1UF,25V,10%,X7R,CA':;

SECTION_NUMBER 1
 '@S9S_MB_2U_LIB.S9S_MB_2U(SCH_1):PAGE256_I7@PURE_QUANTA.Q_CAP(CHIPS)':
 C_PATH='@s9s_mb_2u_lib.s9s_mb_2u(sch_1):page256_i7@pure_quanta.q_cap(chips)',
 P_PATH='@s9s_mb_2u_lib.s9s_mb_2u(sch_1):page270_i7@pure_quanta.q_cap(chips)',
 PATH='I7',
 DRAWING='@S9S_MB_2U_LIB.S9S_MB_2U(SCH_1):PAGE256',
 PHYS_PAGE='270',
 XY='(-7025,-5600)',
 ROT='0',
 VER='2',
 PACK_TYPE='0402',
 LOCATION='PC1344',
 CDS_LIB='pure_quanta',
 CDS_PART_NAME='Q_CAP_0402-0.1UF,25V,10%,X7R,CA',
 TOLERANCE='10%',
 MATERIAL='X7R',
 VOLTAGE='25V',
 VALUE='0.1UF',
 PRIM_FILE='./archive_libs/logical/q_cap/chips/chips.prt';

PART_NAME
 PC1345 'Q_CAP_0402-0.1UF,25V,10%,X7R,CA':;

SECTION_NUMBER 1
 '@S9S_MB_2U_LIB.S9S_MB_2U(SCH_1):PAGE256_I29@PURE_QUANTA.Q_CAP(CHIPS)':
 C_PATH='@s9s_mb_2u_lib.s9s_mb_2u(sch_1):page256_i29@pure_quanta.q_cap(chips)',
 P_PATH='@s9s_mb_2u_lib.s9s_mb_2u(sch_1):page270_i29@pure_quanta.q_cap(chips)',
 PATH='I29',
 DRAWING='@S9S_MB_2U_LIB.S9S_MB_2U(SCH_1):PAGE256',
 PHYS_PAGE='270',
 XY='(-6950,-2775)',
 ROT='0',
 VER='2',
 PACK_TYPE='0402',
 LOCATION='PC1345',
 CDS_LIB='pure_quanta',
 CDS_PART_NAME='Q_CAP_0402-0.1UF,25V,10%,X7R,CA',
 TOLERANCE='10%',
 MATERIAL='X7R',
 VOLTAGE='25V',
 VALUE='0.1UF',
 PRIM_FILE='./archive_libs/logical/q_cap/chips/chips.prt';

PART_NAME
 PC1346 'Q_CAP_0402-0.1UF,25V,10%,X7R,CA':;

SECTION_NUMBER 1
 '@S9S_MB_2U_LIB.S9S_MB_2U(SCH_1):PAGE261_I11@PURE_QUANTA.Q_CAP(CHIPS)':
 C_PATH='@s9s_mb_2u_lib.s9s_mb_2u(sch_1):page261_i11@pure_quanta.q_cap(chips)',
 P_PATH='@s9s_mb_2u_lib.s9s_mb_2u(sch_1):page275_i11@pure_quanta.q_cap(chips)',
 PATH='I11',
 DRAWING='@S9S_MB_2U_LIB.S9S_MB_2U(SCH_1):PAGE261',
 PHYS_PAGE='275',
 XY='(-10225,1800)',
 ROT='0',
 VER='2',
 PACK_TYPE='0402',
 LOCATION='PC1346',
 CDS_LIB='pure_quanta',
 CDS_PART_NAME='Q_CAP_0402-0.1UF,25V,10%,X7R,CA',
 TOLERANCE='10%',
 MATERIAL='X7R',
 VOLTAGE='25V',
 VALUE='0.1UF',
 PRIM_FILE='./archive_libs/logical/q_cap/chips/chips.prt';

PART_NAME
 PC1347 'Q_CAP_0402-0.1UF,25V,10%,X7R,CA':;

SECTION_NUMBER 1
 '@S9S_MB_2U_LIB.S9S_MB_2U(SCH_1):PAGE261_I25@PURE_QUANTA.Q_CAP(CHIPS)':
 C_PATH='@s9s_mb_2u_lib.s9s_mb_2u(sch_1):page261_i25@pure_quanta.q_cap(chips)',
 P_PATH='@s9s_mb_2u_lib.s9s_mb_2u(sch_1):page275_i25@pure_quanta.q_cap(chips)',
 PATH='I25',
 DRAWING='@S9S_MB_2U_LIB.S9S_MB_2U(SCH_1):PAGE261',
 PHYS_PAGE='275',
 XY='(-10200,4600)',
 ROT='0',
 VER='2',
 PACK_TYPE='0402',
 LOCATION='PC1347',
 CDS_LIB='pure_quanta',
 CDS_PART_NAME='Q_CAP_0402-0.1UF,25V,10%,X7R,CA',
 TOLERANCE='10%',
 MATERIAL='X7R',
 VOLTAGE='25V',
 VALUE='0.1UF',
 PRIM_FILE='./archive_libs/logical/q_cap/chips/chips.prt';

PART_NAME
 PC1348 'Q_CAP_0402-0.1UF,25V,10%,X7R,CA':;

SECTION_NUMBER 1
 '@S9S_MB_2U_LIB.S9S_MB_2U(SCH_1):PAGE262_I10@PURE_QUANTA.Q_CAP(CHIPS)':
 C_PATH='@s9s_mb_2u_lib.s9s_mb_2u(sch_1):page262_i10@pure_quanta.q_cap(chips)',
 P_PATH='@s9s_mb_2u_lib.s9s_mb_2u(sch_1):page276_i10@pure_quanta.q_cap(chips)',
 PATH='I10',
 DRAWING='@S9S_MB_2U_LIB.S9S_MB_2U(SCH_1):PAGE262',
 PHYS_PAGE='276',
 XY='(-9500,3350)',
 ROT='0',
 VER='2',
 PACK_TYPE='0402',
 LOCATION='PC1348',
 CDS_LIB='pure_quanta',
 CDS_PART_NAME='Q_CAP_0402-0.1UF,25V,10%,X7R,CA',
 TOLERANCE='10%',
 MATERIAL='X7R',
 VOLTAGE='25V',
 VALUE='0.1UF',
 PRIM_FILE='./archive_libs/logical/q_cap/chips/chips.prt';

PART_NAME
 PC1349 'Q_CAP_0402-0.1UF,25V,10%,X7R,CA':;

SECTION_NUMBER 1
 '@S9S_MB_2U_LIB.S9S_MB_2U(SCH_1):PAGE257_I35@PURE_QUANTA.Q_CAP(CHIPS)':
 C_PATH='@s9s_mb_2u_lib.s9s_mb_2u(sch_1):page257_i35@pure_quanta.q_cap(chips)',
 P_PATH='@s9s_mb_2u_lib.s9s_mb_2u(sch_1):page271_i35@pure_quanta.q_cap(chips)',
 PATH='I35',
 DRAWING='@S9S_MB_2U_LIB.S9S_MB_2U(SCH_1):PAGE257',
 PHYS_PAGE='271',
 XY='(-3975,5000)',
 ROT='0',
 VER='2',
 PACK_TYPE='0402',
 LOCATION='PC1349',
 CDS_LIB='pure_quanta',
 CDS_PART_NAME='Q_CAP_0402-0.1UF,25V,10%,X7R,CA',
 TOLERANCE='10%',
 MATERIAL='X7R',
 VOLTAGE='25V',
 VALUE='0.1UF',
 PRIM_FILE='./archive_libs/logical/q_cap/chips/chips.prt';

PART_NAME
 PC1350 'Q_CAP_0402-0.1UF,25V,10%,X7R,CA':;

SECTION_NUMBER 1
 '@S9S_MB_2U_LIB.S9S_MB_2U(SCH_1):PAGE257_I15@PURE_QUANTA.Q_CAP(CHIPS)':
 C_PATH='@s9s_mb_2u_lib.s9s_mb_2u(sch_1):page257_i15@pure_quanta.q_cap(chips)',
 P_PATH='@s9s_mb_2u_lib.s9s_mb_2u(sch_1):page271_i15@pure_quanta.q_cap(chips)',
 PATH='I15',
 DRAWING='@S9S_MB_2U_LIB.S9S_MB_2U(SCH_1):PAGE257',
 PHYS_PAGE='271',
 XY='(-3975,2200)',
 ROT='0',
 VER='2',
 PACK_TYPE='0402',
 LOCATION='PC1350',
 CDS_LIB='pure_quanta',
 CDS_PART_NAME='Q_CAP_0402-0.1UF,25V,10%,X7R,CA',
 TOLERANCE='10%',
 MATERIAL='X7R',
 VOLTAGE='25V',
 VALUE='0.1UF',
 PRIM_FILE='./archive_libs/logical/q_cap/chips/chips.prt';

PART_NAME
 PC1351 'Q_CAP_0402-0.1UF,25V,10%,X7R,CA':;

SECTION_NUMBER 1
 '@S9S_MB_2U_LIB.S9S_MB_2U(SCH_1):PAGE258_I25@PURE_QUANTA.Q_CAP(CHIPS)':
 C_PATH='@s9s_mb_2u_lib.s9s_mb_2u(sch_1):page258_i25@pure_quanta.q_cap(chips)',
 P_PATH='@s9s_mb_2u_lib.s9s_mb_2u(sch_1):page272_i25@pure_quanta.q_cap(chips)',
 PATH='I25',
 DRAWING='@S9S_MB_2U_LIB.S9S_MB_2U(SCH_1):PAGE258',
 PHYS_PAGE='272',
 XY='(-10425,4700)',
 ROT='0',
 VER='2',
 PACK_TYPE='0402',
 LOCATION='PC1351',
 CDS_LIB='pure_quanta',
 CDS_PART_NAME='Q_CAP_0402-0.1UF,25V,10%,X7R,CA',
 TOLERANCE='10%',
 MATERIAL='X7R',
 VOLTAGE='25V',
 VALUE='0.1UF',
 PRIM_FILE='./archive_libs/logical/q_cap/chips/chips.prt';

PART_NAME
 PC1352 'Q_CAP_0402-0.1UF,25V,10%,X7R,CA':;

SECTION_NUMBER 1
 '@S9S_MB_2U_LIB.S9S_MB_2U(SCH_1):PAGE258_I9@PURE_QUANTA.Q_CAP(CHIPS)':
 C_PATH='@s9s_mb_2u_lib.s9s_mb_2u(sch_1):page258_i9@pure_quanta.q_cap(chips)',
 P_PATH='@s9s_mb_2u_lib.s9s_mb_2u(sch_1):page272_i9@pure_quanta.q_cap(chips)',
 PATH='I9',
 DRAWING='@S9S_MB_2U_LIB.S9S_MB_2U(SCH_1):PAGE258',
 PHYS_PAGE='272',
 XY='(-10425,1900)',
 ROT='0',
 VER='2',
 PACK_TYPE='0402',
 LOCATION='PC1352',
 CDS_LIB='pure_quanta',
 CDS_PART_NAME='Q_CAP_0402-0.1UF,25V,10%,X7R,CA',
 TOLERANCE='10%',
 MATERIAL='X7R',
 VOLTAGE='25V',
 VALUE='0.1UF',
 PRIM_FILE='./archive_libs/logical/q_cap/chips/chips.prt';

PART_NAME
 PC1354 'Q_CAP_0402-0.1UF,25V,10%,X7R,CA':;

SECTION_NUMBER 1
 '@S9S_MB_2U_LIB.S9S_MB_2U(SCH_1):PAGE265_I7@PURE_QUANTA.Q_CAP(CHIPS)':
 C_PATH='@s9s_mb_2u_lib.s9s_mb_2u(sch_1):page265_i7@pure_quanta.q_cap(chips)',
 P_PATH='@s9s_mb_2u_lib.s9s_mb_2u(sch_1):page279_i7@pure_quanta.q_cap(chips)',
 PATH='I7',
 DRAWING='@S9S_MB_2U_LIB.S9S_MB_2U(SCH_1):PAGE265',
 PHYS_PAGE='279',
 XY='(-8050,1750)',
 ROT='0',
 VER='2',
 PACK_TYPE='0402',
 LOCATION='PC1354',
 CDS_LIB='pure_quanta',
 CDS_PART_NAME='Q_CAP_0402-0.1UF,25V,10%,X7R,CA',
 TOLERANCE='10%',
 MATERIAL='X7R',
 VOLTAGE='25V',
 VALUE='0.1UF',
 PRIM_FILE='./archive_libs/logical/q_cap/chips/chips.prt';

PART_NAME
 PC1355 'Q_CAP_0402-0.1UF,25V,10%,X7R,CA':;

SECTION_NUMBER 1
 '@S9S_MB_2U_LIB.S9S_MB_2U(SCH_1):PAGE253_I11@PURE_QUANTA.Q_CAP(CHIPS)':
 C_PATH='@s9s_mb_2u_lib.s9s_mb_2u(sch_1):page253_i11@pure_quanta.q_cap(chips)',
 P_PATH='@s9s_mb_2u_lib.s9s_mb_2u(sch_1):page267_i11@pure_quanta.q_cap(chips)',
 PATH='I11',
 DRAWING='@S9S_MB_2U_LIB.S9S_MB_2U(SCH_1):PAGE253',
 PHYS_PAGE='267',
 XY='(-3475,-2325)',
 ROT='0',
 VER='2',
 PACK_TYPE='0402',
 LOCATION='PC1355',
 CDS_LIB='pure_quanta',
 CDS_PART_NAME='Q_CAP_0402-0.1UF,25V,10%,X7R,CA',
 TOLERANCE='10%',
 MATERIAL='X7R',
 VOLTAGE='25V',
 VALUE='0.1UF',
 PRIM_FILE='./archive_libs/logical/q_cap/chips/chips.prt';

PART_NAME
 PC1356 'Q_CAP_0402-0.1UF,25V,10%,X7R,CA':;

SECTION_NUMBER 1
 '@S9S_MB_2U_LIB.S9S_MB_2U(SCH_1):PAGE253_I34@PURE_QUANTA.Q_CAP(CHIPS)':
 C_PATH='@s9s_mb_2u_lib.s9s_mb_2u(sch_1):page253_i34@pure_quanta.q_cap(chips)',
 P_PATH='@s9s_mb_2u_lib.s9s_mb_2u(sch_1):page267_i34@pure_quanta.q_cap(chips)',
 PATH='I34',
 DRAWING='@S9S_MB_2U_LIB.S9S_MB_2U(SCH_1):PAGE253',
 PHYS_PAGE='267',
 XY='(-3450,500)',
 ROT='0',
 VER='2',
 PACK_TYPE='0402',
 LOCATION='PC1356',
 CDS_LIB='pure_quanta',
 CDS_PART_NAME='Q_CAP_0402-0.1UF,25V,10%,X7R,CA',
 TOLERANCE='10%',
 MATERIAL='X7R',
 VOLTAGE='25V',
 VALUE='0.1UF',
 PRIM_FILE='./archive_libs/logical/q_cap/chips/chips.prt';

PART_NAME
 PC1358 'Q_CAP_0402-0.1UF,25V,10%,X7R,CA':;

SECTION_NUMBER 1
 '@S9S_MB_2U_LIB.S9S_MB_2U(SCH_1):PAGE272_I6@PURE_QUANTA.Q_CAP(CHIPS)':
 C_PATH='@s9s_mb_2u_lib.s9s_mb_2u(sch_1):page272_i6@pure_quanta.q_cap(chips)',
 P_PATH='@s9s_mb_2u_lib.s9s_mb_2u(sch_1):page286_i6@pure_quanta.q_cap(chips)',
 PATH='I6',
 DRAWING='@S9S_MB_2U_LIB.S9S_MB_2U(SCH_1):PAGE272',
 PHYS_PAGE='286',
 XY='(-2050,-1750)',
 ROT='0',
 VER='2',
 PACK_TYPE='0402',
 LOCATION='PC1358',
 CDS_LIB='pure_quanta',
 CDS_PART_NAME='Q_CAP_0402-0.1UF,25V,10%,X7R,CA',
 TOLERANCE='10%',
 MATERIAL='X7R',
 VOLTAGE='25V',
 VALUE='0.1UF',
 PRIM_FILE='./archive_libs/logical/q_cap/chips/chips.prt';

PART_NAME
 PC1359 'Q_CAP_0402-0.1UF,25V,10%,X7R,CA':;

SECTION_NUMBER 1
 '@S9S_MB_2U_LIB.S9S_MB_2U(SCH_1):PAGE272_I27@PURE_QUANTA.Q_CAP(CHIPS)':
 C_PATH='@s9s_mb_2u_lib.s9s_mb_2u(sch_1):page272_i27@pure_quanta.q_cap(chips)',
 P_PATH='@s9s_mb_2u_lib.s9s_mb_2u(sch_1):page286_i27@pure_quanta.q_cap(chips)',
 PATH='I27',
 DRAWING='@S9S_MB_2U_LIB.S9S_MB_2U(SCH_1):PAGE272',
 PHYS_PAGE='286',
 XY='(-2025,1075)',
 ROT='0',
 VER='2',
 PACK_TYPE='0402',
 LOCATION='PC1359',
 CDS_LIB='pure_quanta',
 CDS_PART_NAME='Q_CAP_0402-0.1UF,25V,10%,X7R,CA',
 TOLERANCE='10%',
 MATERIAL='X7R',
 VOLTAGE='25V',
 VALUE='0.1UF',
 PRIM_FILE='./archive_libs/logical/q_cap/chips/chips.prt';

PART_NAME
 PC1360 'Q_CAP_0402-0.1UF,25V,10%,X7R,CA':;

SECTION_NUMBER 1
 '@S9S_MB_2U_LIB.S9S_MB_2U(SCH_1):PAGE273_I15@PURE_QUANTA.Q_CAP(CHIPS)':
 C_PATH='@s9s_mb_2u_lib.s9s_mb_2u(sch_1):page273_i15@pure_quanta.q_cap(chips)',
 P_PATH='@s9s_mb_2u_lib.s9s_mb_2u(sch_1):page287_i15@pure_quanta.q_cap(chips)',
 PATH='I15',
 DRAWING='@S9S_MB_2U_LIB.S9S_MB_2U(SCH_1):PAGE273',
 PHYS_PAGE='287',
 XY='(4100,-525)',
 ROT='0',
 VER='2',
 PACK_TYPE='0402',
 LOCATION='PC1360',
 CDS_LIB='pure_quanta',
 CDS_PART_NAME='Q_CAP_0402-0.1UF,25V,10%,X7R,CA',
 TOLERANCE='10%',
 MATERIAL='X7R',
 VOLTAGE='25V',
 VALUE='0.1UF',
 PRIM_FILE='./archive_libs/logical/q_cap/chips/chips.prt';

PART_NAME
 PC1361 'Q_CAP_0402-0.1UF,25V,10%,X7R,CA':;

SECTION_NUMBER 1
 '@S9S_MB_2U_LIB.S9S_MB_2U(SCH_1):PAGE273_I36@PURE_QUANTA.Q_CAP(CHIPS)':
 C_PATH='@s9s_mb_2u_lib.s9s_mb_2u(sch_1):page273_i36@pure_quanta.q_cap(chips)',
 P_PATH='@s9s_mb_2u_lib.s9s_mb_2u(sch_1):page287_i36@pure_quanta.q_cap(chips)',
 PATH='I36',
 DRAWING='@S9S_MB_2U_LIB.S9S_MB_2U(SCH_1):PAGE273',
 PHYS_PAGE='287',
 XY='(4125,2300)',
 ROT='0',
 VER='2',
 PACK_TYPE='0402',
 LOCATION='PC1361',
 CDS_LIB='pure_quanta',
 CDS_PART_NAME='Q_CAP_0402-0.1UF,25V,10%,X7R,CA',
 TOLERANCE='10%',
 MATERIAL='X7R',
 VOLTAGE='25V',
 VALUE='0.1UF',
 PRIM_FILE='./archive_libs/logical/q_cap/chips/chips.prt';

PART_NAME
 PC1362 'Q_CAP_0402-0.1UF,25V,10%,X7R,CA':;

SECTION_NUMBER 1
 '@S9S_MB_2U_LIB.S9S_MB_2U(SCH_1):PAGE274_I7@PURE_QUANTA.Q_CAP(CHIPS)':
 C_PATH='@s9s_mb_2u_lib.s9s_mb_2u(sch_1):page274_i7@pure_quanta.q_cap(chips)',
 P_PATH='@s9s_mb_2u_lib.s9s_mb_2u(sch_1):page288_i7@pure_quanta.q_cap(chips)',
 PATH='I7',
 DRAWING='@S9S_MB_2U_LIB.S9S_MB_2U(SCH_1):PAGE274',
 PHYS_PAGE='288',
 XY='(-7225,1500)',
 ROT='0',
 VER='2',
 PACK_TYPE='0402',
 LOCATION='PC1362',
 CDS_LIB='pure_quanta',
 CDS_PART_NAME='Q_CAP_0402-0.1UF,25V,10%,X7R,CA',
 TOLERANCE='10%',
 MATERIAL='X7R',
 VOLTAGE='25V',
 VALUE='0.1UF',
 PRIM_FILE='./archive_libs/logical/q_cap/chips/chips.prt';

PART_NAME
 PC1363 'Q_CAP_0402-0.1UF,25V,10%,X7R,CA':;

SECTION_NUMBER 1
 '@S9S_MB_2U_LIB.S9S_MB_2U(SCH_1):PAGE274_I32@PURE_QUANTA.Q_CAP(CHIPS)':
 C_PATH='@s9s_mb_2u_lib.s9s_mb_2u(sch_1):page274_i32@pure_quanta.q_cap(chips)',
 P_PATH='@s9s_mb_2u_lib.s9s_mb_2u(sch_1):page288_i32@pure_quanta.q_cap(chips)',
 PATH='I32',
 DRAWING='@S9S_MB_2U_LIB.S9S_MB_2U(SCH_1):PAGE274',
 PHYS_PAGE='288',
 XY='(-7200,4325)',
 ROT='0',
 VER='2',
 PACK_TYPE='0402',
 LOCATION='PC1363',
 CDS_LIB='pure_quanta',
 CDS_PART_NAME='Q_CAP_0402-0.1UF,25V,10%,X7R,CA',
 TOLERANCE='10%',
 MATERIAL='X7R',
 VOLTAGE='25V',
 VALUE='0.1UF',
 PRIM_FILE='./archive_libs/logical/q_cap/chips/chips.prt';

PART_NAME
 PC1364 'Q_CAP_0402-0.1UF,25V,10%,X7R,CA':;

SECTION_NUMBER 1
 '@S9S_MB_2U_LIB.S9S_MB_2U(SCH_1):PAGE279_I20@PURE_QUANTA.Q_CAP(CHIPS)':
 C_PATH='@s9s_mb_2u_lib.s9s_mb_2u(sch_1):page279_i20@pure_quanta.q_cap(chips)',
 P_PATH='@s9s_mb_2u_lib.s9s_mb_2u(sch_1):page293_i20@pure_quanta.q_cap(chips)',
 PATH='I20',
 DRAWING='@S9S_MB_2U_LIB.S9S_MB_2U(SCH_1):PAGE279',
 PHYS_PAGE='293',
 XY='(-8325,11050)',
 ROT='0',
 VER='2',
 PACK_TYPE='0402',
 LOCATION='PC1364',
 CDS_LIB='pure_quanta',
 CDS_PART_NAME='Q_CAP_0402-0.1UF,25V,10%,X7R,CA',
 TOLERANCE='10%',
 MATERIAL='X7R',
 VOLTAGE='25V',
 VALUE='0.1UF',
 PRIM_FILE='./archive_libs/logical/q_cap/chips/chips.prt';

PART_NAME
 PC1365 'Q_CAP_0402-0.1UF,25V,10%,X7R,CA':;

SECTION_NUMBER 1
 '@S9S_MB_2U_LIB.S9S_MB_2U(SCH_1):PAGE279_I6@PURE_QUANTA.Q_CAP(CHIPS)':
 C_PATH='@s9s_mb_2u_lib.s9s_mb_2u(sch_1):page279_i6@pure_quanta.q_cap(chips)',
 P_PATH='@s9s_mb_2u_lib.s9s_mb_2u(sch_1):page293_i6@pure_quanta.q_cap(chips)',
 PATH='I6',
 DRAWING='@S9S_MB_2U_LIB.S9S_MB_2U(SCH_1):PAGE279',
 PHYS_PAGE='293',
 XY='(-8325,8250)',
 ROT='0',
 VER='2',
 PACK_TYPE='0402',
 LOCATION='PC1365',
 CDS_LIB='pure_quanta',
 CDS_PART_NAME='Q_CAP_0402-0.1UF,25V,10%,X7R,CA',
 TOLERANCE='10%',
 MATERIAL='X7R',
 VOLTAGE='25V',
 VALUE='0.1UF',
 PRIM_FILE='./archive_libs/logical/q_cap/chips/chips.prt';

PART_NAME
 PC1366 'Q_CAP_0402-0.1UF,25V,10%,X7R,CA':;

SECTION_NUMBER 1
 '@S9S_MB_2U_LIB.S9S_MB_2U(SCH_1):PAGE280_I9@PURE_QUANTA.Q_CAP(CHIPS)':
 C_PATH='@s9s_mb_2u_lib.s9s_mb_2u(sch_1):page280_i9@pure_quanta.q_cap(chips)',
 P_PATH='@s9s_mb_2u_lib.s9s_mb_2u(sch_1):page294_i9@pure_quanta.q_cap(chips)',
 PATH='I9',
 DRAWING='@S9S_MB_2U_LIB.S9S_MB_2U(SCH_1):PAGE280',
 PHYS_PAGE='294',
 XY='(-5925,9000)',
 ROT='0',
 VER='2',
 PACK_TYPE='0402',
 LOCATION='PC1366',
 CDS_LIB='pure_quanta',
 CDS_PART_NAME='Q_CAP_0402-0.1UF,25V,10%,X7R,CA',
 TOLERANCE='10%',
 MATERIAL='X7R',
 VOLTAGE='25V',
 VALUE='0.1UF',
 PRIM_FILE='./archive_libs/logical/q_cap/chips/chips.prt';

PART_NAME
 PC1367 'Q_CAP_0402-0.1UF,25V,10%,X7R,CA':;

SECTION_NUMBER 1
 '@S9S_MB_2U_LIB.S9S_MB_2U(SCH_1):PAGE275_I29@PURE_QUANTA.Q_CAP(CHIPS)':
 C_PATH='@s9s_mb_2u_lib.s9s_mb_2u(sch_1):page275_i29@pure_quanta.q_cap(chips)',
 P_PATH='@s9s_mb_2u_lib.s9s_mb_2u(sch_1):page289_i29@pure_quanta.q_cap(chips)',
 PATH='I29',
 DRAWING='@S9S_MB_2U_LIB.S9S_MB_2U(SCH_1):PAGE275',
 PHYS_PAGE='289',
 XY='(-9975,4475)',
 ROT='0',
 VER='2',
 PACK_TYPE='0402',
 LOCATION='PC1367',
 CDS_LIB='pure_quanta',
 CDS_PART_NAME='Q_CAP_0402-0.1UF,25V,10%,X7R,CA',
 TOLERANCE='10%',
 MATERIAL='X7R',
 VOLTAGE='25V',
 VALUE='0.1UF',
 PRIM_FILE='./archive_libs/logical/q_cap/chips/chips.prt';

PART_NAME
 PC1368 'Q_CAP_0402-0.1UF,25V,10%,X7R,CA':;

SECTION_NUMBER 1
 '@S9S_MB_2U_LIB.S9S_MB_2U(SCH_1):PAGE275_I8@PURE_QUANTA.Q_CAP(CHIPS)':
 C_PATH='@s9s_mb_2u_lib.s9s_mb_2u(sch_1):page275_i8@pure_quanta.q_cap(chips)',
 P_PATH='@s9s_mb_2u_lib.s9s_mb_2u(sch_1):page289_i8@pure_quanta.q_cap(chips)',
 PATH='I8',
 DRAWING='@S9S_MB_2U_LIB.S9S_MB_2U(SCH_1):PAGE275',
 PHYS_PAGE='289',
 XY='(-9975,1675)',
 ROT='0',
 VER='2',
 PACK_TYPE='0402',
 LOCATION='PC1368',
 CDS_LIB='pure_quanta',
 CDS_PART_NAME='Q_CAP_0402-0.1UF,25V,10%,X7R,CA',
 TOLERANCE='10%',
 MATERIAL='X7R',
 VOLTAGE='25V',
 VALUE='0.1UF',
 PRIM_FILE='./archive_libs/logical/q_cap/chips/chips.prt';

PART_NAME
 PC1369 'Q_CAP_0402-0.1UF,25V,10%,X7R,CA':;

SECTION_NUMBER 1
 '@S9S_MB_2U_LIB.S9S_MB_2U(SCH_1):PAGE276_I23@PURE_QUANTA.Q_CAP(CHIPS)':
 C_PATH='@s9s_mb_2u_lib.s9s_mb_2u(sch_1):page276_i23@pure_quanta.q_cap(chips)',
 P_PATH='@s9s_mb_2u_lib.s9s_mb_2u(sch_1):page290_i23@pure_quanta.q_cap(chips)',
 PATH='I23',
 DRAWING='@S9S_MB_2U_LIB.S9S_MB_2U(SCH_1):PAGE276',
 PHYS_PAGE='290',
 XY='(-7050,6425)',
 ROT='0',
 VER='2',
 PACK_TYPE='0402',
 LOCATION='PC1369',
 CDS_LIB='pure_quanta',
 CDS_PART_NAME='Q_CAP_0402-0.1UF,25V,10%,X7R,CA',
 TOLERANCE='10%',
 MATERIAL='X7R',
 VOLTAGE='25V',
 VALUE='0.1UF',
 PRIM_FILE='./archive_libs/logical/q_cap/chips/chips.prt';

PART_NAME
 PC1370 'Q_CAP_0402-0.1UF,25V,10%,X7R,CA':;

SECTION_NUMBER 1
 '@S9S_MB_2U_LIB.S9S_MB_2U(SCH_1):PAGE276_I13@PURE_QUANTA.Q_CAP(CHIPS)':
 C_PATH='@s9s_mb_2u_lib.s9s_mb_2u(sch_1):page276_i13@pure_quanta.q_cap(chips)',
 P_PATH='@s9s_mb_2u_lib.s9s_mb_2u(sch_1):page290_i13@pure_quanta.q_cap(chips)',
 PATH='I13',
 DRAWING='@S9S_MB_2U_LIB.S9S_MB_2U(SCH_1):PAGE276',
 PHYS_PAGE='290',
 XY='(-7050,3625)',
 ROT='0',
 VER='2',
 PACK_TYPE='0402',
 LOCATION='PC1370',
 CDS_LIB='pure_quanta',
 CDS_PART_NAME='Q_CAP_0402-0.1UF,25V,10%,X7R,CA',
 TOLERANCE='10%',
 MATERIAL='X7R',
 VOLTAGE='25V',
 VALUE='0.1UF',
 PRIM_FILE='./archive_libs/logical/q_cap/chips/chips.prt';

PART_NAME
 PC1371 'Q_CAP_0402-0.1UF,25V,10%,X7R,CA':;

SECTION_NUMBER 1
 '@S9S_MB_2U_LIB.S9S_MB_2U(SCH_1):PAGE283_I8@PURE_QUANTA.Q_CAP(CHIPS)':
 C_PATH='@s9s_mb_2u_lib.s9s_mb_2u(sch_1):page283_i8@pure_quanta.q_cap(chips)',
 P_PATH='@s9s_mb_2u_lib.s9s_mb_2u(sch_1):page297_i8@pure_quanta.q_cap(chips)',
 PATH='I8',
 DRAWING='@S9S_MB_2U_LIB.S9S_MB_2U(SCH_1):PAGE283',
 PHYS_PAGE='297',
 XY='(-7850,3450)',
 ROT='0',
 VER='2',
 PACK_TYPE='0402',
 LOCATION='PC1371',
 CDS_LIB='pure_quanta',
 CDS_PART_NAME='Q_CAP_0402-0.1UF,25V,10%,X7R,CA',
 TOLERANCE='10%',
 MATERIAL='X7R',
 VOLTAGE='25V',
 VALUE='0.1UF',
 PRIM_FILE='./archive_libs/logical/q_cap/chips/chips.prt';

PART_NAME
 PC1372 'Q_CAP_C0402-1UF,16V,10%,X6S,CHA':;

SECTION_NUMBER 1
 '@S9S_MB_2U_LIB.S9S_MB_2U(SCH_1):PAGE260_I95@PURE_QUANTA.Q_CAP(CHIPS)':
 C_PATH='@s9s_mb_2u_lib.s9s_mb_2u(sch_1):page260_i95@pure_quanta.q_cap(chips)',
 P_PATH='@s9s_mb_2u_lib.s9s_mb_2u(sch_1):page274_i95@pure_quanta.q_cap(chips)',
 PATH='I95',
 DRAWING='@S9S_MB_2U_LIB.S9S_MB_2U(SCH_1):PAGE260',
 PHYS_PAGE='274',
 XY='(-5175,6900)',
 ROT='0',
 VER='1',
 PACK_TYPE='C0402',
 LOCATION='PC1372',
 CDS_LIB='pure_quanta',
 CDS_PART_NAME='Q_CAP_C0402-1UF,16V,10%,X6S,CHA',
 TOLERANCE='10%',
 MATERIAL='X6S',
 VOLTAGE='16V',
 VALUE='1UF',
 PRIM_FILE='./archive_libs/logical/q_cap/chips/chips.prt';

PART_NAME
 PC1420 'Q_CAP_0402-0.01UF,25V,10%,X7R,A':;

SECTION_NUMBER 1
 '@S9S_MB_2U_LIB.S9S_MB_2U(SCH_1):PAGE268_I39@PURE_QUANTA.Q_CAP(CHIPS)':
 C_PATH='@s9s_mb_2u_lib.s9s_mb_2u(sch_1):page268_i39@pure_quanta.q_cap(chips)',
 P_PATH='@s9s_mb_2u_lib.s9s_mb_2u(sch_1):page282_i39@pure_quanta.q_cap(chips)',
 PATH='I39',
 DRAWING='@S9S_MB_2U_LIB.S9S_MB_2U(SCH_1):PAGE268',
 PHYS_PAGE='282',
 XY='(-2725,8700)',
 ROT='0',
 VER='1',
 PACK_TYPE='0402',
 LOCATION='PC1420',
 CDS_LIB='pure_quanta',
 CDS_PART_NAME='Q_CAP_0402-0.01UF,25V,10%,X7R,A',
 TOLERANCE='10%',
 MATERIAL='X7R',
 VOLTAGE='25V',
 VALUE='0.01UF',
 PRIM_FILE='./archive_libs/logical/q_cap/chips/chips.prt';

PART_NAME
 PC1421 'Q_CAP_0402-0.01UF,25V,10%,X7R,A':;

SECTION_NUMBER 1
 '@S9S_MB_2U_LIB.S9S_MB_2U(SCH_1):PAGE267_I40@PURE_QUANTA.Q_CAP(CHIPS)':
 C_PATH='@s9s_mb_2u_lib.s9s_mb_2u(sch_1):page267_i40@pure_quanta.q_cap(chips)',
 P_PATH='@s9s_mb_2u_lib.s9s_mb_2u(sch_1):page281_i40@pure_quanta.q_cap(chips)',
 PATH='I40',
 DRAWING='@S9S_MB_2U_LIB.S9S_MB_2U(SCH_1):PAGE267',
 PHYS_PAGE='281',
 XY='(-5050,2425)',
 ROT='0',
 VER='1',
 PACK_TYPE='0402',
 LOCATION='PC1421',
 CDS_LIB='pure_quanta',
 CDS_PART_NAME='Q_CAP_0402-0.01UF,25V,10%,X7R,A',
 TOLERANCE='10%',
 MATERIAL='X7R',
 VOLTAGE='25V',
 VALUE='0.01UF',
 PRIM_FILE='./archive_libs/logical/q_cap/chips/chips.prt';

PART_NAME
 PC1525 'Q_CAP_C0402-1UF,25V,10%,X6S,CHA':
 ROOM='HSC1_BOM1';

SECTION_NUMBER 1
 '@S9S_MB_2U_LIB.S9S_MB_2U(SCH_1):PAGE301_I20@PURE_QUANTA.Q_CAP(CHIPS)':
 C_PATH='@s9s_mb_2u_lib.s9s_mb_2u(sch_1):page301_i20@pure_quanta.q_cap(chips)',
 P_PATH='@s9s_mb_2u_lib.s9s_mb_2u(sch_1):page302_i20@pure_quanta.q_cap(chips)',
 PATH='I20',
 DRAWING='@S9S_MB_2U_LIB.S9S_MB_2U(SCH_1):PAGE301',
 PHYS_PAGE='302',
 XY='(-3675,1425)',
 ROT='0',
 VER='1',
 PACK_TYPE='C0402',
 LOCATION='PC1525',
 CDS_LIB='pure_quanta',
 CDS_PART_NAME='Q_CAP_C0402-1UF,25V,10%,X6S,CHA',
 TOLERANCE='10%',
 MATERIAL='X6S',
 VOLTAGE='25V',
 ROOM='HSC1_BOM1',
 VALUE='1UF',
 PRIM_FILE='./archive_libs/logical/q_cap/chips/chips.prt';

PART_NAME
 PC1573 'Q_CAPP_SMLF-330UF,2V,35%,SPCAPA':;

SECTION_NUMBER 1
 '@S9S_MB_2U_LIB.S9S_MB_2U(SCH_1):PAGE261_I68@PURE_QUANTA.Q_CAPP(CHIPS)':
 C_PATH='@s9s_mb_2u_lib.s9s_mb_2u(sch_1):page261_i68@pure_quanta.q_capp(chips)',
 P_PATH='@s9s_mb_2u_lib.s9s_mb_2u(sch_1):page275_i68@pure_quanta.q_capp(chips)',
 PATH='I68',
 DRAWING='@S9S_MB_2U_LIB.S9S_MB_2U(SCH_1):PAGE261',
 PHYS_PAGE='275',
 XY='(-4325,4050)',
 ROT='0',
 VER='1',
 PACK_TYPE='SMLF',
 LOCATION='PC1573',
 CDS_LIB='pure_quanta',
 CDS_PART_NAME='Q_CAPP_SMLF-330UF,2V,35%,SPCAPA',
 TOLERANCE='35%',
 MATERIAL='SPCAP',
 VOLTAGE='2V',
 VALUE='330UF',
 PRIM_FILE='./archive_libs/logical/q_capp/chips/chips.prt';

PART_NAME
 PC1574 'Q_CAPP_THLF-560UF,2.5V,20%,OSCA':;

SECTION_NUMBER 1
 '@S9S_MB_2U_LIB.S9S_MB_2U(SCH_1):PAGE261_I66@PURE_QUANTA.Q_CAPP(CHIPS)':
 C_PATH='@s9s_mb_2u_lib.s9s_mb_2u(sch_1):page261_i66@pure_quanta.q_capp(chips)',
 P_PATH='@s9s_mb_2u_lib.s9s_mb_2u(sch_1):page275_i66@pure_quanta.q_capp(chips)',
 PATH='I66',
 DRAWING='@S9S_MB_2U_LIB.S9S_MB_2U(SCH_1):PAGE261',
 PHYS_PAGE='275',
 XY='(-4325,3125)',
 ROT='0',
 VER='1',
 PACK_TYPE='THLF',
 LOCATION='PC1574',
 CDS_LIB='pure_quanta',
 CDS_PART_NAME='Q_CAPP_THLF-560UF,2.5V,20%,OSCA',
 TOLERANCE='20%',
 MATERIAL='OSCON',
 VOLTAGE='2.5V',
 VALUE='560UF',
 PRIM_FILE='./archive_libs/logical/q_capp/chips/chips.prt';

PART_NAME
 PC1575 'Q_CAPP_SMLF-330UF,2V,35%,SPCAPA':;

SECTION_NUMBER 1
 '@S9S_MB_2U_LIB.S9S_MB_2U(SCH_1):PAGE261_I69@PURE_QUANTA.Q_CAPP(CHIPS)':
 C_PATH='@s9s_mb_2u_lib.s9s_mb_2u(sch_1):page261_i69@pure_quanta.q_capp(chips)',
 P_PATH='@s9s_mb_2u_lib.s9s_mb_2u(sch_1):page275_i69@pure_quanta.q_capp(chips)',
 PATH='I69',
 DRAWING='@S9S_MB_2U_LIB.S9S_MB_2U(SCH_1):PAGE261',
 PHYS_PAGE='275',
 XY='(-3750,4050)',
 ROT='0',
 VER='1',
 PACK_TYPE='SMLF',
 LOCATION='PC1575',
 CDS_LIB='pure_quanta',
 CDS_PART_NAME='Q_CAPP_SMLF-330UF,2V,35%,SPCAPA',
 TOLERANCE='35%',
 MATERIAL='SPCAP',
 VOLTAGE='2V',
 VALUE='330UF',
 PRIM_FILE='./archive_libs/logical/q_capp/chips/chips.prt';

PART_NAME
 PC1576 'Q_CAPP_THLF-560UF,2.5V,20%,OSCA':;

SECTION_NUMBER 1
 '@S9S_MB_2U_LIB.S9S_MB_2U(SCH_1):PAGE261_I67@PURE_QUANTA.Q_CAPP(CHIPS)':
 C_PATH='@s9s_mb_2u_lib.s9s_mb_2u(sch_1):page261_i67@pure_quanta.q_capp(chips)',
 P_PATH='@s9s_mb_2u_lib.s9s_mb_2u(sch_1):page275_i67@pure_quanta.q_capp(chips)',
 PATH='I67',
 DRAWING='@S9S_MB_2U_LIB.S9S_MB_2U(SCH_1):PAGE261',
 PHYS_PAGE='275',
 XY='(-3750,3125)',
 ROT='0',
 VER='1',
 PACK_TYPE='THLF',
 LOCATION='PC1576',
 CDS_LIB='pure_quanta',
 CDS_PART_NAME='Q_CAPP_THLF-560UF,2.5V,20%,OSCA',
 TOLERANCE='20%',
 MATERIAL='OSCON',
 VOLTAGE='2.5V',
 VALUE='560UF',
 PRIM_FILE='./archive_libs/logical/q_capp/chips/chips.prt';

PART_NAME
 PC1579 'Q_CAPP_THLF-560UF,2.5V,20%,OSCA':;

SECTION_NUMBER 1
 '@S9S_MB_2U_LIB.S9S_MB_2U(SCH_1):PAGE261_I70@PURE_QUANTA.Q_CAPP(CHIPS)':
 C_PATH='@s9s_mb_2u_lib.s9s_mb_2u(sch_1):page261_i70@pure_quanta.q_capp(chips)',
 P_PATH='@s9s_mb_2u_lib.s9s_mb_2u(sch_1):page275_i70@pure_quanta.q_capp(chips)',
 PATH='I70',
 DRAWING='@S9S_MB_2U_LIB.S9S_MB_2U(SCH_1):PAGE261',
 PHYS_PAGE='275',
 XY='(-3175,3125)',
 ROT='0',
 VER='1',
 PACK_TYPE='THLF',
 LOCATION='PC1579',
 CDS_LIB='pure_quanta',
 CDS_PART_NAME='Q_CAPP_THLF-560UF,2.5V,20%,OSCA',
 TOLERANCE='20%',
 MATERIAL='OSCON',
 VOLTAGE='2.5V',
 VALUE='560UF',
 PRIM_FILE='./archive_libs/logical/q_capp/chips/chips.prt';

PART_NAME
 PC1588 'Q_CAPP_SMLF-330UF,2V,35%,SPCAPA':;

SECTION_NUMBER 1
 '@S9S_MB_2U_LIB.S9S_MB_2U(SCH_1):PAGE279_I61@PURE_QUANTA.Q_CAPP(CHIPS)':
 C_PATH='@s9s_mb_2u_lib.s9s_mb_2u(sch_1):page279_i61@pure_quanta.q_capp(chips)',
 P_PATH='@s9s_mb_2u_lib.s9s_mb_2u(sch_1):page293_i61@pure_quanta.q_capp(chips)',
 PATH='I61',
 DRAWING='@S9S_MB_2U_LIB.S9S_MB_2U(SCH_1):PAGE279',
 PHYS_PAGE='293',
 XY='(-2475,10150)',
 ROT='0',
 VER='1',
 PACK_TYPE='SMLF',
 LOCATION='PC1588',
 CDS_LIB='pure_quanta',
 CDS_PART_NAME='Q_CAPP_SMLF-330UF,2V,35%,SPCAPA',
 TOLERANCE='35%',
 MATERIAL='SPCAP',
 VOLTAGE='2V',
 VALUE='330UF',
 PRIM_FILE='./archive_libs/logical/q_capp/chips/chips.prt';

PART_NAME
 PC1593 'Q_CAPP_THLF-560UF,2.5V,20%,OSCA':;

SECTION_NUMBER 1
 '@S9S_MB_2U_LIB.S9S_MB_2U(SCH_1):PAGE279_I59@PURE_QUANTA.Q_CAPP(CHIPS)':
 C_PATH='@s9s_mb_2u_lib.s9s_mb_2u(sch_1):page279_i59@pure_quanta.q_capp(chips)',
 P_PATH='@s9s_mb_2u_lib.s9s_mb_2u(sch_1):page293_i59@pure_quanta.q_capp(chips)',
 PATH='I59',
 DRAWING='@S9S_MB_2U_LIB.S9S_MB_2U(SCH_1):PAGE279',
 PHYS_PAGE='293',
 XY='(-2475,9225)',
 ROT='0',
 VER='1',
 PACK_TYPE='THLF',
 LOCATION='PC1593',
 CDS_LIB='pure_quanta',
 CDS_PART_NAME='Q_CAPP_THLF-560UF,2.5V,20%,OSCA',
 TOLERANCE='20%',
 MATERIAL='OSCON',
 VOLTAGE='2.5V',
 VALUE='560UF',
 PRIM_FILE='./archive_libs/logical/q_capp/chips/chips.prt';

PART_NAME
 PC1594 'Q_CAPP_SMLF-330UF,2V,35%,SPCAPA':;

SECTION_NUMBER 1
 '@S9S_MB_2U_LIB.S9S_MB_2U(SCH_1):PAGE279_I62@PURE_QUANTA.Q_CAPP(CHIPS)':
 C_PATH='@s9s_mb_2u_lib.s9s_mb_2u(sch_1):page279_i62@pure_quanta.q_capp(chips)',
 P_PATH='@s9s_mb_2u_lib.s9s_mb_2u(sch_1):page293_i62@pure_quanta.q_capp(chips)',
 PATH='I62',
 DRAWING='@S9S_MB_2U_LIB.S9S_MB_2U(SCH_1):PAGE279',
 PHYS_PAGE='293',
 XY='(-1900,10150)',
 ROT='0',
 VER='1',
 PACK_TYPE='SMLF',
 LOCATION='PC1594',
 CDS_LIB='pure_quanta',
 CDS_PART_NAME='Q_CAPP_SMLF-330UF,2V,35%,SPCAPA',
 TOLERANCE='35%',
 MATERIAL='SPCAP',
 VOLTAGE='2V',
 VALUE='330UF',
 PRIM_FILE='./archive_libs/logical/q_capp/chips/chips.prt';

PART_NAME
 PC1595 'Q_CAPP_THLF-560UF,2.5V,20%,OSCA':;

SECTION_NUMBER 1
 '@S9S_MB_2U_LIB.S9S_MB_2U(SCH_1):PAGE279_I60@PURE_QUANTA.Q_CAPP(CHIPS)':
 C_PATH='@s9s_mb_2u_lib.s9s_mb_2u(sch_1):page279_i60@pure_quanta.q_capp(chips)',
 P_PATH='@s9s_mb_2u_lib.s9s_mb_2u(sch_1):page293_i60@pure_quanta.q_capp(chips)',
 PATH='I60',
 DRAWING='@S9S_MB_2U_LIB.S9S_MB_2U(SCH_1):PAGE279',
 PHYS_PAGE='293',
 XY='(-1900,9225)',
 ROT='0',
 VER='1',
 PACK_TYPE='THLF',
 LOCATION='PC1595',
 CDS_LIB='pure_quanta',
 CDS_PART_NAME='Q_CAPP_THLF-560UF,2.5V,20%,OSCA',
 TOLERANCE='20%',
 MATERIAL='OSCON',
 VOLTAGE='2.5V',
 VALUE='560UF',
 PRIM_FILE='./archive_libs/logical/q_capp/chips/chips.prt';

PART_NAME
 PC1596 'Q_CAPP_THLF-560UF,2.5V,20%,OSCA':;

SECTION_NUMBER 1
 '@S9S_MB_2U_LIB.S9S_MB_2U(SCH_1):PAGE279_I71@PURE_QUANTA.Q_CAPP(CHIPS)':
 C_PATH='@s9s_mb_2u_lib.s9s_mb_2u(sch_1):page279_i71@pure_quanta.q_capp(chips)',
 P_PATH='@s9s_mb_2u_lib.s9s_mb_2u(sch_1):page293_i71@pure_quanta.q_capp(chips)',
 PATH='I71',
 DRAWING='@S9S_MB_2U_LIB.S9S_MB_2U(SCH_1):PAGE279',
 PHYS_PAGE='293',
 XY='(-1325,9225)',
 ROT='0',
 VER='1',
 PACK_TYPE='THLF',
 LOCATION='PC1596',
 CDS_LIB='pure_quanta',
 CDS_PART_NAME='Q_CAPP_THLF-560UF,2.5V,20%,OSCA',
 TOLERANCE='20%',
 MATERIAL='OSCON',
 VOLTAGE='2.5V',
 VALUE='560UF',
 PRIM_FILE='./archive_libs/logical/q_capp/chips/chips.prt';

PART_NAME
 PC1599 'Q_CAP_C0805-22UF,10V,20%,X6S,CA':;

SECTION_NUMBER 1
 '@S9S_MB_2U_LIB.S9S_MB_2U(SCH_1):PAGE245_I134@PURE_QUANTA.Q_CAP(CHIPS)':
 C_PATH='@s9s_mb_2u_lib.s9s_mb_2u(sch_1):page245_i134@pure_quanta.q_cap(chips)',
 P_PATH='@s9s_mb_2u_lib.s9s_mb_2u(sch_1):page259_i134@pure_quanta.q_cap(chips)',
 PATH='I134',
 DRAWING='@S9S_MB_2U_LIB.S9S_MB_2U(SCH_1):PAGE245',
 PHYS_PAGE='259',
 XY='(2950,-975)',
 ROT='0',
 VER='1',
 PACK_TYPE='C0805',
 LOCATION='PC1599',
 CDS_LIB='pure_quanta',
 CDS_PART_NAME='Q_CAP_C0805-22UF,10V,20%,X6S,CA',
 TOLERANCE='20%',
 MATERIAL='X6S',
 VOLTAGE='10V',
 VALUE='22UF',
 PRIM_FILE='./archive_libs/logical/q_cap/chips/chips.prt';

PART_NAME
 PC1600 'Q_CAP_C0805-22UF,10V,20%,X6S,CA':;

SECTION_NUMBER 1
 '@S9S_MB_2U_LIB.S9S_MB_2U(SCH_1):PAGE245_I136@PURE_QUANTA.Q_CAP(CHIPS)':
 C_PATH='@s9s_mb_2u_lib.s9s_mb_2u(sch_1):page245_i136@pure_quanta.q_cap(chips)',
 P_PATH='@s9s_mb_2u_lib.s9s_mb_2u(sch_1):page259_i136@pure_quanta.q_cap(chips)',
 PATH='I136',
 DRAWING='@S9S_MB_2U_LIB.S9S_MB_2U(SCH_1):PAGE245',
 PHYS_PAGE='259',
 XY='(3325,-975)',
 ROT='0',
 VER='1',
 PACK_TYPE='C0805',
 LOCATION='PC1600',
 CDS_LIB='pure_quanta',
 CDS_PART_NAME='Q_CAP_C0805-22UF,10V,20%,X6S,CA',
 TOLERANCE='20%',
 MATERIAL='X6S',
 VOLTAGE='10V',
 VALUE='22UF',
 PRIM_FILE='./archive_libs/logical/q_cap/chips/chips.prt';

PART_NAME
 PC1642 'Q_CAP_C0402-1UF,25V,10%,X6S,CHA':;

SECTION_NUMBER 1
 '@S9S_MB_2U_LIB.S9S_MB_2U(SCH_1):PAGE249_I4@PURE_QUANTA.Q_CAP(CHIPS)':
 C_PATH='@s9s_mb_2u_lib.s9s_mb_2u(sch_1):page249_i4@pure_quanta.q_cap(chips)',
 P_PATH='@s9s_mb_2u_lib.s9s_mb_2u(sch_1):page263_i4@pure_quanta.q_cap(chips)',
 PATH='I4',
 DRAWING='@S9S_MB_2U_LIB.S9S_MB_2U(SCH_1):PAGE249',
 BOM_COST='VR_PCH',
 PHYS_PAGE='263',
 XY='(-5750,5175)',
 ROT='0',
 VER='1',
 PACK_TYPE='C0402',
 LOCATION='PC1642',
 SEC='1',
 CDS_LIB='pure_quanta',
 CDS_PART_NAME='Q_CAP_C0402-1UF,25V,10%,X6S,CHA',
 SEC_TYPE='C0402',
 TOLERANCE='10%',
 MATERIAL='X6S',
 VOLTAGE='25V',
 VALUE='1UF',
 PRIM_FILE='./archive_libs/logical/q_cap/chips/chips.prt';

PART_NAME
 PC1644 'Q_CAPP_THLF-560UF,2.5V,20%,OSCA':;

SECTION_NUMBER 1
 '@S9S_MB_2U_LIB.S9S_MB_2U(SCH_1):PAGE265_I27@PURE_QUANTA.Q_CAPP(CHIPS)':
 C_PATH='@s9s_mb_2u_lib.s9s_mb_2u(sch_1):page265_i27@pure_quanta.q_capp(chips)',
 P_PATH='@s9s_mb_2u_lib.s9s_mb_2u(sch_1):page279_i27@pure_quanta.q_capp(chips)',
 PATH='I27',
 DRAWING='@S9S_MB_2U_LIB.S9S_MB_2U(SCH_1):PAGE265',
 PHYS_PAGE='279',
 XY='(-2675,275)',
 ROT='0',
 VER='1',
 PACK_TYPE='THLF',
 LOCATION='PC1644',
 CDS_LIB='pure_quanta',
 CDS_PART_NAME='Q_CAPP_THLF-560UF,2.5V,20%,OSCA',
 TOLERANCE='20%',
 MATERIAL='OSCON',
 VOLTAGE='2.5V',
 VALUE='560UF',
 PRIM_FILE='./archive_libs/logical/q_capp/chips/chips.prt';

PART_NAME
 PC1645 'Q_CAPP_THLF-560UF,2.5V,20%,OSCA':;

SECTION_NUMBER 1
 '@S9S_MB_2U_LIB.S9S_MB_2U(SCH_1):PAGE265_I34@PURE_QUANTA.Q_CAPP(CHIPS)':
 C_PATH='@s9s_mb_2u_lib.s9s_mb_2u(sch_1):page265_i34@pure_quanta.q_capp(chips)',
 P_PATH='@s9s_mb_2u_lib.s9s_mb_2u(sch_1):page279_i34@pure_quanta.q_capp(chips)',
 PATH='I34',
 DRAWING='@S9S_MB_2U_LIB.S9S_MB_2U(SCH_1):PAGE265',
 PHYS_PAGE='279',
 XY='(-2175,275)',
 ROT='0',
 VER='1',
 PACK_TYPE='THLF',
 LOCATION='PC1645',
 CDS_LIB='pure_quanta',
 CDS_PART_NAME='Q_CAPP_THLF-560UF,2.5V,20%,OSCA',
 TOLERANCE='20%',
 MATERIAL='OSCON',
 VOLTAGE='2.5V',
 VALUE='560UF',
 PRIM_FILE='./archive_libs/logical/q_capp/chips/chips.prt';

PART_NAME
 PC1648 'Q_CAP_C0402-100NF,50V,10%,X7R,A':;

SECTION_NUMBER 1
 '@S9S_MB_2U_LIB.S9S_MB_2U(SCH_1):PAGE244_I2@PURE_QUANTA.Q_CAP(CHIPS)':
 C_PATH='@s9s_mb_2u_lib.s9s_mb_2u(sch_1):page244_i2@pure_quanta.q_cap(chips)',
 P_PATH='@s9s_mb_2u_lib.s9s_mb_2u(sch_1):page258_i2@pure_quanta.q_cap(chips)',
 PATH='I2',
 DRAWING='@S9S_MB_2U_LIB.S9S_MB_2U(SCH_1):PAGE244',
 PHYS_PAGE='258',
 XY='(-7750,6775)',
 ROT='0',
 VER='1',
 PACK_TYPE='C0402',
 LOCATION='PC1648',
 CDS_LIB='pure_quanta',
 CDS_PART_NAME='Q_CAP_C0402-100NF,50V,10%,X7R,A',
 TOLERANCE='10%',
 MATERIAL='X7R',
 VOLTAGE='50V',
 VALUE='100NF',
 PRIM_FILE='./archive_libs/logical/q_cap/chips/chips.prt';

PART_NAME
 PC1649 'Q_CAP_C0402-100NF,50V,10%,X7R,A':;

SECTION_NUMBER 1
 '@S9S_MB_2U_LIB.S9S_MB_2U(SCH_1):PAGE245_I97@PURE_QUANTA.Q_CAP(CHIPS)':
 C_PATH='@s9s_mb_2u_lib.s9s_mb_2u(sch_1):page245_i97@pure_quanta.q_cap(chips)',
 P_PATH='@s9s_mb_2u_lib.s9s_mb_2u(sch_1):page259_i97@pure_quanta.q_cap(chips)',
 PATH='I97',
 DRAWING='@S9S_MB_2U_LIB.S9S_MB_2U(SCH_1):PAGE245',
 PHYS_PAGE='259',
 XY='(-4525,850)',
 ROT='0',
 VER='1',
 PACK_TYPE='C0402',
 LOCATION='PC1649',
 CDS_LIB='pure_quanta',
 CDS_PART_NAME='Q_CAP_C0402-100NF,50V,10%,X7R,A',
 TOLERANCE='10%',
 MATERIAL='X7R',
 VOLTAGE='50V',
 VALUE='100NF',
 PRIM_FILE='./archive_libs/logical/q_cap/chips/chips.prt';

PART_NAME
 PC1650 'Q_CAP_C0402-100NF,50V,10%,X7R,A':;

SECTION_NUMBER 1
 '@S9S_MB_2U_LIB.S9S_MB_2U(SCH_1):PAGE248_I18@PURE_QUANTA.Q_CAP(CHIPS)':
 C_PATH='@s9s_mb_2u_lib.s9s_mb_2u(sch_1):page248_i18@pure_quanta.q_cap(chips)',
 P_PATH='@s9s_mb_2u_lib.s9s_mb_2u(sch_1):page262_i18@pure_quanta.q_cap(chips)',
 PATH='I18',
 DRAWING='@S9S_MB_2U_LIB.S9S_MB_2U(SCH_1):PAGE248',
 PHYS_PAGE='262',
 XY='(-4900,425)',
 ROT='0',
 VER='1',
 PACK_TYPE='C0402',
 LOCATION='PC1650',
 CDS_LIB='pure_quanta',
 CDS_PART_NAME='Q_CAP_C0402-100NF,50V,10%,X7R,A',
 TOLERANCE='10%',
 MATERIAL='X7R',
 VOLTAGE='50V',
 VALUE='100NF',
 PRIM_FILE='./archive_libs/logical/q_cap/chips/chips.prt';

PART_NAME
 PC1651 'Q_CAP_C0402-100NF,50V,10%,X7R,A':;

SECTION_NUMBER 1
 '@S9S_MB_2U_LIB.S9S_MB_2U(SCH_1):PAGE249_I14@PURE_QUANTA.Q_CAP(CHIPS)':
 C_PATH='@s9s_mb_2u_lib.s9s_mb_2u(sch_1):page249_i14@pure_quanta.q_cap(chips)',
 P_PATH='@s9s_mb_2u_lib.s9s_mb_2u(sch_1):page263_i14@pure_quanta.q_cap(chips)',
 PATH='I14',
 DRAWING='@S9S_MB_2U_LIB.S9S_MB_2U(SCH_1):PAGE249',
 PHYS_PAGE='263',
 XY='(-6350,7025)',
 ROT='0',
 VER='1',
 PACK_TYPE='C0402',
 LOCATION='PC1651',
 CDS_LIB='pure_quanta',
 CDS_PART_NAME='Q_CAP_C0402-100NF,50V,10%,X7R,A',
 TOLERANCE='10%',
 MATERIAL='X7R',
 VOLTAGE='50V',
 VALUE='100NF',
 PRIM_FILE='./archive_libs/logical/q_cap/chips/chips.prt';

PART_NAME
 PC1652 'Q_CAP_C0402-100NF,50V,10%,X7R,A':;

SECTION_NUMBER 1
 '@S9S_MB_2U_LIB.S9S_MB_2U(SCH_1):PAGE253_I80@PURE_QUANTA.Q_CAP(CHIPS)':
 C_PATH='@s9s_mb_2u_lib.s9s_mb_2u(sch_1):page253_i80@pure_quanta.q_cap(chips)',
 P_PATH='@s9s_mb_2u_lib.s9s_mb_2u(sch_1):page267_i80@pure_quanta.q_cap(chips)',
 PATH='I80',
 DRAWING='@S9S_MB_2U_LIB.S9S_MB_2U(SCH_1):PAGE253',
 PHYS_PAGE='267',
 XY='(1450,1825)',
 ROT='2',
 VER='1',
 PACK_TYPE='C0402',
 LOCATION='PC1652',
 CDS_LIB='pure_quanta',
 CDS_PART_NAME='Q_CAP_C0402-100NF,50V,10%,X7R,A',
 TOLERANCE='10%',
 MATERIAL='X7R',
 VOLTAGE='50V',
 VALUE='100NF',
 PRIM_FILE='./archive_libs/logical/q_cap/chips/chips.prt';

PART_NAME
 PC1653 'Q_CAP_C0402-100NF,50V,10%,X7R,A':;

SECTION_NUMBER 1
 '@S9S_MB_2U_LIB.S9S_MB_2U(SCH_1):PAGE257_I78@PURE_QUANTA.Q_CAP(CHIPS)':
 C_PATH='@s9s_mb_2u_lib.s9s_mb_2u(sch_1):page257_i78@pure_quanta.q_cap(chips)',
 P_PATH='@s9s_mb_2u_lib.s9s_mb_2u(sch_1):page271_i78@pure_quanta.q_cap(chips)',
 PATH='I78',
 DRAWING='@S9S_MB_2U_LIB.S9S_MB_2U(SCH_1):PAGE257',
 PHYS_PAGE='271',
 XY='(1000,5875)',
 ROT='0',
 VER='1',
 PACK_TYPE='C0402',
 LOCATION='PC1653',
 CDS_LIB='pure_quanta',
 CDS_PART_NAME='Q_CAP_C0402-100NF,50V,10%,X7R,A',
 TOLERANCE='10%',
 MATERIAL='X7R',
 VOLTAGE='50V',
 VALUE='100NF',
 PRIM_FILE='./archive_libs/logical/q_cap/chips/chips.prt';

PART_NAME
 PC1654 'Q_CAP_C0402-100NF,50V,10%,X7R,A':;

SECTION_NUMBER 1
 '@S9S_MB_2U_LIB.S9S_MB_2U(SCH_1):PAGE258_I57@PURE_QUANTA.Q_CAP(CHIPS)':
 C_PATH='@s9s_mb_2u_lib.s9s_mb_2u(sch_1):page258_i57@pure_quanta.q_cap(chips)',
 P_PATH='@s9s_mb_2u_lib.s9s_mb_2u(sch_1):page272_i57@pure_quanta.q_cap(chips)',
 PATH='I57',
 DRAWING='@S9S_MB_2U_LIB.S9S_MB_2U(SCH_1):PAGE258',
 PHYS_PAGE='272',
 XY='(-5450,5575)',
 ROT='0',
 VER='1',
 PACK_TYPE='C0402',
 LOCATION='PC1654',
 CDS_LIB='pure_quanta',
 CDS_PART_NAME='Q_CAP_C0402-100NF,50V,10%,X7R,A',
 TOLERANCE='10%',
 MATERIAL='X7R',
 VOLTAGE='50V',
 VALUE='100NF',
 PRIM_FILE='./archive_libs/logical/q_cap/chips/chips.prt';

PART_NAME
 PC1655 'Q_CAP_C0402-100NF,50V,10%,X7R,A':;

SECTION_NUMBER 1
 '@S9S_MB_2U_LIB.S9S_MB_2U(SCH_1):PAGE261_I60@PURE_QUANTA.Q_CAP(CHIPS)':
 C_PATH='@s9s_mb_2u_lib.s9s_mb_2u(sch_1):page261_i60@pure_quanta.q_cap(chips)',
 P_PATH='@s9s_mb_2u_lib.s9s_mb_2u(sch_1):page275_i60@pure_quanta.q_cap(chips)',
 PATH='I60',
 DRAWING='@S9S_MB_2U_LIB.S9S_MB_2U(SCH_1):PAGE261',
 PHYS_PAGE='275',
 XY='(-5025,5900)',
 ROT='0',
 VER='1',
 PACK_TYPE='C0402',
 LOCATION='PC1655',
 CDS_LIB='pure_quanta',
 CDS_PART_NAME='Q_CAP_C0402-100NF,50V,10%,X7R,A',
 TOLERANCE='10%',
 MATERIAL='X7R',
 VOLTAGE='50V',
 VALUE='100NF',
 PRIM_FILE='./archive_libs/logical/q_cap/chips/chips.prt';

PART_NAME
 PC1656 'Q_CAP_C0402-100NF,50V,10%,X7R,A':;

SECTION_NUMBER 1
 '@S9S_MB_2U_LIB.S9S_MB_2U(SCH_1):PAGE271_I79@PURE_QUANTA.Q_CAP(CHIPS)':
 C_PATH='@s9s_mb_2u_lib.s9s_mb_2u(sch_1):page271_i79@pure_quanta.q_cap(chips)',
 P_PATH='@s9s_mb_2u_lib.s9s_mb_2u(sch_1):page285_i79@pure_quanta.q_cap(chips)',
 PATH='I79',
 DRAWING='@S9S_MB_2U_LIB.S9S_MB_2U(SCH_1):PAGE271',
 PHYS_PAGE='285',
 XY='(1400,2250)',
 ROT='2',
 VER='1',
 PACK_TYPE='C0402',
 LOCATION='PC1656',
 CDS_LIB='pure_quanta',
 CDS_PART_NAME='Q_CAP_C0402-100NF,50V,10%,X7R,A',
 TOLERANCE='10%',
 MATERIAL='X7R',
 VOLTAGE='50V',
 VALUE='100NF',
 PRIM_FILE='./archive_libs/logical/q_cap/chips/chips.prt';

PART_NAME
 PC1657 'Q_CAP_C0402-100NF,50V,10%,X7R,A':;

SECTION_NUMBER 1
 '@S9S_MB_2U_LIB.S9S_MB_2U(SCH_1):PAGE275_I77@PURE_QUANTA.Q_CAP(CHIPS)':
 C_PATH='@s9s_mb_2u_lib.s9s_mb_2u(sch_1):page275_i77@pure_quanta.q_cap(chips)',
 P_PATH='@s9s_mb_2u_lib.s9s_mb_2u(sch_1):page289_i77@pure_quanta.q_cap(chips)',
 PATH='I77',
 DRAWING='@S9S_MB_2U_LIB.S9S_MB_2U(SCH_1):PAGE275',
 PHYS_PAGE='289',
 XY='(-5000,5350)',
 ROT='0',
 VER='1',
 PACK_TYPE='C0402',
 LOCATION='PC1657',
 CDS_LIB='pure_quanta',
 CDS_PART_NAME='Q_CAP_C0402-100NF,50V,10%,X7R,A',
 TOLERANCE='10%',
 MATERIAL='X7R',
 VOLTAGE='50V',
 VALUE='100NF',
 PRIM_FILE='./archive_libs/logical/q_cap/chips/chips.prt';

PART_NAME
 PC1658 'Q_CAP_C0402-100NF,50V,10%,X7R,A':;

SECTION_NUMBER 1
 '@S9S_MB_2U_LIB.S9S_MB_2U(SCH_1):PAGE276_I62@PURE_QUANTA.Q_CAP(CHIPS)':
 C_PATH='@s9s_mb_2u_lib.s9s_mb_2u(sch_1):page276_i62@pure_quanta.q_cap(chips)',
 P_PATH='@s9s_mb_2u_lib.s9s_mb_2u(sch_1):page290_i62@pure_quanta.q_cap(chips)',
 PATH='I62',
 DRAWING='@S9S_MB_2U_LIB.S9S_MB_2U(SCH_1):PAGE276',
 PHYS_PAGE='290',
 XY='(-2075,7300)',
 ROT='0',
 VER='1',
 PACK_TYPE='C0402',
 LOCATION='PC1658',
 CDS_LIB='pure_quanta',
 CDS_PART_NAME='Q_CAP_C0402-100NF,50V,10%,X7R,A',
 TOLERANCE='10%',
 MATERIAL='X7R',
 VOLTAGE='50V',
 VALUE='100NF',
 PRIM_FILE='./archive_libs/logical/q_cap/chips/chips.prt';

PART_NAME
 PC1659 'Q_CAP_C0402-100NF,50V,10%,X7R,A':;

SECTION_NUMBER 1
 '@S9S_MB_2U_LIB.S9S_MB_2U(SCH_1):PAGE279_I68@PURE_QUANTA.Q_CAP(CHIPS)':
 C_PATH='@s9s_mb_2u_lib.s9s_mb_2u(sch_1):page279_i68@pure_quanta.q_cap(chips)',
 P_PATH='@s9s_mb_2u_lib.s9s_mb_2u(sch_1):page293_i68@pure_quanta.q_cap(chips)',
 PATH='I68',
 DRAWING='@S9S_MB_2U_LIB.S9S_MB_2U(SCH_1):PAGE279',
 PHYS_PAGE='293',
 XY='(-3125,12350)',
 ROT='0',
 VER='1',
 PACK_TYPE='C0402',
 LOCATION='PC1659',
 CDS_LIB='pure_quanta',
 CDS_PART_NAME='Q_CAP_C0402-100NF,50V,10%,X7R,A',
 TOLERANCE='10%',
 MATERIAL='X7R',
 VOLTAGE='50V',
 VALUE='100NF',
 PRIM_FILE='./archive_libs/logical/q_cap/chips/chips.prt';

PART_NAME
 PC1669 'Q_CAP_C0805-22UF,16V,20%,X6S,CA':;

SECTION_NUMBER 1
 '@S9S_MB_2U_LIB.S9S_MB_2U(SCH_1):PAGE257_I83@PURE_QUANTA.Q_CAP(CHIPS)':
 C_PATH='@s9s_mb_2u_lib.s9s_mb_2u(sch_1):page257_i83@pure_quanta.q_cap(chips)',
 P_PATH='@s9s_mb_2u_lib.s9s_mb_2u(sch_1):page271_i83@pure_quanta.q_cap(chips)',
 PATH='I83',
 DRAWING='@S9S_MB_2U_LIB.S9S_MB_2U(SCH_1):PAGE257',
 PHYS_PAGE='271',
 XY='(1775,5850)',
 ROT='0',
 VER='1',
 PACK_TYPE='C0805',
 LOCATION='PC1669',
 CDS_LIB='pure_quanta',
 CDS_PART_NAME='Q_CAP_C0805-22UF,16V,20%,X6S,CA',
 TOLERANCE='20%',
 MATERIAL='X6S',
 VOLTAGE='16V',
 VALUE='22UF',
 PRIM_FILE='./archive_libs/logical/q_cap/chips/chips.prt';

PART_NAME
 PC1670 'Q_CAP_C0805-22UF,16V,20%,X6S,CA':;

SECTION_NUMBER 1
 '@S9S_MB_2U_LIB.S9S_MB_2U(SCH_1):PAGE257_I84@PURE_QUANTA.Q_CAP(CHIPS)':
 C_PATH='@s9s_mb_2u_lib.s9s_mb_2u(sch_1):page257_i84@pure_quanta.q_cap(chips)',
 P_PATH='@s9s_mb_2u_lib.s9s_mb_2u(sch_1):page271_i84@pure_quanta.q_cap(chips)',
 PATH='I84',
 DRAWING='@S9S_MB_2U_LIB.S9S_MB_2U(SCH_1):PAGE257',
 PHYS_PAGE='271',
 XY='(2075,5850)',
 ROT='0',
 VER='1',
 PACK_TYPE='C0805',
 LOCATION='PC1670',
 CDS_LIB='pure_quanta',
 CDS_PART_NAME='Q_CAP_C0805-22UF,16V,20%,X6S,CA',
 TOLERANCE='20%',
 MATERIAL='X6S',
 VOLTAGE='16V',
 VALUE='22UF',
 PRIM_FILE='./archive_libs/logical/q_cap/chips/chips.prt';

PART_NAME
 PC1671 'Q_CAP_C0805-22UF,16V,20%,X6S,CA':;

SECTION_NUMBER 1
 '@S9S_MB_2U_LIB.S9S_MB_2U(SCH_1):PAGE257_I85@PURE_QUANTA.Q_CAP(CHIPS)':
 C_PATH='@s9s_mb_2u_lib.s9s_mb_2u(sch_1):page257_i85@pure_quanta.q_cap(chips)',
 P_PATH='@s9s_mb_2u_lib.s9s_mb_2u(sch_1):page271_i85@pure_quanta.q_cap(chips)',
 PATH='I85',
 DRAWING='@S9S_MB_2U_LIB.S9S_MB_2U(SCH_1):PAGE257',
 PHYS_PAGE='271',
 XY='(2350,5850)',
 ROT='0',
 VER='1',
 PACK_TYPE='C0805',
 LOCATION='PC1671',
 CDS_LIB='pure_quanta',
 CDS_PART_NAME='Q_CAP_C0805-22UF,16V,20%,X6S,CA',
 TOLERANCE='20%',
 MATERIAL='X6S',
 VOLTAGE='16V',
 VALUE='22UF',
 PRIM_FILE='./archive_libs/logical/q_cap/chips/chips.prt';

PART_NAME
 PC1672 'Q_CAP_C0805-22UF,16V,20%,X6S,CA':;

SECTION_NUMBER 1
 '@S9S_MB_2U_LIB.S9S_MB_2U(SCH_1):PAGE257_I86@PURE_QUANTA.Q_CAP(CHIPS)':
 C_PATH='@s9s_mb_2u_lib.s9s_mb_2u(sch_1):page257_i86@pure_quanta.q_cap(chips)',
 P_PATH='@s9s_mb_2u_lib.s9s_mb_2u(sch_1):page271_i86@pure_quanta.q_cap(chips)',
 PATH='I86',
 DRAWING='@S9S_MB_2U_LIB.S9S_MB_2U(SCH_1):PAGE257',
 PHYS_PAGE='271',
 XY='(2625,5850)',
 ROT='0',
 VER='1',
 PACK_TYPE='C0805',
 LOCATION='PC1672',
 CDS_LIB='pure_quanta',
 CDS_PART_NAME='Q_CAP_C0805-22UF,16V,20%,X6S,CA',
 TOLERANCE='20%',
 MATERIAL='X6S',
 VOLTAGE='16V',
 VALUE='22UF',
 PRIM_FILE='./archive_libs/logical/q_cap/chips/chips.prt';

PART_NAME
 PC1673 'Q_CAP_C0805-22UF,16V,20%,X6S,CA':;

SECTION_NUMBER 1
 '@S9S_MB_2U_LIB.S9S_MB_2U(SCH_1):PAGE258_I75@PURE_QUANTA.Q_CAP(CHIPS)':
 C_PATH='@s9s_mb_2u_lib.s9s_mb_2u(sch_1):page258_i75@pure_quanta.q_cap(chips)',
 P_PATH='@s9s_mb_2u_lib.s9s_mb_2u(sch_1):page272_i75@pure_quanta.q_cap(chips)',
 PATH='I75',
 DRAWING='@S9S_MB_2U_LIB.S9S_MB_2U(SCH_1):PAGE258',
 PHYS_PAGE='272',
 XY='(-4625,5550)',
 ROT='0',
 VER='1',
 PACK_TYPE='C0805',
 LOCATION='PC1673',
 CDS_LIB='pure_quanta',
 CDS_PART_NAME='Q_CAP_C0805-22UF,16V,20%,X6S,CA',
 TOLERANCE='20%',
 MATERIAL='X6S',
 VOLTAGE='16V',
 VALUE='22UF',
 PRIM_FILE='./archive_libs/logical/q_cap/chips/chips.prt';

PART_NAME
 PC1674 'Q_CAP_C0805-22UF,16V,20%,X6S,CA':;

SECTION_NUMBER 1
 '@S9S_MB_2U_LIB.S9S_MB_2U(SCH_1):PAGE258_I76@PURE_QUANTA.Q_CAP(CHIPS)':
 C_PATH='@s9s_mb_2u_lib.s9s_mb_2u(sch_1):page258_i76@pure_quanta.q_cap(chips)',
 P_PATH='@s9s_mb_2u_lib.s9s_mb_2u(sch_1):page272_i76@pure_quanta.q_cap(chips)',
 PATH='I76',
 DRAWING='@S9S_MB_2U_LIB.S9S_MB_2U(SCH_1):PAGE258',
 PHYS_PAGE='272',
 XY='(-4325,5550)',
 ROT='0',
 VER='1',
 PACK_TYPE='C0805',
 LOCATION='PC1674',
 CDS_LIB='pure_quanta',
 CDS_PART_NAME='Q_CAP_C0805-22UF,16V,20%,X6S,CA',
 TOLERANCE='20%',
 MATERIAL='X6S',
 VOLTAGE='16V',
 VALUE='22UF',
 PRIM_FILE='./archive_libs/logical/q_cap/chips/chips.prt';

PART_NAME
 PC1675 'Q_CAP_C0805-22UF,16V,20%,X6S,CA':;

SECTION_NUMBER 1
 '@S9S_MB_2U_LIB.S9S_MB_2U(SCH_1):PAGE258_I77@PURE_QUANTA.Q_CAP(CHIPS)':
 C_PATH='@s9s_mb_2u_lib.s9s_mb_2u(sch_1):page258_i77@pure_quanta.q_cap(chips)',
 P_PATH='@s9s_mb_2u_lib.s9s_mb_2u(sch_1):page272_i77@pure_quanta.q_cap(chips)',
 PATH='I77',
 DRAWING='@S9S_MB_2U_LIB.S9S_MB_2U(SCH_1):PAGE258',
 PHYS_PAGE='272',
 XY='(-4050,5550)',
 ROT='0',
 VER='1',
 PACK_TYPE='C0805',
 LOCATION='PC1675',
 CDS_LIB='pure_quanta',
 CDS_PART_NAME='Q_CAP_C0805-22UF,16V,20%,X6S,CA',
 TOLERANCE='20%',
 MATERIAL='X6S',
 VOLTAGE='16V',
 VALUE='22UF',
 PRIM_FILE='./archive_libs/logical/q_cap/chips/chips.prt';

PART_NAME
 PC1676 'Q_CAP_C0805-22UF,16V,20%,X6S,CA':;

SECTION_NUMBER 1
 '@S9S_MB_2U_LIB.S9S_MB_2U(SCH_1):PAGE258_I79@PURE_QUANTA.Q_CAP(CHIPS)':
 C_PATH='@s9s_mb_2u_lib.s9s_mb_2u(sch_1):page258_i79@pure_quanta.q_cap(chips)',
 P_PATH='@s9s_mb_2u_lib.s9s_mb_2u(sch_1):page272_i79@pure_quanta.q_cap(chips)',
 PATH='I79',
 DRAWING='@S9S_MB_2U_LIB.S9S_MB_2U(SCH_1):PAGE258',
 PHYS_PAGE='272',
 XY='(-3775,5550)',
 ROT='0',
 VER='1',
 PACK_TYPE='C0805',
 LOCATION='PC1676',
 CDS_LIB='pure_quanta',
 CDS_PART_NAME='Q_CAP_C0805-22UF,16V,20%,X6S,CA',
 TOLERANCE='20%',
 MATERIAL='X6S',
 VOLTAGE='16V',
 VALUE='22UF',
 PRIM_FILE='./archive_libs/logical/q_cap/chips/chips.prt';

PART_NAME
 PC1677 'Q_CAP_C0805-22UF,16V,20%,X6S,CA':;

SECTION_NUMBER 1
 '@S9S_MB_2U_LIB.S9S_MB_2U(SCH_1):PAGE275_I80@PURE_QUANTA.Q_CAP(CHIPS)':
 C_PATH='@s9s_mb_2u_lib.s9s_mb_2u(sch_1):page275_i80@pure_quanta.q_cap(chips)',
 P_PATH='@s9s_mb_2u_lib.s9s_mb_2u(sch_1):page289_i80@pure_quanta.q_cap(chips)',
 PATH='I80',
 DRAWING='@S9S_MB_2U_LIB.S9S_MB_2U(SCH_1):PAGE275',
 PHYS_PAGE='289',
 XY='(-4250,5325)',
 ROT='0',
 VER='1',
 PACK_TYPE='C0805',
 LOCATION='PC1677',
 CDS_LIB='pure_quanta',
 CDS_PART_NAME='Q_CAP_C0805-22UF,16V,20%,X6S,CA',
 TOLERANCE='20%',
 MATERIAL='X6S',
 VOLTAGE='16V',
 VALUE='22UF',
 PRIM_FILE='./archive_libs/logical/q_cap/chips/chips.prt';

PART_NAME
 PC1678 'Q_CAP_C0805-22UF,16V,20%,X6S,CA':;

SECTION_NUMBER 1
 '@S9S_MB_2U_LIB.S9S_MB_2U(SCH_1):PAGE275_I83@PURE_QUANTA.Q_CAP(CHIPS)':
 C_PATH='@s9s_mb_2u_lib.s9s_mb_2u(sch_1):page275_i83@pure_quanta.q_cap(chips)',
 P_PATH='@s9s_mb_2u_lib.s9s_mb_2u(sch_1):page289_i83@pure_quanta.q_cap(chips)',
 PATH='I83',
 DRAWING='@S9S_MB_2U_LIB.S9S_MB_2U(SCH_1):PAGE275',
 PHYS_PAGE='289',
 XY='(-3950,5325)',
 ROT='0',
 VER='1',
 PACK_TYPE='C0805',
 LOCATION='PC1678',
 CDS_LIB='pure_quanta',
 CDS_PART_NAME='Q_CAP_C0805-22UF,16V,20%,X6S,CA',
 TOLERANCE='20%',
 MATERIAL='X6S',
 VOLTAGE='16V',
 VALUE='22UF',
 PRIM_FILE='./archive_libs/logical/q_cap/chips/chips.prt';

PART_NAME
 PC1679 'Q_CAP_C0805-22UF,16V,20%,X6S,CA':;

SECTION_NUMBER 1
 '@S9S_MB_2U_LIB.S9S_MB_2U(SCH_1):PAGE275_I84@PURE_QUANTA.Q_CAP(CHIPS)':
 C_PATH='@s9s_mb_2u_lib.s9s_mb_2u(sch_1):page275_i84@pure_quanta.q_cap(chips)',
 P_PATH='@s9s_mb_2u_lib.s9s_mb_2u(sch_1):page289_i84@pure_quanta.q_cap(chips)',
 PATH='I84',
 DRAWING='@S9S_MB_2U_LIB.S9S_MB_2U(SCH_1):PAGE275',
 PHYS_PAGE='289',
 XY='(-3675,5325)',
 ROT='0',
 VER='1',
 PACK_TYPE='C0805',
 LOCATION='PC1679',
 CDS_LIB='pure_quanta',
 CDS_PART_NAME='Q_CAP_C0805-22UF,16V,20%,X6S,CA',
 TOLERANCE='20%',
 MATERIAL='X6S',
 VOLTAGE='16V',
 VALUE='22UF',
 PRIM_FILE='./archive_libs/logical/q_cap/chips/chips.prt';

PART_NAME
 PC1680 'Q_CAP_C0805-22UF,16V,20%,X6S,CA':;

SECTION_NUMBER 1
 '@S9S_MB_2U_LIB.S9S_MB_2U(SCH_1):PAGE275_I85@PURE_QUANTA.Q_CAP(CHIPS)':
 C_PATH='@s9s_mb_2u_lib.s9s_mb_2u(sch_1):page275_i85@pure_quanta.q_cap(chips)',
 P_PATH='@s9s_mb_2u_lib.s9s_mb_2u(sch_1):page289_i85@pure_quanta.q_cap(chips)',
 PATH='I85',
 DRAWING='@S9S_MB_2U_LIB.S9S_MB_2U(SCH_1):PAGE275',
 PHYS_PAGE='289',
 XY='(-3400,5325)',
 ROT='0',
 VER='1',
 PACK_TYPE='C0805',
 LOCATION='PC1680',
 CDS_LIB='pure_quanta',
 CDS_PART_NAME='Q_CAP_C0805-22UF,16V,20%,X6S,CA',
 TOLERANCE='20%',
 MATERIAL='X6S',
 VOLTAGE='16V',
 VALUE='22UF',
 PRIM_FILE='./archive_libs/logical/q_cap/chips/chips.prt';

PART_NAME
 PC1681 'Q_CAP_C0805-22UF,16V,20%,X6S,CA':;

SECTION_NUMBER 1
 '@S9S_MB_2U_LIB.S9S_MB_2U(SCH_1):PAGE276_I75@PURE_QUANTA.Q_CAP(CHIPS)':
 C_PATH='@s9s_mb_2u_lib.s9s_mb_2u(sch_1):page276_i75@pure_quanta.q_cap(chips)',
 P_PATH='@s9s_mb_2u_lib.s9s_mb_2u(sch_1):page290_i75@pure_quanta.q_cap(chips)',
 PATH='I75',
 DRAWING='@S9S_MB_2U_LIB.S9S_MB_2U(SCH_1):PAGE276',
 PHYS_PAGE='290',
 XY='(-1275,7275)',
 ROT='0',
 VER='1',
 PACK_TYPE='C0805',
 LOCATION='PC1681',
 CDS_LIB='pure_quanta',
 CDS_PART_NAME='Q_CAP_C0805-22UF,16V,20%,X6S,CA',
 TOLERANCE='20%',
 MATERIAL='X6S',
 VOLTAGE='16V',
 VALUE='22UF',
 PRIM_FILE='./archive_libs/logical/q_cap/chips/chips.prt';

PART_NAME
 PC1682 'Q_CAP_C0805-22UF,16V,20%,X6S,CA':;

SECTION_NUMBER 1
 '@S9S_MB_2U_LIB.S9S_MB_2U(SCH_1):PAGE276_I77@PURE_QUANTA.Q_CAP(CHIPS)':
 C_PATH='@s9s_mb_2u_lib.s9s_mb_2u(sch_1):page276_i77@pure_quanta.q_cap(chips)',
 P_PATH='@s9s_mb_2u_lib.s9s_mb_2u(sch_1):page290_i77@pure_quanta.q_cap(chips)',
 PATH='I77',
 DRAWING='@S9S_MB_2U_LIB.S9S_MB_2U(SCH_1):PAGE276',
 PHYS_PAGE='290',
 XY='(-975,7275)',
 ROT='0',
 VER='1',
 PACK_TYPE='C0805',
 LOCATION='PC1682',
 CDS_LIB='pure_quanta',
 CDS_PART_NAME='Q_CAP_C0805-22UF,16V,20%,X6S,CA',
 TOLERANCE='20%',
 MATERIAL='X6S',
 VOLTAGE='16V',
 VALUE='22UF',
 PRIM_FILE='./archive_libs/logical/q_cap/chips/chips.prt';

PART_NAME
 PC1683 'Q_CAP_C0805-22UF,16V,20%,X6S,CA':;

SECTION_NUMBER 1
 '@S9S_MB_2U_LIB.S9S_MB_2U(SCH_1):PAGE276_I78@PURE_QUANTA.Q_CAP(CHIPS)':
 C_PATH='@s9s_mb_2u_lib.s9s_mb_2u(sch_1):page276_i78@pure_quanta.q_cap(chips)',
 P_PATH='@s9s_mb_2u_lib.s9s_mb_2u(sch_1):page290_i78@pure_quanta.q_cap(chips)',
 PATH='I78',
 DRAWING='@S9S_MB_2U_LIB.S9S_MB_2U(SCH_1):PAGE276',
 PHYS_PAGE='290',
 XY='(-700,7275)',
 ROT='0',
 VER='1',
 PACK_TYPE='C0805',
 LOCATION='PC1683',
 CDS_LIB='pure_quanta',
 CDS_PART_NAME='Q_CAP_C0805-22UF,16V,20%,X6S,CA',
 TOLERANCE='20%',
 MATERIAL='X6S',
 VOLTAGE='16V',
 VALUE='22UF',
 PRIM_FILE='./archive_libs/logical/q_cap/chips/chips.prt';

PART_NAME
 PC1684 'Q_CAP_C0805-22UF,16V,20%,X6S,CA':;

SECTION_NUMBER 1
 '@S9S_MB_2U_LIB.S9S_MB_2U(SCH_1):PAGE276_I80@PURE_QUANTA.Q_CAP(CHIPS)':
 C_PATH='@s9s_mb_2u_lib.s9s_mb_2u(sch_1):page276_i80@pure_quanta.q_cap(chips)',
 P_PATH='@s9s_mb_2u_lib.s9s_mb_2u(sch_1):page290_i80@pure_quanta.q_cap(chips)',
 PATH='I80',
 DRAWING='@S9S_MB_2U_LIB.S9S_MB_2U(SCH_1):PAGE276',
 PHYS_PAGE='290',
 XY='(-425,7275)',
 ROT='0',
 VER='1',
 PACK_TYPE='C0805',
 LOCATION='PC1684',
 CDS_LIB='pure_quanta',
 CDS_PART_NAME='Q_CAP_C0805-22UF,16V,20%,X6S,CA',
 TOLERANCE='20%',
 MATERIAL='X6S',
 VOLTAGE='16V',
 VALUE='22UF',
 PRIM_FILE='./archive_libs/logical/q_cap/chips/chips.prt';

PART_NAME
 PC1750 'Q_CAP_C0402-33NF,25V,10%,EMPTYA':;

SECTION_NUMBER 1
 '@S9S_MB_2U_LIB.S9S_MB_2U(SCH_1):PAGE328_I68@PURE_QUANTA.Q_CAP(CHIPS)':
 C_PATH='@s9s_mb_2u_lib.s9s_mb_2u(sch_1):page328_i68@pure_quanta.q_cap(chips)',
 P_PATH='@s9s_mb_2u_lib.s9s_mb_2u(sch_1):page304_i68@pure_quanta.q_cap(chips)',
 PATH='I68',
 DRAWING='@S9S_MB_2U_LIB.S9S_MB_2U(SCH_1):PAGE328',
 PHYS_PAGE='304',
 XY='(4025,675)',
 ROT='0',
 VER='1',
 PACK_TYPE='C0402',
 LOCATION='PC1750',
 CDS_LIB='pure_quanta',
 CDS_PART_NAME='Q_CAP_C0402-33NF,25V,10%,EMPTYA',
 TOLERANCE='10%',
 MATERIAL='EMPTY',
 VOLTAGE='25V',
 VALUE='33NF',
 PRIM_FILE='./archive_libs/logical/q_cap/chips/chips.prt';

PART_NAME
 PC1751 'Q_CAP_0402-1NF,50V,10%,EMPTY,CA':;

SECTION_NUMBER 1
 '@S9S_MB_2U_LIB.S9S_MB_2U(SCH_1):PAGE328_I69@PURE_QUANTA.Q_CAP(CHIPS)':
 C_PATH='@s9s_mb_2u_lib.s9s_mb_2u(sch_1):page328_i69@pure_quanta.q_cap(chips)',
 P_PATH='@s9s_mb_2u_lib.s9s_mb_2u(sch_1):page304_i69@pure_quanta.q_cap(chips)',
 PATH='I69',
 DRAWING='@S9S_MB_2U_LIB.S9S_MB_2U(SCH_1):PAGE328',
 PHYS_PAGE='304',
 XY='(4500,375)',
 ROT='0',
 VER='1',
 PACK_TYPE='0402',
 LOCATION='PC1751',
 CDS_LIB='pure_quanta',
 CDS_PART_NAME='Q_CAP_0402-1NF,50V,10%,EMPTY,CA',
 TOLERANCE='10%',
 MATERIAL='EMPTY',
 VOLTAGE='50V',
 VALUE='1NF',
 PRIM_FILE='./archive_libs/logical/q_cap/chips/chips.prt';

PART_NAME
 PC1771 'Q_CAPP_THLF-560UF,6.3V,20%,OSCA':;

SECTION_NUMBER 1
 '@S9S_MB_2U_LIB.S9S_MB_2U(SCH_1):PAGE285_I49@PURE_QUANTA.Q_CAPP(CHIPS)':
 C_PATH='@s9s_mb_2u_lib.s9s_mb_2u(sch_1):page285_i49@pure_quanta.q_capp(chips)',
 P_PATH='@s9s_mb_2u_lib.s9s_mb_2u(sch_1):page299_i49@pure_quanta.q_capp(chips)',
 PATH='I49',
 DRAWING='@S9S_MB_2U_LIB.S9S_MB_2U(SCH_1):PAGE285',
 BOM_COST='VR_PCH',
 PHYS_PAGE='299',
 XY='(-3700,2975)',
 ROT='0',
 VER='1',
 PACK_TYPE='THLF',
 LOCATION='PC1771',
 CDS_LIB='pure_quanta',
 CDS_PART_NAME='Q_CAPP_THLF-560UF,6.3V,20%,OSCA',
 TOLERANCE='20%',
 MATERIAL='OSCON',
 VOLTAGE='6.3V',
 VALUE='560UF',
 PRIM_FILE='./archive_libs/logical/q_capp/chips/chips.prt';

PART_NAME
 PC1789 'Q_CAP_0402-0.1UF,25V,10%,EMPTYA':
 ROOM='HSC1_BOM2';

SECTION_NUMBER 1
 '@S9S_MB_2U_LIB.S9S_MB_2U(SCH_1):PAGE327_I38@PURE_QUANTA.Q_CAP(CHIPS)':
 C_PATH='@s9s_mb_2u_lib.s9s_mb_2u(sch_1):page327_i38@pure_quanta.q_cap(chips)',
 P_PATH='@s9s_mb_2u_lib.s9s_mb_2u(sch_1):page305_i38@pure_quanta.q_cap(chips)',
 PATH='I38',
 DRAWING='@S9S_MB_2U_LIB.S9S_MB_2U(SCH_1):PAGE327',
 PHYS_PAGE='305',
 XY='(4425,1950)',
 ROT='0',
 VER='1',
 PACK_TYPE='0402',
 CDS_LIB='pure_quanta',
 CDS_PART_NAME='Q_CAP_0402-0.1UF,25V,10%,EMPTYA',
 TOLERANCE='10%',
 MATERIAL='EMPTY',
 VOLTAGE='25V',
 ROOM='HSC1_BOM2',
 VALUE='0.1UF',
 PRIM_FILE='./archive_libs/logical/q_cap/chips/chips.prt';

PART_NAME
 PC1845 'Q_CAPP_SMLF-220UF,6.3V,20%,ALUA':;

SECTION_NUMBER 1
 '@S9S_MB_2U_LIB.S9S_MB_2U(SCH_1):PAGE244_I32@PURE_QUANTA.Q_CAPP(CHIPS)':
 C_PATH='@s9s_mb_2u_lib.s9s_mb_2u(sch_1):page244_i32@pure_quanta.q_capp(chips)',
 P_PATH='@s9s_mb_2u_lib.s9s_mb_2u(sch_1):page258_i32@pure_quanta.q_capp(chips)',
 PATH='I32',
 DRAWING='@S9S_MB_2U_LIB.S9S_MB_2U(SCH_1):PAGE244',
 PHYS_PAGE='258',
 XY='(-1125,5950)',
 ROT='0',
 VER='1',
 PACK_TYPE='SMLF',
 LOCATION='PC1845',
 CDS_LIB='pure_quanta',
 CDS_PART_NAME='Q_CAPP_SMLF-220UF,6.3V,20%,ALUA',
 TOLERANCE='20%',
 MATERIAL='ALUM',
 VOLTAGE='6.3V',
 VALUE='220UF',
 PRIM_FILE='./archive_libs/logical/q_capp/chips/chips.prt';

PART_NAME
 PC1846 'Q_CAP_C0402-1UF,16V,10%,X6S,CHA':;

SECTION_NUMBER 1
 '@S9S_MB_2U_LIB.S9S_MB_2U(SCH_1):PAGE244_I14@PURE_QUANTA.Q_CAP(CHIPS)':
 C_PATH='@s9s_mb_2u_lib.s9s_mb_2u(sch_1):page244_i14@pure_quanta.q_cap(chips)',
 P_PATH='@s9s_mb_2u_lib.s9s_mb_2u(sch_1):page258_i14@pure_quanta.q_cap(chips)',
 PATH='I14',
 DRAWING='@S9S_MB_2U_LIB.S9S_MB_2U(SCH_1):PAGE244',
 PHYS_PAGE='258',
 XY='(-5725,6750)',
 ROT='0',
 VER='1',
 PACK_TYPE='C0402',
 LOCATION='PC1846',
 CDS_LIB='pure_quanta',
 CDS_PART_NAME='Q_CAP_C0402-1UF,16V,10%,X6S,CHA',
 TOLERANCE='10%',
 MATERIAL='X6S',
 VOLTAGE='16V',
 VALUE='1UF',
 PRIM_FILE='./archive_libs/logical/q_cap/chips/chips.prt';

PART_NAME
 PC1847 'Q_CAP_C0402-0.22UF,25V,10%,X7RA':;

SECTION_NUMBER 1
 '@S9S_MB_2U_LIB.S9S_MB_2U(SCH_1):PAGE244_I26@PURE_QUANTA.Q_CAP(CHIPS)':
 C_PATH='@s9s_mb_2u_lib.s9s_mb_2u(sch_1):page244_i26@pure_quanta.q_cap(chips)',
 P_PATH='@s9s_mb_2u_lib.s9s_mb_2u(sch_1):page258_i26@pure_quanta.q_cap(chips)',
 PATH='I26',
 DRAWING='@S9S_MB_2U_LIB.S9S_MB_2U(SCH_1):PAGE244',
 PHYS_PAGE='258',
 XY='(-3300,6350)',
 ROT='0',
 VER='1',
 PACK_TYPE='C0402',
 LOCATION='PC1847',
 CDS_LIB='pure_quanta',
 CDS_PART_NAME='Q_CAP_C0402-0.22UF,25V,10%,X7RA',
 TOLERANCE='10%',
 MATERIAL='X7R',
 VOLTAGE='25V',
 VALUE='0.22UF',
 PRIM_FILE='./archive_libs/logical/q_cap/chips/chips.prt';

PART_NAME
 PC1848 'Q_CAP_C0402-1UF,25V,10%,X6S,CHA':
 SIGNAL_MODEL='DEFAULT_CAPACITOR_100000PF_2_1';

SECTION_NUMBER 1
 '@S9S_MB_2U_LIB.S9S_MB_2U(SCH_1):PAGE244_I8@PURE_QUANTA.Q_CAP(CHIPS)':
 C_PATH='@s9s_mb_2u_lib.s9s_mb_2u(sch_1):page244_i8@pure_quanta.q_cap(chips)',
 P_PATH='@s9s_mb_2u_lib.s9s_mb_2u(sch_1):page258_i8@pure_quanta.q_cap(chips)',
 PATH='I8',
 DRAWING='@S9S_MB_2U_LIB.S9S_MB_2U(SCH_1):PAGE244',
 PHYS_PAGE='258',
 XY='(-6400,5475)',
 ROT='2',
 VER='1',
 PACK_TYPE='C0402',
 LOCATION='PC1848',
 SEC='1',
 CDS_LIB='pure_quanta',
 CDS_PART_NAME='Q_CAP_C0402-1UF,25V,10%,X6S,CHA',
 SEC_TYPE='C0402',
 TOLERANCE='10%',
 MATERIAL='X6S',
 SIGNAL_MODEL='DEFAULT_CAPACITOR_100000PF_2_1',
 VOLTAGE='25V',
 VALUE='1UF',
 PRIM_FILE='./archive_libs/logical/q_cap/chips/chips.prt';

PART_NAME
 PC1849 'Q_CAP_C0805-22UF,16V,20%,X6S,CA':;

SECTION_NUMBER 1
 '@S9S_MB_2U_LIB.S9S_MB_2U(SCH_1):PAGE244_I7@PURE_QUANTA.Q_CAP(CHIPS)':
 C_PATH='@s9s_mb_2u_lib.s9s_mb_2u(sch_1):page244_i7@pure_quanta.q_cap(chips)',
 P_PATH='@s9s_mb_2u_lib.s9s_mb_2u(sch_1):page258_i7@pure_quanta.q_cap(chips)',
 PATH='I7',
 DRAWING='@S9S_MB_2U_LIB.S9S_MB_2U(SCH_1):PAGE244',
 PHYS_PAGE='258',
 XY='(-6975,6750)',
 ROT='0',
 VER='1',
 PACK_TYPE='C0805',
 LOCATION='PC1849',
 CDS_LIB='pure_quanta',
 CDS_PART_NAME='Q_CAP_C0805-22UF,16V,20%,X6S,CA',
 TOLERANCE='20%',
 MATERIAL='X6S',
 VOLTAGE='16V',
 VALUE='22UF',
 PRIM_FILE='./archive_libs/logical/q_cap/chips/chips.prt';

PART_NAME
 PC1850 'Q_CAP_C0805-22UF,16V,20%,X6S,CA':;

SECTION_NUMBER 1
 '@S9S_MB_2U_LIB.S9S_MB_2U(SCH_1):PAGE244_I11@PURE_QUANTA.Q_CAP(CHIPS)':
 C_PATH='@s9s_mb_2u_lib.s9s_mb_2u(sch_1):page244_i11@pure_quanta.q_cap(chips)',
 P_PATH='@s9s_mb_2u_lib.s9s_mb_2u(sch_1):page258_i11@pure_quanta.q_cap(chips)',
 PATH='I11',
 DRAWING='@S9S_MB_2U_LIB.S9S_MB_2U(SCH_1):PAGE244',
 PHYS_PAGE='258',
 XY='(-6575,6750)',
 ROT='0',
 VER='1',
 PACK_TYPE='C0805',
 LOCATION='PC1850',
 CDS_LIB='pure_quanta',
 CDS_PART_NAME='Q_CAP_C0805-22UF,16V,20%,X6S,CA',
 TOLERANCE='20%',
 MATERIAL='X6S',
 VOLTAGE='16V',
 VALUE='22UF',
 PRIM_FILE='./archive_libs/logical/q_cap/chips/chips.prt';

PART_NAME
 PC1852 'Q_CAP_0402-0.1UF,25V,10%,X7R,CA':;

SECTION_NUMBER 1
 '@S9S_MB_2U_LIB.S9S_MB_2U(SCH_1):PAGE244_I36@PURE_QUANTA.Q_CAP(CHIPS)':
 C_PATH='@s9s_mb_2u_lib.s9s_mb_2u(sch_1):page244_i36@pure_quanta.q_cap(chips)',
 P_PATH='@s9s_mb_2u_lib.s9s_mb_2u(sch_1):page258_i36@pure_quanta.q_cap(chips)',
 PATH='I36',
 DRAWING='@S9S_MB_2U_LIB.S9S_MB_2U(SCH_1):PAGE244',
 PHYS_PAGE='258',
 XY='(250,5950)',
 ROT='0',
 VER='1',
 PACK_TYPE='0402',
 LOCATION='PC1852',
 SEC='1',
 CDS_LIB='pure_quanta',
 CDS_PART_NAME='Q_CAP_0402-0.1UF,25V,10%,X7R,CA',
 SEC_TYPE='0402',
 TOLERANCE='10%',
 MATERIAL='X7R',
 VOLTAGE='25V',
 VALUE='0.1UF',
 PRIM_FILE='./archive_libs/logical/q_cap/chips/chips.prt';

PART_NAME
 PC1853 'Q_CAP_0402-0.1UF,25V,10%,X7R,CA':;

SECTION_NUMBER 1
 '@S9S_MB_2U_LIB.S9S_MB_2U(SCH_1):PAGE244_I21@PURE_QUANTA.Q_CAP(CHIPS)':
 C_PATH='@s9s_mb_2u_lib.s9s_mb_2u(sch_1):page244_i21@pure_quanta.q_cap(chips)',
 P_PATH='@s9s_mb_2u_lib.s9s_mb_2u(sch_1):page258_i21@pure_quanta.q_cap(chips)',
 PATH='I21',
 DRAWING='@S9S_MB_2U_LIB.S9S_MB_2U(SCH_1):PAGE244',
 PHYS_PAGE='258',
 XY='(-3825,5300)',
 ROT='0',
 VER='1',
 PACK_TYPE='0402',
 LOCATION='PC1853',
 CDS_LIB='pure_quanta',
 CDS_PART_NAME='Q_CAP_0402-0.1UF,25V,10%,X7R,CA',
 TOLERANCE='10%',
 MATERIAL='X7R',
 VOLTAGE='25V',
 VALUE='0.1UF',
 PRIM_FILE='./archive_libs/logical/q_cap/chips/chips.prt';

PART_NAME
 PC1855 'Q_CAP_C0805-22UF,10V,20%,X6S,CA':;

SECTION_NUMBER 1
 '@S9S_MB_2U_LIB.S9S_MB_2U(SCH_1):PAGE244_I33@PURE_QUANTA.Q_CAP(CHIPS)':
 C_PATH='@s9s_mb_2u_lib.s9s_mb_2u(sch_1):page244_i33@pure_quanta.q_cap(chips)',
 P_PATH='@s9s_mb_2u_lib.s9s_mb_2u(sch_1):page258_i33@pure_quanta.q_cap(chips)',
 PATH='I33',
 DRAWING='@S9S_MB_2U_LIB.S9S_MB_2U(SCH_1):PAGE244',
 PHYS_PAGE='258',
 XY='(-675,5950)',
 ROT='0',
 VER='1',
 PACK_TYPE='C0805',
 LOCATION='PC1855',
 CDS_LIB='pure_quanta',
 CDS_PART_NAME='Q_CAP_C0805-22UF,10V,20%,X6S,CA',
 TOLERANCE='20%',
 MATERIAL='X6S',
 VOLTAGE='10V',
 VALUE='22UF',
 PRIM_FILE='./archive_libs/logical/q_cap/chips/chips.prt';

PART_NAME
 PC1856 'Q_CAP_C0805-22UF,10V,20%,X6S,CA':;

SECTION_NUMBER 1
 '@S9S_MB_2U_LIB.S9S_MB_2U(SCH_1):PAGE244_I34@PURE_QUANTA.Q_CAP(CHIPS)':
 C_PATH='@s9s_mb_2u_lib.s9s_mb_2u(sch_1):page244_i34@pure_quanta.q_cap(chips)',
 P_PATH='@s9s_mb_2u_lib.s9s_mb_2u(sch_1):page258_i34@pure_quanta.q_cap(chips)',
 PATH='I34',
 DRAWING='@S9S_MB_2U_LIB.S9S_MB_2U(SCH_1):PAGE244',
 PHYS_PAGE='258',
 XY='(-175,5950)',
 ROT='0',
 VER='1',
 PACK_TYPE='C0805',
 LOCATION='PC1856',
 CDS_LIB='pure_quanta',
 CDS_PART_NAME='Q_CAP_C0805-22UF,10V,20%,X6S,CA',
 TOLERANCE='20%',
 MATERIAL='X6S',
 VOLTAGE='10V',
 VALUE='22UF',
 PRIM_FILE='./archive_libs/logical/q_cap/chips/chips.prt';

PART_NAME
 PC1866 'Q_CAPP_THLF-560UF,6.3V,20%,OSCA':;

SECTION_NUMBER 1
 '@S9S_MB_2U_LIB.S9S_MB_2U(SCH_1):PAGE245_I131@PURE_QUANTA.Q_CAPP(CHIPS)':
 C_PATH='@s9s_mb_2u_lib.s9s_mb_2u(sch_1):page245_i131@pure_quanta.q_capp(chips)',
 P_PATH='@s9s_mb_2u_lib.s9s_mb_2u(sch_1):page259_i131@pure_quanta.q_capp(chips)',
 PATH='I131',
 DRAWING='@S9S_MB_2U_LIB.S9S_MB_2U(SCH_1):PAGE245',
 PHYS_PAGE='259',
 XY='(1650,-975)',
 ROT='0',
 VER='1',
 PACK_TYPE='THLF',
 LOCATION='PC1866',
 CDS_LIB='pure_quanta',
 CDS_PART_NAME='Q_CAPP_THLF-560UF,6.3V,20%,OSCA',
 TOLERANCE='20%',
 MATERIAL='OSCON',
 VOLTAGE='6.3V',
 VALUE='560UF',
 PRIM_FILE='./archive_libs/logical/q_capp/chips/chips.prt';

PART_NAME
 PC1867 'Q_CAPP_THLF-560UF,6.3V,20%,OSCA':;

SECTION_NUMBER 1
 '@S9S_MB_2U_LIB.S9S_MB_2U(SCH_1):PAGE245_I132@PURE_QUANTA.Q_CAPP(CHIPS)':
 C_PATH='@s9s_mb_2u_lib.s9s_mb_2u(sch_1):page245_i132@pure_quanta.q_capp(chips)',
 P_PATH='@s9s_mb_2u_lib.s9s_mb_2u(sch_1):page259_i132@pure_quanta.q_capp(chips)',
 PATH='I132',
 DRAWING='@S9S_MB_2U_LIB.S9S_MB_2U(SCH_1):PAGE245',
 PHYS_PAGE='259',
 XY='(2100,-975)',
 ROT='0',
 VER='1',
 PACK_TYPE='THLF',
 LOCATION='PC1867',
 CDS_LIB='pure_quanta',
 CDS_PART_NAME='Q_CAPP_THLF-560UF,6.3V,20%,OSCA',
 TOLERANCE='20%',
 MATERIAL='OSCON',
 VOLTAGE='6.3V',
 VALUE='560UF',
 PRIM_FILE='./archive_libs/logical/q_capp/chips/chips.prt';

PART_NAME
 PC1868 'Q_CAP_C0805-22UF,10V,20%,X6S,CA':;

SECTION_NUMBER 1
 '@S9S_MB_2U_LIB.S9S_MB_2U(SCH_1):PAGE245_I133@PURE_QUANTA.Q_CAP(CHIPS)':
 C_PATH='@s9s_mb_2u_lib.s9s_mb_2u(sch_1):page245_i133@pure_quanta.q_cap(chips)',
 P_PATH='@s9s_mb_2u_lib.s9s_mb_2u(sch_1):page259_i133@pure_quanta.q_cap(chips)',
 PATH='I133',
 DRAWING='@S9S_MB_2U_LIB.S9S_MB_2U(SCH_1):PAGE245',
 PHYS_PAGE='259',
 XY='(2550,-950)',
 ROT='0',
 VER='1',
 PACK_TYPE='C0805',
 LOCATION='PC1868',
 CDS_LIB='pure_quanta',
 CDS_PART_NAME='Q_CAP_C0805-22UF,10V,20%,X6S,CA',
 TOLERANCE='20%',
 MATERIAL='X6S',
 VOLTAGE='10V',
 VALUE='22UF',
 PRIM_FILE='./archive_libs/logical/q_cap/chips/chips.prt';

PART_NAME
 PC1869 'Q_CAP_0402-0.1UF,25V,10%,X7R,CA':;

SECTION_NUMBER 1
 '@S9S_MB_2U_LIB.S9S_MB_2U(SCH_1):PAGE245_I137@PURE_QUANTA.Q_CAP(CHIPS)':
 C_PATH='@s9s_mb_2u_lib.s9s_mb_2u(sch_1):page245_i137@pure_quanta.q_cap(chips)',
 P_PATH='@s9s_mb_2u_lib.s9s_mb_2u(sch_1):page259_i137@pure_quanta.q_cap(chips)',
 PATH='I137',
 DRAWING='@S9S_MB_2U_LIB.S9S_MB_2U(SCH_1):PAGE245',
 PHYS_PAGE='259',
 XY='(3725,-975)',
 ROT='0',
 VER='1',
 PACK_TYPE='0402',
 LOCATION='PC1869',
 CDS_LIB='pure_quanta',
 CDS_PART_NAME='Q_CAP_0402-0.1UF,25V,10%,X7R,CA',
 TOLERANCE='10%',
 MATERIAL='X7R',
 VOLTAGE='25V',
 VALUE='0.1UF',
 PRIM_FILE='./archive_libs/logical/q_cap/chips/chips.prt';

PART_NAME
 PC1877 'Q_CAP_0402-47PF,50V,5%,NPO,TMPA':;

SECTION_NUMBER 1
 '@S9S_MB_2U_LIB.S9S_MB_2U(SCH_1):PAGE244_I22@PURE_QUANTA.Q_CAP(CHIPS)':
 C_PATH='@s9s_mb_2u_lib.s9s_mb_2u(sch_1):page244_i22@pure_quanta.q_cap(chips)',
 P_PATH='@s9s_mb_2u_lib.s9s_mb_2u(sch_1):page258_i22@pure_quanta.q_cap(chips)',
 PATH='I22',
 DRAWING='@S9S_MB_2U_LIB.S9S_MB_2U(SCH_1):PAGE244',
 PHYS_PAGE='258',
 XY='(-1900,5075)',
 ROT='0',
 VER='2',
 PACK_TYPE='0402',
 LOCATION='PC1877',
 CDS_LIB='pure_quanta',
 CDS_PART_NAME='Q_CAP_0402-47PF,50V,5%,NPO,TMPA',
 TOLERANCE='5%',
 MATERIAL='NPO',
 VOLTAGE='50V',
 VALUE='47PF',
 PRIM_FILE='./archive_libs/logical/q_cap/chips/chips.prt';

PART_NAME
 PC1898 'Q_CAP_C0805-22UF,16V,20%,X6S,CA':;

SECTION_NUMBER 1
 '@S9S_MB_2U_LIB.S9S_MB_2U(SCH_1):PAGE244_I12@PURE_QUANTA.Q_CAP(CHIPS)':
 C_PATH='@s9s_mb_2u_lib.s9s_mb_2u(sch_1):page244_i12@pure_quanta.q_cap(chips)',
 P_PATH='@s9s_mb_2u_lib.s9s_mb_2u(sch_1):page258_i12@pure_quanta.q_cap(chips)',
 PATH='I12',
 DRAWING='@S9S_MB_2U_LIB.S9S_MB_2U(SCH_1):PAGE244',
 PHYS_PAGE='258',
 XY='(-6125,6750)',
 ROT='0',
 VER='1',
 PACK_TYPE='C0805',
 LOCATION='PC1898',
 CDS_LIB='pure_quanta',
 CDS_PART_NAME='Q_CAP_C0805-22UF,16V,20%,X6S,CA',
 TOLERANCE='20%',
 MATERIAL='X6S',
 VOLTAGE='16V',
 VALUE='22UF',
 PRIM_FILE='./archive_libs/logical/q_cap/chips/chips.prt';

PART_NAME
 PC1900 'Q_CAPP_SMLF-330UF,2.5V,+10/-35B':;

SECTION_NUMBER 1
 '@S9S_MB_2U_LIB.S9S_MB_2U(SCH_1):PAGE262_I34@PURE_QUANTA.Q_CAPP(CHIPS)':
 C_PATH='@s9s_mb_2u_lib.s9s_mb_2u(sch_1):page262_i34@pure_quanta.q_capp(chips)',
 P_PATH='@s9s_mb_2u_lib.s9s_mb_2u(sch_1):page276_i34@pure_quanta.q_capp(chips)',
 PATH='I34',
 DRAWING='@S9S_MB_2U_LIB.S9S_MB_2U(SCH_1):PAGE262',
 PHYS_PAGE='276',
 XY='(-3525,3350)',
 ROT='0',
 VER='1',
 PACK_TYPE='SMLF',
 LOCATION='PC1900',
 CDS_LIB='pure_quanta',
 CDS_PART_NAME='Q_CAPP_SMLF-330UF,2.5V,+10/-35B',
 TOLERANCE='+10/-35%',
 MATERIAL='SPCAP',
 VOLTAGE='2.5V',
 VALUE='330UF',
 PRIM_FILE='./archive_libs/logical/q_capp/chips/chips.prt';

PART_NAME
 PC1910 'Q_CAPP_SMLF-330UF,2V,35%,SPCAPA':;

SECTION_NUMBER 1
 '@S9S_MB_2U_LIB.S9S_MB_2U(SCH_1):PAGE265_I26@PURE_QUANTA.Q_CAPP(CHIPS)':
 C_PATH='@s9s_mb_2u_lib.s9s_mb_2u(sch_1):page265_i26@pure_quanta.q_capp(chips)',
 P_PATH='@s9s_mb_2u_lib.s9s_mb_2u(sch_1):page279_i26@pure_quanta.q_capp(chips)',
 PATH='I26',
 DRAWING='@S9S_MB_2U_LIB.S9S_MB_2U(SCH_1):PAGE265',
 PHYS_PAGE='279',
 XY='(-3150,300)',
 ROT='0',
 VER='1',
 PACK_TYPE='SMLF',
 LOCATION='PC1910',
 CDS_LIB='pure_quanta',
 CDS_PART_NAME='Q_CAPP_SMLF-330UF,2V,35%,SPCAPA',
 TOLERANCE='35%',
 MATERIAL='SPCAP',
 VOLTAGE='2V',
 VALUE='330UF',
 PRIM_FILE='./archive_libs/logical/q_capp/chips/chips.prt';

PART_NAME
 PC1920 'Q_CAPP_SMLF-330UF,2.5V,+10/-35A':;

SECTION_NUMBER 1
 '@S9S_MB_2U_LIB.S9S_MB_2U(SCH_1):PAGE253_I63@PURE_QUANTA.Q_CAPP(CHIPS)':
 C_PATH='@s9s_mb_2u_lib.s9s_mb_2u(sch_1):page253_i63@pure_quanta.q_capp(chips)',
 P_PATH='@s9s_mb_2u_lib.s9s_mb_2u(sch_1):page267_i63@pure_quanta.q_capp(chips)',
 PATH='I63',
 DRAWING='@S9S_MB_2U_LIB.S9S_MB_2U(SCH_1):PAGE253',
 PHYS_PAGE='267',
 XY='(3025,-1400)',
 ROT='0',
 VER='1',
 PACK_TYPE='SMLF',
 LOCATION='PC1920',
 CDS_LIB='pure_quanta',
 CDS_PART_NAME='Q_CAPP_SMLF-330UF,2.5V,+10/-35A',
 TOLERANCE='+10/-35%',
 MATERIAL='EMPTY',
 VOLTAGE='2.5V',
 VALUE='330UF',
 PRIM_FILE='./archive_libs/logical/q_capp/chips/chips.prt';

PART_NAME
 PC1930 'Q_CAPP_SMLF-330UF,2.5V,+10/-35B':;

SECTION_NUMBER 1
 '@S9S_MB_2U_LIB.S9S_MB_2U(SCH_1):PAGE280_I33@PURE_QUANTA.Q_CAPP(CHIPS)':
 C_PATH='@s9s_mb_2u_lib.s9s_mb_2u(sch_1):page280_i33@pure_quanta.q_capp(chips)',
 P_PATH='@s9s_mb_2u_lib.s9s_mb_2u(sch_1):page294_i33@pure_quanta.q_capp(chips)',
 PATH='I33',
 DRAWING='@S9S_MB_2U_LIB.S9S_MB_2U(SCH_1):PAGE280',
 PHYS_PAGE='294',
 XY='(-350,9000)',
 ROT='0',
 VER='1',
 PACK_TYPE='SMLF',
 LOCATION='PC1930',
 CDS_LIB='pure_quanta',
 CDS_PART_NAME='Q_CAPP_SMLF-330UF,2.5V,+10/-35B',
 TOLERANCE='+10/-35%',
 MATERIAL='SPCAP',
 VOLTAGE='2.5V',
 VALUE='330UF',
 PRIM_FILE='./archive_libs/logical/q_capp/chips/chips.prt';

PART_NAME
 PC1940 'Q_CAPP_SMLF-330UF,2V,35%,SPCAPA':;

SECTION_NUMBER 1
 '@S9S_MB_2U_LIB.S9S_MB_2U(SCH_1):PAGE283_I25@PURE_QUANTA.Q_CAPP(CHIPS)':
 C_PATH='@s9s_mb_2u_lib.s9s_mb_2u(sch_1):page283_i25@pure_quanta.q_capp(chips)',
 P_PATH='@s9s_mb_2u_lib.s9s_mb_2u(sch_1):page297_i25@pure_quanta.q_capp(chips)',
 PATH='I25',
 DRAWING='@S9S_MB_2U_LIB.S9S_MB_2U(SCH_1):PAGE283',
 PHYS_PAGE='297',
 XY='(-2975,2000)',
 ROT='0',
 VER='1',
 PACK_TYPE='SMLF',
 LOCATION='PC1940',
 CDS_LIB='pure_quanta',
 CDS_PART_NAME='Q_CAPP_SMLF-330UF,2V,35%,SPCAPA',
 TOLERANCE='35%',
 MATERIAL='SPCAP',
 VOLTAGE='2V',
 VALUE='330UF',
 PRIM_FILE='./archive_libs/logical/q_capp/chips/chips.prt';

PART_NAME
 PC1990 'Q_CAPP_SMLF-330UF,2.5V,+10/-35A':;

SECTION_NUMBER 1
 '@S9S_MB_2U_LIB.S9S_MB_2U(SCH_1):PAGE271_I61@PURE_QUANTA.Q_CAPP(CHIPS)':
 C_PATH='@s9s_mb_2u_lib.s9s_mb_2u(sch_1):page271_i61@pure_quanta.q_capp(chips)',
 P_PATH='@s9s_mb_2u_lib.s9s_mb_2u(sch_1):page285_i61@pure_quanta.q_capp(chips)',
 PATH='I61',
 DRAWING='@S9S_MB_2U_LIB.S9S_MB_2U(SCH_1):PAGE271',
 PHYS_PAGE='285',
 XY='(2600,-950)',
 ROT='0',
 VER='1',
 PACK_TYPE='SMLF',
 LOCATION='PC1990',
 CDS_LIB='pure_quanta',
 CDS_PART_NAME='Q_CAPP_SMLF-330UF,2.5V,+10/-35A',
 TOLERANCE='+10/-35%',
 MATERIAL='EMPTY',
 VOLTAGE='2.5V',
 VALUE='330UF',
 PRIM_FILE='./archive_libs/logical/q_capp/chips/chips.prt';

PART_NAME
 PC2000 'Q_CAP_0402-0.022UF,16V,10%,X7RA':;

SECTION_NUMBER 1
 '@S9S_MB_2U_LIB.S9S_MB_2U(SCH_1):PAGE248_I14@PURE_QUANTA.Q_CAP(CHIPS)':
 C_PATH='@s9s_mb_2u_lib.s9s_mb_2u(sch_1):page248_i14@pure_quanta.q_cap(chips)',
 P_PATH='@s9s_mb_2u_lib.s9s_mb_2u(sch_1):page262_i14@pure_quanta.q_cap(chips)',
 PATH='I14',
 DRAWING='@S9S_MB_2U_LIB.S9S_MB_2U(SCH_1):PAGE248',
 PHYS_PAGE='262',
 XY='(-275,-1275)',
 ROT='0',
 VER='1',
 PACK_TYPE='0402',
 LOCATION='PC2000',
 CDS_LIB='pure_quanta',
 CDS_PART_NAME='Q_CAP_0402-0.022UF,16V,10%,X7RA',
 TOLERANCE='10%',
 MATERIAL='X7R',
 VOLTAGE='16V',
 VALUE='0.022UF',
 PRIM_FILE='./archive_libs/logical/q_cap/chips/chips.prt';

PART_NAME
 PC2001 'Q_CAP_0402-0.022UF,16V,10%,X7RA':;

SECTION_NUMBER 1
 '@S9S_MB_2U_LIB.S9S_MB_2U(SCH_1):PAGE267_I23@PURE_QUANTA.Q_CAP(CHIPS)':
 C_PATH='@s9s_mb_2u_lib.s9s_mb_2u(sch_1):page267_i23@pure_quanta.q_cap(chips)',
 P_PATH='@s9s_mb_2u_lib.s9s_mb_2u(sch_1):page281_i23@pure_quanta.q_cap(chips)',
 PATH='I23',
 DRAWING='@S9S_MB_2U_LIB.S9S_MB_2U(SCH_1):PAGE267',
 PHYS_PAGE='281',
 XY='(-8000,2575)',
 ROT='0',
 VER='1',
 PACK_TYPE='0402',
 LOCATION='PC2001',
 CDS_LIB='pure_quanta',
 CDS_PART_NAME='Q_CAP_0402-0.022UF,16V,10%,X7RA',
 TOLERANCE='10%',
 MATERIAL='X7R',
 VOLTAGE='16V',
 VALUE='0.022UF',
 PRIM_FILE='./archive_libs/logical/q_cap/chips/chips.prt';

PART_NAME
 PC2002 'Q_CAP_0402-0.022UF,16V,10%,X7RA':;

SECTION_NUMBER 1
 '@S9S_MB_2U_LIB.S9S_MB_2U(SCH_1):PAGE285_I23@PURE_QUANTA.Q_CAP(CHIPS)':
 C_PATH='@s9s_mb_2u_lib.s9s_mb_2u(sch_1):page285_i23@pure_quanta.q_cap(chips)',
 P_PATH='@s9s_mb_2u_lib.s9s_mb_2u(sch_1):page299_i23@pure_quanta.q_cap(chips)',
 PATH='I23',
 DRAWING='@S9S_MB_2U_LIB.S9S_MB_2U(SCH_1):PAGE285',
 PHYS_PAGE='299',
 XY='(-7350,2125)',
 ROT='0',
 VER='1',
 PACK_TYPE='0402',
 LOCATION='PC2002',
 CDS_LIB='pure_quanta',
 CDS_PART_NAME='Q_CAP_0402-0.022UF,16V,10%,X7RA',
 TOLERANCE='10%',
 MATERIAL='X7R',
 VOLTAGE='16V',
 VALUE='0.022UF',
 PRIM_FILE='./archive_libs/logical/q_cap/chips/chips.prt';

PART_NAME
 PC2079 'Q_CAP_C0402-1UF,25V,10%,X6S,CHA':;

SECTION_NUMBER 1
 '@S9S_MB_2U_LIB.S9S_MB_2U(SCH_1):PAGE153_I44@PURE_QUANTA.Q_CAP(CHIPS)':
 C_PATH='@s9s_mb_2u_lib.s9s_mb_2u(sch_1):page153_i44@pure_quanta.q_cap(chips)',
 P_PATH='@s9s_mb_2u_lib.s9s_mb_2u(sch_1):page156_i44@pure_quanta.q_cap(chips)',
 PATH='I44',
 DRAWING='@S9S_MB_2U_LIB.S9S_MB_2U(SCH_1):PAGE153',
 PHYS_PAGE='156',
 XY='(5575,11425)',
 ROT='0',
 VER='1',
 PACK_TYPE='C0402',
 LOCATION='PC2079',
 CDS_LIB='pure_quanta',
 CDS_PART_NAME='Q_CAP_C0402-1UF,25V,10%,X6S,CHA',
 TOLERANCE='10%',
 MATERIAL='X6S',
 VOLTAGE='25V',
 VALUE='1UF',
 PRIM_FILE='./archive_libs/logical/q_cap/chips/chips.prt';

PART_NAME
 PC2080 'Q_CAP_C0805-22UF,16V,20%,X6S,CC':;

SECTION_NUMBER 1
 '@S9S_MB_2U_LIB.S9S_MB_2U(SCH_1):PAGE153_I94@PURE_QUANTA.Q_CAP(CHIPS)':
 C_PATH='@s9s_mb_2u_lib.s9s_mb_2u(sch_1):page153_i94@pure_quanta.q_cap(chips)',
 P_PATH='@s9s_mb_2u_lib.s9s_mb_2u(sch_1):page156_i94@pure_quanta.q_cap(chips)',
 PATH='I94',
 DRAWING='@S9S_MB_2U_LIB.S9S_MB_2U(SCH_1):PAGE153',
 PHYS_PAGE='156',
 XY='(9625,11650)',
 ROT='0',
 VER='1',
 PACK_TYPE='C0805',
 LOCATION='PC2080',
 CDS_LIB='pure_quanta',
 CDS_PART_NAME='Q_CAP_C0805-22UF,16V,20%,X6S,CC',
 TOLERANCE='20%',
 MATERIAL='X6S',
 VOLTAGE='16V',
 VALUE='22UF',
 PRIM_FILE='./archive_libs/logical/q_cap/chips/chips.prt';

PART_NAME
 PC2081 'Q_CAP_C0805-10UF,16V,10%,X6S,CB':;

SECTION_NUMBER 1
 '@S9S_MB_2U_LIB.S9S_MB_2U(SCH_1):PAGE153_I113@PURE_QUANTA.Q_CAP(CHIPS)':
 C_PATH='@s9s_mb_2u_lib.s9s_mb_2u(sch_1):page153_i113@pure_quanta.q_cap(chips)',
 P_PATH='@s9s_mb_2u_lib.s9s_mb_2u(sch_1):page156_i113@pure_quanta.q_cap(chips)',
 PATH='I113',
 DRAWING='@S9S_MB_2U_LIB.S9S_MB_2U(SCH_1):PAGE153',
 PHYS_PAGE='156',
 XY='(10025,13675)',
 ROT='0',
 VER='1',
 PACK_TYPE='C0805',
 LOCATION='PC2081',
 CDS_LIB='pure_quanta',
 CDS_PART_NAME='Q_CAP_C0805-10UF,16V,10%,X6S,CC',
 TOLERANCE='10%',
 MATERIAL='X6S',
 VOLTAGE='16V',
 VALUE='10UF',
 PRIM_FILE='./archive_libs/logical/q_cap/chips/chips.prt';

PART_NAME
 PC2082 'Q_CAP_C0805-10UF,16V,10%,X6S,CC':;

SECTION_NUMBER 1
 '@S9S_MB_2U_LIB.S9S_MB_2U(SCH_1):PAGE153_I96@PURE_QUANTA.Q_CAP(CHIPS)':
 C_PATH='@s9s_mb_2u_lib.s9s_mb_2u(sch_1):page153_i96@pure_quanta.q_cap(chips)',
 P_PATH='@s9s_mb_2u_lib.s9s_mb_2u(sch_1):page156_i96@pure_quanta.q_cap(chips)',
 PATH='I96',
 DRAWING='@S9S_MB_2U_LIB.S9S_MB_2U(SCH_1):PAGE153',
 PHYS_PAGE='156',
 XY='(10025,11650)',
 ROT='0',
 VER='1',
 PACK_TYPE='C0805',
 LOCATION='PC2082',
 CDS_LIB='pure_quanta',
 CDS_PART_NAME='Q_CAP_C0805-10UF,16V,10%,X6S,CB',
 TOLERANCE='10%',
 MATERIAL='X6S',
 VOLTAGE='16V',
 VALUE='10UF',
 PRIM_FILE='./archive_libs/logical/q_cap/chips/chips.prt';

PART_NAME
 PC2085 'Q_CAP_C0402-1UF,25V,10%,EMPTY,A':
 ROOM='NIC1_P12V_MAM_MAM_BOM1';

SECTION_NUMBER 1
 '@S9S_MB_2U_LIB.S9S_MB_2U(SCH_1):PAGE153_I55@PURE_QUANTA.Q_CAP(CHIPS)':
 C_PATH='@s9s_mb_2u_lib.s9s_mb_2u(sch_1):page153_i55@pure_quanta.q_cap(chips)',
 P_PATH='@s9s_mb_2u_lib.s9s_mb_2u(sch_1):page156_i55@pure_quanta.q_cap(chips)',
 PATH='I55',
 DRAWING='@S9S_MB_2U_LIB.S9S_MB_2U(SCH_1):PAGE153',
 ROOM1='NIC1_P12V_MAM_TIC_BOM2',
 PHYS_PAGE='156',
 XY='(6250,11000)',
 ROT='0',
 VER='1',
 PACK_TYPE='C0402',
 LOCATION='PC2085',
 CDS_LIB='pure_quanta',
 CDS_PART_NAME='Q_CAP_C0402-1UF,25V,10%,EMPTY,A',
 TOLERANCE='10%',
 MATERIAL='EMPTY',
 VOLTAGE='25V',
 ROOM='NIC1_P12V_MAM_MAM_BOM1',
 VALUE='1UF',
 PRIM_FILE='./archive_libs/logical/q_cap/chips/chips.prt';

PART_NAME
 PC2086 'Q_CAP_C0402-1UF,25V,10%,X6S,CHA':
 ROOM='NIC1_P3V3_BOM1';

SECTION_NUMBER 1
 '@S9S_MB_2U_LIB.S9S_MB_2U(SCH_1):PAGE153_I71@PURE_QUANTA.Q_CAP(CHIPS)':
 C_PATH='@s9s_mb_2u_lib.s9s_mb_2u(sch_1):page153_i71@pure_quanta.q_cap(chips)',
 P_PATH='@s9s_mb_2u_lib.s9s_mb_2u(sch_1):page156_i71@pure_quanta.q_cap(chips)',
 PATH='I71',
 DRAWING='@S9S_MB_2U_LIB.S9S_MB_2U(SCH_1):PAGE153',
 PHYS_PAGE='156',
 XY='(6475,13100)',
 ROT='0',
 VER='1',
 PACK_TYPE='C0402',
 LOCATION='PC2086',
 CDS_LIB='pure_quanta',
 CDS_PART_NAME='Q_CAP_C0402-1UF,25V,10%,X6S,CHA',
 TOLERANCE='10%',
 MATERIAL='X6S',
 VOLTAGE='25V',
 ROOM='NIC1_P3V3_BOM1',
 VALUE='1UF',
 PRIM_FILE='./archive_libs/logical/q_cap/chips/chips.prt';

PART_NAME
 PC2087 'Q_CAP_C0402-1UF,25V,10%,EMPTY,A':
 ROOM='NIC1_P12V_MAM_MAM_BOM1';

SECTION_NUMBER 1
 '@S9S_MB_2U_LIB.S9S_MB_2U(SCH_1):PAGE153_I54@PURE_QUANTA.Q_CAP(CHIPS)':
 C_PATH='@s9s_mb_2u_lib.s9s_mb_2u(sch_1):page153_i54@pure_quanta.q_cap(chips)',
 P_PATH='@s9s_mb_2u_lib.s9s_mb_2u(sch_1):page156_i54@pure_quanta.q_cap(chips)',
 PATH='I54',
 DRAWING='@S9S_MB_2U_LIB.S9S_MB_2U(SCH_1):PAGE153',
 ROOM1='NIC1_P12V_MAM_TIC_BOM2',
 PHYS_PAGE='156',
 XY='(6475,10700)',
 ROT='1',
 VER='1',
 PACK_TYPE='C0402',
 LOCATION='PC2087',
 CDS_LIB='pure_quanta',
 CDS_PART_NAME='Q_CAP_C0402-1UF,25V,10%,EMPTY,A',
 TOLERANCE='10%',
 MATERIAL='EMPTY',
 VOLTAGE='25V',
 ROOM='NIC1_P12V_MAM_MAM_BOM1',
 VALUE='1UF',
 PRIM_FILE='./archive_libs/logical/q_cap/chips/chips.prt';

PART_NAME
 PC2088 'Q_CAP_C0402-0.01UF,50V,10%,EMPA':;

SECTION_NUMBER 1
 '@S9S_MB_2U_LIB.S9S_MB_2U(SCH_1):PAGE153_I81@PURE_QUANTA.Q_CAP(CHIPS)':
 C_PATH='@s9s_mb_2u_lib.s9s_mb_2u(sch_1):page153_i81@pure_quanta.q_cap(chips)',
 P_PATH='@s9s_mb_2u_lib.s9s_mb_2u(sch_1):page156_i81@pure_quanta.q_cap(chips)',
 PATH='I81',
 DRAWING='@S9S_MB_2U_LIB.S9S_MB_2U(SCH_1):PAGE153',
 PHYS_PAGE='156',
 XY='(8300,11025)',
 ROT='0',
 VER='1',
 PACK_TYPE='C0402',
 LOCATION='PC2088',
 CDS_LIB='pure_quanta',
 CDS_PART_NAME='Q_CAP_C0402-0.01UF,50V,10%,EMPA',
 TOLERANCE='10%',
 MATERIAL='EMPTY',
 VOLTAGE='50V',
 VALUE='0.01UF',
 PRIM_FILE='./archive_libs/logical/q_cap/chips/chips.prt';

PART_NAME
 PC2089 'Q_CAP_C0402-6800PF,50V,10%,X7RA':
 ROOM='NIC1_P3V3_BOM1';

SECTION_NUMBER 1
 '@S9S_MB_2U_LIB.S9S_MB_2U(SCH_1):PAGE153_I107@PURE_QUANTA.Q_CAP(CHIPS)':
 C_PATH='@s9s_mb_2u_lib.s9s_mb_2u(sch_1):page153_i107@pure_quanta.q_cap(chips)',
 P_PATH='@s9s_mb_2u_lib.s9s_mb_2u(sch_1):page156_i107@pure_quanta.q_cap(chips)',
 PATH='I107',
 DRAWING='@S9S_MB_2U_LIB.S9S_MB_2U(SCH_1):PAGE153',
 PHYS_PAGE='156',
 XY='(9175,12900)',
 ROT='1',
 VER='1',
 PACK_TYPE='C0402',
 LOCATION='PC2089',
 CDS_LIB='pure_quanta',
 CDS_PART_NAME='Q_CAP_C0402-6800PF,50V,10%,X7RA',
 TOLERANCE='10%',
 MATERIAL='X7R',
 VOLTAGE='50V',
 ROOM='NIC1_P3V3_BOM1',
 VALUE='6800PF',
 PRIM_FILE='./archive_libs/logical/q_cap/chips/chips.prt';

PART_NAME
 PC2091 'Q_CAP_0402-0.1UF,25V,10%,X7R,CA':;

SECTION_NUMBER 1
 '@S9S_MB_2U_LIB.S9S_MB_2U(SCH_1):PAGE153_I111@PURE_QUANTA.Q_CAP(CHIPS)':
 C_PATH='@s9s_mb_2u_lib.s9s_mb_2u(sch_1):page153_i111@pure_quanta.q_cap(chips)',
 P_PATH='@s9s_mb_2u_lib.s9s_mb_2u(sch_1):page156_i111@pure_quanta.q_cap(chips)',
 PATH='I111',
 DRAWING='@S9S_MB_2U_LIB.S9S_MB_2U(SCH_1):PAGE153',
 PHYS_PAGE='156',
 XY='(9450,13675)',
 ROT='0',
 VER='1',
 PACK_TYPE='0402',
 LOCATION='PC2091',
 CDS_LIB='pure_quanta',
 CDS_PART_NAME='Q_CAP_0402-0.1UF,25V,10%,X7R,CA',
 TOLERANCE='10%',
 MATERIAL='X7R',
 VOLTAGE='25V',
 VALUE='0.1UF',
 PRIM_FILE='./archive_libs/logical/q_cap/chips/chips.prt';

PART_NAME
 PC2092 'Q_CAP_0402-0.1UF,25V,10%,X7R,CA':;

SECTION_NUMBER 1
 '@S9S_MB_2U_LIB.S9S_MB_2U(SCH_1):PAGE153_I93@PURE_QUANTA.Q_CAP(CHIPS)':
 C_PATH='@s9s_mb_2u_lib.s9s_mb_2u(sch_1):page153_i93@pure_quanta.q_cap(chips)',
 P_PATH='@s9s_mb_2u_lib.s9s_mb_2u(sch_1):page156_i93@pure_quanta.q_cap(chips)',
 PATH='I93',
 DRAWING='@S9S_MB_2U_LIB.S9S_MB_2U(SCH_1):PAGE153',
 PHYS_PAGE='156',
 XY='(9200,11650)',
 ROT='0',
 VER='1',
 PACK_TYPE='0402',
 LOCATION='PC2092',
 CDS_LIB='pure_quanta',
 CDS_PART_NAME='Q_CAP_0402-0.1UF,25V,10%,X7R,CA',
 TOLERANCE='10%',
 MATERIAL='X7R',
 VOLTAGE='25V',
 VALUE='0.1UF',
 PRIM_FILE='./archive_libs/logical/q_cap/chips/chips.prt';

PART_NAME
 PC2093 'Q_CAP_C0402-1UF,25V,10%,X6S,CHA':
 ROOM='NIC1_P3V3_BOM1';

SECTION_NUMBER 1
 '@S9S_MB_2U_LIB.S9S_MB_2U(SCH_1):PAGE153_I72@PURE_QUANTA.Q_CAP(CHIPS)':
 C_PATH='@s9s_mb_2u_lib.s9s_mb_2u(sch_1):page153_i72@pure_quanta.q_cap(chips)',
 P_PATH='@s9s_mb_2u_lib.s9s_mb_2u(sch_1):page156_i72@pure_quanta.q_cap(chips)',
 PATH='I72',
 DRAWING='@S9S_MB_2U_LIB.S9S_MB_2U(SCH_1):PAGE153',
 PHYS_PAGE='156',
 XY='(6700,12800)',
 ROT='1',
 VER='1',
 PACK_TYPE='C0402',
 LOCATION='PC2093',
 CDS_LIB='pure_quanta',
 CDS_PART_NAME='Q_CAP_C0402-1UF,25V,10%,X6S,CHA',
 TOLERANCE='10%',
 MATERIAL='X6S',
 VOLTAGE='25V',
 ROOM='NIC1_P3V3_BOM1',
 VALUE='1UF',
 PRIM_FILE='./archive_libs/logical/q_cap/chips/chips.prt';

PART_NAME
 PC2098 'Q_CAP_C0402-1UF,25V,10%,EMPTY,A':
 ROOM='NIC1_P12V_MAM_MAM_BOM1';

SECTION_NUMBER 1
 '@S9S_MB_2U_LIB.S9S_MB_2U(SCH_1):PAGE131_I61@PURE_QUANTA.Q_CAP(CHIPS)':
 C_PATH='@s9s_mb_2u_lib.s9s_mb_2u(sch_1):page131_i61@pure_quanta.q_cap(chips)',
 P_PATH='@s9s_mb_2u_lib.s9s_mb_2u(sch_1):page162_i61@pure_quanta.q_cap(chips)',
 PATH='I61',
 DRAWING='@S9S_MB_2U_LIB.S9S_MB_2U(SCH_1):PAGE131',
 ROOM1='NIC1_P12V_MAM_TIC_BOM2',
 PHYS_PAGE='162',
 XY='(150,-225)',
 ROT='0',
 VER='1',
 PACK_TYPE='C0402',
 LOCATION='PC2098',
 CDS_LIB='pure_quanta',
 CDS_PART_NAME='Q_CAP_C0402-1UF,25V,10%,EMPTY,A',
 TOLERANCE='10%',
 MATERIAL='EMPTY',
 VOLTAGE='25V',
 ROOM='NIC1_P12V_MAM_MAM_BOM1',
 VALUE='1UF',
 PRIM_FILE='./archive_libs/logical/q_cap/chips/chips.prt';

PART_NAME
 PC2103 'Q_CAP_C0402-1UF,25V,10%,X6S,CHA':
 ROOM='HSC1_BOM1';

SECTION_NUMBER 1
 '@S9S_MB_2U_LIB.S9S_MB_2U(SCH_1):PAGE303_I35@PURE_QUANTA.Q_CAP(CHIPS)':
 C_PATH='@s9s_mb_2u_lib.s9s_mb_2u(sch_1):page303_i35@pure_quanta.q_cap(chips)',
 P_PATH='@s9s_mb_2u_lib.s9s_mb_2u(sch_1):page301_i35@pure_quanta.q_cap(chips)',
 PATH='I35',
 DRAWING='@S9S_MB_2U_LIB.S9S_MB_2U(SCH_1):PAGE303',
 PHYS_PAGE='301',
 XY='(-15050,2875)',
 ROT='0',
 VER='1',
 PACK_TYPE='C0402',
 CDS_LIB='pure_quanta',
 CDS_PART_NAME='Q_CAP_C0402-1UF,25V,10%,X6S,CHA',
 TOLERANCE='10%',
 MATERIAL='X6S',
 VOLTAGE='25V',
 ROOM='HSC1_BOM1',
 VALUE='1UF',
 PRIM_FILE='./archive_libs/logical/q_cap/chips/chips.prt';

PART_NAME
 PC2137 'Q_CAP_0402-0.1UF,25V,10%,X7R,CA':;

SECTION_NUMBER 1
 '@S9S_MB_2U_LIB.S9S_MB_2U(SCH_1):PAGE131_I109@PURE_QUANTA.Q_CAP(CHIPS)':
 C_PATH='@s9s_mb_2u_lib.s9s_mb_2u(sch_1):page131_i109@pure_quanta.q_cap(chips)',
 P_PATH='@s9s_mb_2u_lib.s9s_mb_2u(sch_1):page162_i109@pure_quanta.q_cap(chips)',
 PATH='I109',
 DRAWING='@S9S_MB_2U_LIB.S9S_MB_2U(SCH_1):PAGE131',
 PHYS_PAGE='162',
 XY='(3275,2725)',
 ROT='0',
 VER='1',
 PACK_TYPE='0402',
 LOCATION='PC2137',
 CDS_LIB='pure_quanta',
 CDS_PART_NAME='Q_CAP_0402-0.1UF,25V,10%,X7R,CA',
 TOLERANCE='10%',
 MATERIAL='X7R',
 VOLTAGE='25V',
 VALUE='0.1UF',
 PRIM_FILE='./archive_libs/logical/q_cap/chips/chips.prt';

PART_NAME
 PC2139 'Q_CAP_C0402-1UF,25V,10%,X6S,CHA':;

SECTION_NUMBER 1
 '@S9S_MB_2U_LIB.S9S_MB_2U(SCH_1):PAGE131_I46@PURE_QUANTA.Q_CAP(CHIPS)':
 C_PATH='@s9s_mb_2u_lib.s9s_mb_2u(sch_1):page131_i46@pure_quanta.q_cap(chips)',
 P_PATH='@s9s_mb_2u_lib.s9s_mb_2u(sch_1):page162_i46@pure_quanta.q_cap(chips)',
 PATH='I46',
 DRAWING='@S9S_MB_2U_LIB.S9S_MB_2U(SCH_1):PAGE131',
 PHYS_PAGE='162',
 XY='(-525,200)',
 ROT='0',
 VER='1',
 PACK_TYPE='C0402',
 LOCATION='PC2139',
 CDS_LIB='pure_quanta',
 CDS_PART_NAME='Q_CAP_C0402-1UF,25V,10%,X6S,CHA',
 TOLERANCE='10%',
 MATERIAL='X6S',
 VOLTAGE='25V',
 VALUE='1UF',
 PRIM_FILE='./archive_libs/logical/q_cap/chips/chips.prt';

PART_NAME
 PC2140 'Q_CAP_C0402-1UF,25V,10%,X6S,CHA':;

SECTION_NUMBER 1
 '@S9S_MB_2U_LIB.S9S_MB_2U(SCH_1):PAGE131_I52@PURE_QUANTA.Q_CAP(CHIPS)':
 C_PATH='@s9s_mb_2u_lib.s9s_mb_2u(sch_1):page131_i52@pure_quanta.q_cap(chips)',
 P_PATH='@s9s_mb_2u_lib.s9s_mb_2u(sch_1):page162_i52@pure_quanta.q_cap(chips)',
 PATH='I52',
 DRAWING='@S9S_MB_2U_LIB.S9S_MB_2U(SCH_1):PAGE131',
 PHYS_PAGE='162',
 XY='(-400,2525)',
 ROT='0',
 VER='1',
 PACK_TYPE='C0402',
 LOCATION='PC2140',
 CDS_LIB='pure_quanta',
 CDS_PART_NAME='Q_CAP_C0402-1UF,25V,10%,X6S,CHA',
 TOLERANCE='10%',
 MATERIAL='X6S',
 VOLTAGE='25V',
 VALUE='1UF',
 PRIM_FILE='./archive_libs/logical/q_cap/chips/chips.prt';

PART_NAME
 PC2141 'Q_CAP_C0805-22UF,16V,20%,X6S,CC':;

SECTION_NUMBER 1
 '@S9S_MB_2U_LIB.S9S_MB_2U(SCH_1):PAGE131_I100@PURE_QUANTA.Q_CAP(CHIPS)':
 C_PATH='@s9s_mb_2u_lib.s9s_mb_2u(sch_1):page131_i100@pure_quanta.q_cap(chips)',
 P_PATH='@s9s_mb_2u_lib.s9s_mb_2u(sch_1):page162_i100@pure_quanta.q_cap(chips)',
 PATH='I100',
 DRAWING='@S9S_MB_2U_LIB.S9S_MB_2U(SCH_1):PAGE131',
 PHYS_PAGE='162',
 XY='(3550,400)',
 ROT='0',
 VER='1',
 PACK_TYPE='C0805',
 LOCATION='PC2141',
 CDS_LIB='pure_quanta',
 CDS_PART_NAME='Q_CAP_C0805-22UF,16V,20%,X6S,CC',
 TOLERANCE='20%',
 MATERIAL='X6S',
 VOLTAGE='16V',
 VALUE='22UF',
 PRIM_FILE='./archive_libs/logical/q_cap/chips/chips.prt';

PART_NAME
 PC2142 'Q_CAP_C0805-10UF,16V,10%,X6S,CB':;

SECTION_NUMBER 1
 '@S9S_MB_2U_LIB.S9S_MB_2U(SCH_1):PAGE131_I113@PURE_QUANTA.Q_CAP(CHIPS)':
 C_PATH='@s9s_mb_2u_lib.s9s_mb_2u(sch_1):page131_i113@pure_quanta.q_cap(chips)',
 P_PATH='@s9s_mb_2u_lib.s9s_mb_2u(sch_1):page162_i113@pure_quanta.q_cap(chips)',
 PATH='I113',
 DRAWING='@S9S_MB_2U_LIB.S9S_MB_2U(SCH_1):PAGE131',
 PHYS_PAGE='162',
 XY='(3850,2725)',
 ROT='0',
 VER='1',
 PACK_TYPE='C0805',
 LOCATION='PC2142',
 CDS_LIB='pure_quanta',
 CDS_PART_NAME='Q_CAP_C0805-10UF,16V,10%,X6S,CC',
 TOLERANCE='10%',
 MATERIAL='X6S',
 VOLTAGE='16V',
 VALUE='10UF',
 PRIM_FILE='./archive_libs/logical/q_cap/chips/chips.prt';

PART_NAME
 PC2143 'Q_CAP_C0805-10UF,16V,10%,X6S,CC':;

SECTION_NUMBER 1
 '@S9S_MB_2U_LIB.S9S_MB_2U(SCH_1):PAGE131_I102@PURE_QUANTA.Q_CAP(CHIPS)':
 C_PATH='@s9s_mb_2u_lib.s9s_mb_2u(sch_1):page131_i102@pure_quanta.q_cap(chips)',
 P_PATH='@s9s_mb_2u_lib.s9s_mb_2u(sch_1):page162_i102@pure_quanta.q_cap(chips)',
 PATH='I102',
 DRAWING='@S9S_MB_2U_LIB.S9S_MB_2U(SCH_1):PAGE131',
 PHYS_PAGE='162',
 XY='(3950,400)',
 ROT='0',
 VER='1',
 PACK_TYPE='C0805',
 LOCATION='PC2143',
 CDS_LIB='pure_quanta',
 CDS_PART_NAME='Q_CAP_C0805-10UF,16V,10%,X6S,CB',
 TOLERANCE='10%',
 MATERIAL='X6S',
 VOLTAGE='16V',
 VALUE='10UF',
 PRIM_FILE='./archive_libs/logical/q_cap/chips/chips.prt';

PART_NAME
 PC2144 'Q_CAP_C0402-0.01UF,50V,10%,EMPA':;

SECTION_NUMBER 1
 '@S9S_MB_2U_LIB.S9S_MB_2U(SCH_1):PAGE153_I101@PURE_QUANTA.Q_CAP(CHIPS)':
 C_PATH='@s9s_mb_2u_lib.s9s_mb_2u(sch_1):page153_i101@pure_quanta.q_cap(chips)',
 P_PATH='@s9s_mb_2u_lib.s9s_mb_2u(sch_1):page156_i101@pure_quanta.q_cap(chips)',
 PATH='I101',
 DRAWING='@S9S_MB_2U_LIB.S9S_MB_2U(SCH_1):PAGE153',
 PHYS_PAGE='156',
 XY='(8575,13125)',
 ROT='0',
 VER='1',
 PACK_TYPE='C0402',
 LOCATION='PC2144',
 CDS_LIB='pure_quanta',
 CDS_PART_NAME='Q_CAP_C0402-0.01UF,50V,10%,EMPA',
 TOLERANCE='10%',
 MATERIAL='EMPTY',
 VOLTAGE='50V',
 VALUE='0.01UF',
 PRIM_FILE='./archive_libs/logical/q_cap/chips/chips.prt';

PART_NAME
 PC2146 'Q_CAP_C0402-1UF,25V,10%,EMPTY,A':
 ROOM='NIC1_P12V_MAM_MAM_BOM1';

SECTION_NUMBER 1
 '@S9S_MB_2U_LIB.S9S_MB_2U(SCH_1):PAGE131_I62@PURE_QUANTA.Q_CAP(CHIPS)':
 C_PATH='@s9s_mb_2u_lib.s9s_mb_2u(sch_1):page131_i62@pure_quanta.q_cap(chips)',
 P_PATH='@s9s_mb_2u_lib.s9s_mb_2u(sch_1):page162_i62@pure_quanta.q_cap(chips)',
 PATH='I62',
 DRAWING='@S9S_MB_2U_LIB.S9S_MB_2U(SCH_1):PAGE131',
 ROOM1='NIC1_P12V_MAM_TIC_BOM2',
 PHYS_PAGE='162',
 XY='(375,-525)',
 ROT='1',
 VER='1',
 PACK_TYPE='C0402',
 LOCATION='PC2146',
 CDS_LIB='pure_quanta',
 CDS_PART_NAME='Q_CAP_C0402-1UF,25V,10%,EMPTY,A',
 TOLERANCE='10%',
 MATERIAL='EMPTY',
 VOLTAGE='25V',
 ROOM='NIC1_P12V_MAM_MAM_BOM1',
 VALUE='1UF',
 PRIM_FILE='./archive_libs/logical/q_cap/chips/chips.prt';

PART_NAME
 PC2147 'Q_CAP_C0402-1UF,25V,10%,X6S,CHA':
 ROOM='NIC1_P3V3_BOM1';

SECTION_NUMBER 1
 '@S9S_MB_2U_LIB.S9S_MB_2U(SCH_1):PAGE131_I87@PURE_QUANTA.Q_CAP(CHIPS)':
 C_PATH='@s9s_mb_2u_lib.s9s_mb_2u(sch_1):page131_i87@pure_quanta.q_cap(chips)',
 P_PATH='@s9s_mb_2u_lib.s9s_mb_2u(sch_1):page162_i87@pure_quanta.q_cap(chips)',
 PATH='I87',
 DRAWING='@S9S_MB_2U_LIB.S9S_MB_2U(SCH_1):PAGE131',
 PHYS_PAGE='162',
 XY='(500,1800)',
 ROT='1',
 VER='1',
 PACK_TYPE='C0402',
 LOCATION='PC2147',
 CDS_LIB='pure_quanta',
 CDS_PART_NAME='Q_CAP_C0402-1UF,25V,10%,X6S,CHA',
 TOLERANCE='10%',
 MATERIAL='X6S',
 VOLTAGE='25V',
 ROOM='NIC1_P3V3_BOM1',
 VALUE='1UF',
 PRIM_FILE='./archive_libs/logical/q_cap/chips/chips.prt';

PART_NAME
 PC2149 'Q_CAP_C0402-0.01UF,50V,10%,EMPA':;

SECTION_NUMBER 1
 '@S9S_MB_2U_LIB.S9S_MB_2U(SCH_1):PAGE131_I105@PURE_QUANTA.Q_CAP(CHIPS)':
 C_PATH='@s9s_mb_2u_lib.s9s_mb_2u(sch_1):page131_i105@pure_quanta.q_cap(chips)',
 P_PATH='@s9s_mb_2u_lib.s9s_mb_2u(sch_1):page162_i105@pure_quanta.q_cap(chips)',
 PATH='I105',
 DRAWING='@S9S_MB_2U_LIB.S9S_MB_2U(SCH_1):PAGE131',
 PHYS_PAGE='162',
 XY='(2375,2125)',
 ROT='0',
 VER='1',
 PACK_TYPE='C0402',
 LOCATION='PC2149',
 CDS_LIB='pure_quanta',
 CDS_PART_NAME='Q_CAP_C0402-0.01UF,50V,10%,EMPA',
 TOLERANCE='10%',
 MATERIAL='EMPTY',
 VOLTAGE='50V',
 VALUE='0.01UF',
 PRIM_FILE='./archive_libs/logical/q_cap/chips/chips.prt';

PART_NAME
 PC2150 'Q_CAP_C0402-3900PF,50V,10%,EMPA':
 ROOM='NIC1_P12V_MAM_MAM_BOM1';

SECTION_NUMBER 1
 '@S9S_MB_2U_LIB.S9S_MB_2U(SCH_1):PAGE131_I76@PURE_QUANTA.Q_CAP(CHIPS)':
 C_PATH='@s9s_mb_2u_lib.s9s_mb_2u(sch_1):page131_i76@pure_quanta.q_cap(chips)',
 P_PATH='@s9s_mb_2u_lib.s9s_mb_2u(sch_1):page162_i76@pure_quanta.q_cap(chips)',
 PATH='I76',
 DRAWING='@S9S_MB_2U_LIB.S9S_MB_2U(SCH_1):PAGE131',
 ROOM1='NIC1_P12V_MAM_TIC_BOM2',
 PHYS_PAGE='162',
 XY='(2825,-425)',
 ROT='1',
 VER='1',
 PACK_TYPE='C0402',
 LOCATION='PC2150',
 CDS_LIB='pure_quanta',
 CDS_PART_NAME='Q_CAP_C0402-3900PF,50V,10%,EMPA',
 TOLERANCE='10%',
 MATERIAL='EMPTY',
 VOLTAGE='50V',
 ROOM='NIC1_P12V_MAM_MAM_BOM1',
 VALUE='3900PF',
 PRIM_FILE='./archive_libs/logical/q_cap/chips/chips.prt';

PART_NAME
 PC2151 'Q_CAP_C0402-6800PF,50V,10%,X7RA':
 ROOM='NIC1_P3V3_BOM1';

SECTION_NUMBER 1
 '@S9S_MB_2U_LIB.S9S_MB_2U(SCH_1):PAGE131_I96@PURE_QUANTA.Q_CAP(CHIPS)':
 C_PATH='@s9s_mb_2u_lib.s9s_mb_2u(sch_1):page131_i96@pure_quanta.q_cap(chips)',
 P_PATH='@s9s_mb_2u_lib.s9s_mb_2u(sch_1):page162_i96@pure_quanta.q_cap(chips)',
 PATH='I96',
 DRAWING='@S9S_MB_2U_LIB.S9S_MB_2U(SCH_1):PAGE131',
 PHYS_PAGE='162',
 XY='(2975,1900)',
 ROT='1',
 VER='1',
 PACK_TYPE='C0402',
 LOCATION='PC2151',
 CDS_LIB='pure_quanta',
 CDS_PART_NAME='Q_CAP_C0402-6800PF,50V,10%,X7RA',
 TOLERANCE='10%',
 MATERIAL='X7R',
 VOLTAGE='50V',
 ROOM='NIC1_P3V3_BOM1',
 VALUE='6800PF',
 PRIM_FILE='./archive_libs/logical/q_cap/chips/chips.prt';

PART_NAME
 PC2152 'Q_CAP_0402-0.1UF,25V,10%,X7R,CA':;

SECTION_NUMBER 1
 '@S9S_MB_2U_LIB.S9S_MB_2U(SCH_1):PAGE131_I98@PURE_QUANTA.Q_CAP(CHIPS)':
 C_PATH='@s9s_mb_2u_lib.s9s_mb_2u(sch_1):page131_i98@pure_quanta.q_cap(chips)',
 P_PATH='@s9s_mb_2u_lib.s9s_mb_2u(sch_1):page162_i98@pure_quanta.q_cap(chips)',
 PATH='I98',
 DRAWING='@S9S_MB_2U_LIB.S9S_MB_2U(SCH_1):PAGE131',
 PHYS_PAGE='162',
 XY='(3125,400)',
 ROT='0',
 VER='1',
 PACK_TYPE='0402',
 LOCATION='PC2152',
 CDS_LIB='pure_quanta',
 CDS_PART_NAME='Q_CAP_0402-0.1UF,25V,10%,X7R,CA',
 TOLERANCE='10%',
 MATERIAL='X7R',
 VOLTAGE='25V',
 VALUE='0.1UF',
 PRIM_FILE='./archive_libs/logical/q_cap/chips/chips.prt';

PART_NAME
 PC2153 'Q_CAP_0402-0.22UF,16V,10%,X7R,A':
 ROOM='NIC1_P12V_MPS_MAM_BOM3';

SECTION_NUMBER 1
 '@S9S_MB_2U_LIB.S9S_MB_2U(SCH_1):PAGE236_I60@PURE_QUANTA.Q_CAP(CHIPS)':
 C_PATH='@s9s_mb_2u_lib.s9s_mb_2u(sch_1):page236_i60@pure_quanta.q_cap(chips)',
 P_PATH='@s9s_mb_2u_lib.s9s_mb_2u(sch_1):page157_i60@pure_quanta.q_cap(chips)',
 PATH='I60',
 DRAWING='@S9S_MB_2U_LIB.S9S_MB_2U(SCH_1):PAGE236',
 ROOM1='NIC1_P12V_MPS_TIC_BOM4',
 PHYS_PAGE='157',
 XY='(-8050,9200)',
 ROT='0',
 VER='1',
 PACK_TYPE='0402',
 LOCATION='PC2153',
 CDS_LIB='pure_quanta',
 CDS_PART_NAME='Q_CAP_0402-0.22UF,16V,10%,X7R,A',
 TOLERANCE='10%',
 MATERIAL='X7R',
 VOLTAGE='16V',
 ROOM='NIC1_P12V_MPS_MAM_BOM3',
 VALUE='0.22UF',
 PRIM_FILE='./archive_libs/logical/q_cap/chips/chips.prt';

PART_NAME
 PC2154 'Q_CAP_C0402-1UF,25V,10%,X6S,CHA':
 ROOM='NIC1_P12V_MPS_MAM_BOM3';

SECTION_NUMBER 1
 '@S9S_MB_2U_LIB.S9S_MB_2U(SCH_1):PAGE236_I68@PURE_QUANTA.Q_CAP(CHIPS)':
 C_PATH='@s9s_mb_2u_lib.s9s_mb_2u(sch_1):page236_i68@pure_quanta.q_cap(chips)',
 P_PATH='@s9s_mb_2u_lib.s9s_mb_2u(sch_1):page157_i68@pure_quanta.q_cap(chips)',
 PATH='I68',
 DRAWING='@S9S_MB_2U_LIB.S9S_MB_2U(SCH_1):PAGE236',
 ROOM1='NIC1_P12V_MPS_TIC_BOM4',
 PHYS_PAGE='157',
 XY='(-7300,10050)',
 ROT='0',
 VER='1',
 PACK_TYPE='C0402',
 LOCATION='PC2154',
 CDS_LIB='pure_quanta',
 CDS_PART_NAME='Q_CAP_C0402-1UF,25V,10%,X6S,CHA',
 TOLERANCE='10%',
 MATERIAL='X6S',
 VOLTAGE='25V',
 ROOM='NIC1_P12V_MPS_MAM_BOM3',
 VALUE='1UF',
 PRIM_FILE='./archive_libs/logical/q_cap/chips/chips.prt';

PART_NAME
 PC2155 'Q_CAP_C0402-0.047UF,25V,10%,X7A':
 ROOM='NIC1_P12V_MPS_MAM_BOM3';

SECTION_NUMBER 1
 '@S9S_MB_2U_LIB.S9S_MB_2U(SCH_1):PAGE236_I63@PURE_QUANTA.Q_CAP(CHIPS)':
 C_PATH='@s9s_mb_2u_lib.s9s_mb_2u(sch_1):page236_i63@pure_quanta.q_cap(chips)',
 P_PATH='@s9s_mb_2u_lib.s9s_mb_2u(sch_1):page157_i63@pure_quanta.q_cap(chips)',
 PATH='I63',
 DRAWING='@S9S_MB_2U_LIB.S9S_MB_2U(SCH_1):PAGE236',
 ROOM1='NIC1_P12V_MPS_TIC_BOM4',
 PHYS_PAGE='157',
 XY='(-7225,8975)',
 ROT='0',
 VER='1',
 PACK_TYPE='C0402',
 LOCATION='PC2155',
 CDS_LIB='pure_quanta',
 CDS_PART_NAME='Q_CAP_C0402-0.047UF,25V,10%,X7A',
 TOLERANCE='10%',
 MATERIAL='X7R',
 VOLTAGE='25V',
 ROOM='NIC1_P12V_MPS_MAM_BOM3',
 VALUE='0.047UF',
 PRIM_FILE='./archive_libs/logical/q_cap/chips/chips.prt';

PART_NAME
 PC2156 'Q_CAP_C0402-100NF,50V,10%,X7R,A':
 ROOM='NIC1_P12V_MPS_MAM_BOM3';

SECTION_NUMBER 1
 '@S9S_MB_2U_LIB.S9S_MB_2U(SCH_1):PAGE236_I74@PURE_QUANTA.Q_CAP(CHIPS)':
 C_PATH='@s9s_mb_2u_lib.s9s_mb_2u(sch_1):page236_i74@pure_quanta.q_cap(chips)',
 P_PATH='@s9s_mb_2u_lib.s9s_mb_2u(sch_1):page157_i74@pure_quanta.q_cap(chips)',
 PATH='I74',
 DRAWING='@S9S_MB_2U_LIB.S9S_MB_2U(SCH_1):PAGE236',
 ROOM1='NIC1_P12V_MPS_TIC_BOM4',
 PHYS_PAGE='157',
 XY='(-5350,8775)',
 ROT='0',
 VER='1',
 PACK_TYPE='C0402',
 LOCATION='PC2156',
 CDS_LIB='pure_quanta',
 CDS_PART_NAME='Q_CAP_C0402-100NF,50V,10%,X7R,A',
 TOLERANCE='10%',
 MATERIAL='X7R',
 VOLTAGE='50V',
 ROOM='NIC1_P12V_MPS_MAM_BOM3',
 VALUE='100NF',
 PRIM_FILE='./archive_libs/logical/q_cap/chips/chips.prt';

PART_NAME
 PC2157 'Q_CAP_C0402-39PF,50V,5%,EMPTY,A':
 ROOM='NIC1_P3V3_BOM2';

SECTION_NUMBER 1
 '@S9S_MB_2U_LIB.S9S_MB_2U(SCH_1):PAGE236_I42@PURE_QUANTA.Q_CAP(CHIPS)':
 C_PATH='@s9s_mb_2u_lib.s9s_mb_2u(sch_1):page236_i42@pure_quanta.q_cap(chips)',
 P_PATH='@s9s_mb_2u_lib.s9s_mb_2u(sch_1):page157_i42@pure_quanta.q_cap(chips)',
 PATH='I42',
 DRAWING='@S9S_MB_2U_LIB.S9S_MB_2U(SCH_1):PAGE236',
 PHYS_PAGE='157',
 XY='(-4275,12300)',
 ROT='0',
 VER='1',
 PACK_TYPE='C0402',
 LOCATION='PC2157',
 CDS_LIB='pure_quanta',
 CDS_PART_NAME='Q_CAP_C0402-39PF,50V,5%,EMPTY,A',
 TOLERANCE='5%',
 MATERIAL='EMPTY',
 VOLTAGE='50V',
 ROOM='NIC1_P3V3_BOM2',
 VALUE='39PF',
 PRIM_FILE='./archive_libs/logical/q_cap/chips/chips.prt';

PART_NAME
 PC2158 'Q_CAP_C0603-2.2UF,16V,20%,X7R,A':
 ROOM='NIC1_P12V_MPS_MAM_BOM3';

SECTION_NUMBER 1
 '@S9S_MB_2U_LIB.S9S_MB_2U(SCH_1):PAGE236_I88@PURE_QUANTA.Q_CAP(CHIPS)':
 C_PATH='@s9s_mb_2u_lib.s9s_mb_2u(sch_1):page236_i88@pure_quanta.q_cap(chips)',
 P_PATH='@s9s_mb_2u_lib.s9s_mb_2u(sch_1):page157_i88@pure_quanta.q_cap(chips)',
 PATH='I88',
 DRAWING='@S9S_MB_2U_LIB.S9S_MB_2U(SCH_1):PAGE236',
 ROOM1='NIC1_P12V_MPS_TIC_BOM4',
 PHYS_PAGE='157',
 XY='(-3900,9125)',
 ROT='0',
 VER='1',
 PACK_TYPE='C0603',
 LOCATION='PC2158',
 CDS_LIB='pure_quanta',
 CDS_PART_NAME='Q_CAP_C0603-2.2UF,16V,20%,X7R,A',
 TOLERANCE='20%',
 MATERIAL='X7R',
 VOLTAGE='16V',
 ROOM='NIC1_P12V_MPS_MAM_BOM3',
 VALUE='2.2UF',
 PRIM_FILE='./archive_libs/logical/q_cap/chips/chips.prt';

PART_NAME
 PC2159 'Q_CAP_C0402-1UF,25V,10%,EMPTY,A':
 ROOM='NIC1_P3V3_BOM2';

SECTION_NUMBER 1
 '@S9S_MB_2U_LIB.S9S_MB_2U(SCH_1):PAGE236_I55@PURE_QUANTA.Q_CAP(CHIPS)':
 C_PATH='@s9s_mb_2u_lib.s9s_mb_2u(sch_1):page236_i55@pure_quanta.q_cap(chips)',
 P_PATH='@s9s_mb_2u_lib.s9s_mb_2u(sch_1):page157_i55@pure_quanta.q_cap(chips)',
 PATH='I55',
 DRAWING='@S9S_MB_2U_LIB.S9S_MB_2U(SCH_1):PAGE236',
 PHYS_PAGE='157',
 XY='(-3550,12875)',
 ROT='0',
 VER='1',
 PACK_TYPE='C0402',
 LOCATION='PC2159',
 CDS_LIB='pure_quanta',
 CDS_PART_NAME='Q_CAP_C0402-1UF,25V,10%,EMPTY,A',
 TOLERANCE='10%',
 MATERIAL='EMPTY',
 VOLTAGE='25V',
 ROOM='NIC1_P3V3_BOM2',
 VALUE='1UF',
 PRIM_FILE='./archive_libs/logical/q_cap/chips/chips.prt';

PART_NAME
 PC2160 'Q_CAP_0402-0.1UF,25V,10%,X7R,CA':
 ROOM='NIC1_P12V_MPS_MAM_BOM3';

SECTION_NUMBER 1
 '@S9S_MB_2U_LIB.S9S_MB_2U(SCH_1):PAGE236_I91@PURE_QUANTA.Q_CAP(CHIPS)':
 C_PATH='@s9s_mb_2u_lib.s9s_mb_2u(sch_1):page236_i91@pure_quanta.q_cap(chips)',
 P_PATH='@s9s_mb_2u_lib.s9s_mb_2u(sch_1):page157_i91@pure_quanta.q_cap(chips)',
 PATH='I91',
 DRAWING='@S9S_MB_2U_LIB.S9S_MB_2U(SCH_1):PAGE236',
 ROOM1='NIC1_P12V_MPS_TIC_BOM4',
 PHYS_PAGE='157',
 XY='(-3550,9975)',
 ROT='2',
 VER='1',
 PACK_TYPE='0402',
 LOCATION='PC2160',
 CDS_LIB='pure_quanta',
 CDS_PART_NAME='Q_CAP_0402-0.1UF,25V,10%,X7R,CA',
 TOLERANCE='10%',
 MATERIAL='X7R',
 VOLTAGE='25V',
 ROOM='NIC1_P12V_MPS_MAM_BOM3',
 VALUE='0.1UF',
 PRIM_FILE='./archive_libs/logical/q_cap/chips/chips.prt';

PART_NAME
 PC2161 'Q_CAP_0402-0.068UF,16V,10%,EMPA':
 ROOM='NIC1_P3V3_BOM2';

SECTION_NUMBER 1
 '@S9S_MB_2U_LIB.S9S_MB_2U(SCH_1):PAGE236_I49@PURE_QUANTA.Q_CAP(CHIPS)':
 C_PATH='@s9s_mb_2u_lib.s9s_mb_2u(sch_1):page236_i49@pure_quanta.q_cap(chips)',
 P_PATH='@s9s_mb_2u_lib.s9s_mb_2u(sch_1):page157_i49@pure_quanta.q_cap(chips)',
 PATH='I49',
 DRAWING='@S9S_MB_2U_LIB.S9S_MB_2U(SCH_1):PAGE236',
 PHYS_PAGE='157',
 XY='(-2975,12225)',
 ROT='0',
 VER='1',
 PACK_TYPE='0402',
 LOCATION='PC2161',
 CDS_LIB='pure_quanta',
 CDS_PART_NAME='Q_CAP_0402-0.068UF,16V,10%,EMPA',
 TOLERANCE='10%',
 MATERIAL='EMPTY',
 VOLTAGE='16V',
 ROOM='NIC1_P3V3_BOM2',
 VALUE='0.068UF',
 PRIM_FILE='./archive_libs/logical/q_cap/chips/chips.prt';

PART_NAME
 PC2162 'Q_CAP_0402-100PF,50V,5%,EMPTY,A':
 ROOM='NIC1_P3V3_BOM2';

SECTION_NUMBER 1
 '@S9S_MB_2U_LIB.S9S_MB_2U(SCH_1):PAGE236_I52@PURE_QUANTA.Q_CAP(CHIPS)':
 C_PATH='@s9s_mb_2u_lib.s9s_mb_2u(sch_1):page236_i52@pure_quanta.q_cap(chips)',
 P_PATH='@s9s_mb_2u_lib.s9s_mb_2u(sch_1):page157_i52@pure_quanta.q_cap(chips)',
 PATH='I52',
 DRAWING='@S9S_MB_2U_LIB.S9S_MB_2U(SCH_1):PAGE236',
 PHYS_PAGE='157',
 XY='(-1475,12150)',
 ROT='0',
 VER='1',
 PACK_TYPE='0402',
 LOCATION='PC2162',
 CDS_LIB='pure_quanta',
 CDS_PART_NAME='Q_CAP_0402-100PF,50V,5%,EMPTY,A',
 TOLERANCE='5%',
 MATERIAL='EMPTY',
 VOLTAGE='50V',
 ROOM='NIC1_P3V3_BOM2',
 VALUE='100PF',
 PRIM_FILE='./archive_libs/logical/q_cap/chips/chips.prt';

PART_NAME
 PC2163 'Q_CAP_C0805-10UF,16V,10%,EMPTYB':
 ROOM='NIC1_P3V3_BOM2';

SECTION_NUMBER 1
 '@S9S_MB_2U_LIB.S9S_MB_2U(SCH_1):PAGE236_I54@PURE_QUANTA.Q_CAP(CHIPS)':
 C_PATH='@s9s_mb_2u_lib.s9s_mb_2u(sch_1):page236_i54@pure_quanta.q_cap(chips)',
 P_PATH='@s9s_mb_2u_lib.s9s_mb_2u(sch_1):page157_i54@pure_quanta.q_cap(chips)',
 PATH='I54',
 DRAWING='@S9S_MB_2U_LIB.S9S_MB_2U(SCH_1):PAGE236',
 PHYS_PAGE='157',
 XY='(-875,12375)',
 ROT='0',
 VER='1',
 PACK_TYPE='C0805',
 LOCATION='PC2163',
 CDS_LIB='pure_quanta',
 CDS_PART_NAME='Q_CAP_C0805-10UF,16V,10%,EMPTYB',
 TOLERANCE='10%',
 MATERIAL='EMPTY',
 VOLTAGE='16V',
 ROOM='NIC1_P3V3_BOM2',
 VALUE='10UF',
 PRIM_FILE='./archive_libs/logical/q_cap/chips/chips.prt';

PART_NAME
 PC2164 'Q_CAP_0402-0.22UF,16V,10%,X7R,A':
 ROOM='NIC1_P12V_MPS_MAM_BOM3';

SECTION_NUMBER 1
 '@S9S_MB_2U_LIB.S9S_MB_2U(SCH_1):PAGE237_I62@PURE_QUANTA.Q_CAP(CHIPS)':
 C_PATH='@s9s_mb_2u_lib.s9s_mb_2u(sch_1):page237_i62@pure_quanta.q_cap(chips)',
 P_PATH='@s9s_mb_2u_lib.s9s_mb_2u(sch_1):page163_i62@pure_quanta.q_cap(chips)',
 PATH='I62',
 DRAWING='@S9S_MB_2U_LIB.S9S_MB_2U(SCH_1):PAGE237',
 ROOM1='NIC1_P12V_MPS_TIC_BOM4',
 PHYS_PAGE='163',
 XY='(-4175,2725)',
 ROT='0',
 VER='1',
 PACK_TYPE='0402',
 LOCATION='PC2164',
 CDS_LIB='pure_quanta',
 CDS_PART_NAME='Q_CAP_0402-0.22UF,16V,10%,X7R,A',
 TOLERANCE='10%',
 MATERIAL='X7R',
 VOLTAGE='16V',
 ROOM='NIC1_P12V_MPS_MAM_BOM3',
 VALUE='0.22UF',
 PRIM_FILE='./archive_libs/logical/q_cap/chips/chips.prt';

PART_NAME
 PC2165 'Q_CAP_C0402-1UF,25V,10%,X6S,CHA':
 ROOM='NIC1_P12V_MPS_MAM_BOM3';

SECTION_NUMBER 1
 '@S9S_MB_2U_LIB.S9S_MB_2U(SCH_1):PAGE237_I68@PURE_QUANTA.Q_CAP(CHIPS)':
 C_PATH='@s9s_mb_2u_lib.s9s_mb_2u(sch_1):page237_i68@pure_quanta.q_cap(chips)',
 P_PATH='@s9s_mb_2u_lib.s9s_mb_2u(sch_1):page163_i68@pure_quanta.q_cap(chips)',
 PATH='I68',
 DRAWING='@S9S_MB_2U_LIB.S9S_MB_2U(SCH_1):PAGE237',
 ROOM1='NIC1_P12V_MPS_TIC_BOM4',
 PHYS_PAGE='163',
 XY='(-3500,3675)',
 ROT='0',
 VER='1',
 PACK_TYPE='C0402',
 LOCATION='PC2165',
 CDS_LIB='pure_quanta',
 CDS_PART_NAME='Q_CAP_C0402-1UF,25V,10%,X6S,CHA',
 TOLERANCE='10%',
 MATERIAL='X6S',
 VOLTAGE='25V',
 ROOM='NIC1_P12V_MPS_MAM_BOM3',
 VALUE='1UF',
 PRIM_FILE='./archive_libs/logical/q_cap/chips/chips.prt';

PART_NAME
 PC2166 'Q_CAP_C0402-0.047UF,25V,10%,X7A':
 ROOM='NIC1_P12V_MPS_MAM_BOM3';

SECTION_NUMBER 1
 '@S9S_MB_2U_LIB.S9S_MB_2U(SCH_1):PAGE237_I65@PURE_QUANTA.Q_CAP(CHIPS)':
 C_PATH='@s9s_mb_2u_lib.s9s_mb_2u(sch_1):page237_i65@pure_quanta.q_cap(chips)',
 P_PATH='@s9s_mb_2u_lib.s9s_mb_2u(sch_1):page163_i65@pure_quanta.q_cap(chips)',
 PATH='I65',
 DRAWING='@S9S_MB_2U_LIB.S9S_MB_2U(SCH_1):PAGE237',
 ROOM1='NIC1_P12V_MPS_TIC_BOM4',
 PHYS_PAGE='163',
 XY='(-3330,2508)',
 ROT='0',
 VER='1',
 PACK_TYPE='C0402',
 LOCATION='PC2166',
 CDS_LIB='pure_quanta',
 CDS_PART_NAME='Q_CAP_C0402-0.047UF,25V,10%,X7A',
 TOLERANCE='10%',
 MATERIAL='X7R',
 VOLTAGE='25V',
 ROOM='NIC1_P12V_MPS_MAM_BOM3',
 VALUE='0.047UF',
 PRIM_FILE='./archive_libs/logical/q_cap/chips/chips.prt';

PART_NAME
 PC2167 'Q_CAP_0402-100PF,50V,5%,X7R,CHA':
 ROOM='NIC1_P12V_MPS_MAM_BOM3';

SECTION_NUMBER 1
 '@S9S_MB_2U_LIB.S9S_MB_2U(SCH_1):PAGE237_I73@PURE_QUANTA.Q_CAP(CHIPS)':
 C_PATH='@s9s_mb_2u_lib.s9s_mb_2u(sch_1):page237_i73@pure_quanta.q_cap(chips)',
 P_PATH='@s9s_mb_2u_lib.s9s_mb_2u(sch_1):page163_i73@pure_quanta.q_cap(chips)',
 PATH='I73',
 DRAWING='@S9S_MB_2U_LIB.S9S_MB_2U(SCH_1):PAGE237',
 ROOM1='NIC1_P12V_MPS_TIC_BOM4',
 PHYS_PAGE='163',
 XY='(-1550,2325)',
 ROT='0',
 VER='1',
 PACK_TYPE='0402',
 LOCATION='PC2167',
 CDS_LIB='pure_quanta',
 CDS_PART_NAME='Q_CAP_0402-100PF,50V,5%,X7R,CHA',
 TOLERANCE='5%',
 MATERIAL='X7R',
 VOLTAGE='50V',
 ROOM='NIC1_P12V_MPS_MAM_BOM3',
 VALUE='100PF',
 PRIM_FILE='./archive_libs/logical/q_cap/chips/chips.prt';

PART_NAME
 PC2168 'Q_CAP_C0402-39PF,50V,5%,EMPTY,A':
 ROOM='NIC1_P3V3_BOM2';

SECTION_NUMBER 1
 '@S9S_MB_2U_LIB.S9S_MB_2U(SCH_1):PAGE237_I35@PURE_QUANTA.Q_CAP(CHIPS)':
 C_PATH='@s9s_mb_2u_lib.s9s_mb_2u(sch_1):page237_i35@pure_quanta.q_cap(chips)',
 P_PATH='@s9s_mb_2u_lib.s9s_mb_2u(sch_1):page163_i35@pure_quanta.q_cap(chips)',
 PATH='I35',
 DRAWING='@S9S_MB_2U_LIB.S9S_MB_2U(SCH_1):PAGE237',
 PHYS_PAGE='163',
 XY='(-250,6175)',
 ROT='0',
 VER='1',
 PACK_TYPE='C0402',
 LOCATION='PC2168',
 CDS_LIB='pure_quanta',
 CDS_PART_NAME='Q_CAP_C0402-39PF,50V,5%,EMPTY,A',
 TOLERANCE='5%',
 MATERIAL='EMPTY',
 VOLTAGE='50V',
 ROOM='NIC1_P3V3_BOM2',
 VALUE='39PF',
 PRIM_FILE='./archive_libs/logical/q_cap/chips/chips.prt';

PART_NAME
 PC2169 'Q_CAP_C0402-1UF,25V,10%,EMPTY,A':
 ROOM='NIC1_P3V3_BOM2';

SECTION_NUMBER 1
 '@S9S_MB_2U_LIB.S9S_MB_2U(SCH_1):PAGE237_I48@PURE_QUANTA.Q_CAP(CHIPS)':
 C_PATH='@s9s_mb_2u_lib.s9s_mb_2u(sch_1):page237_i48@pure_quanta.q_cap(chips)',
 P_PATH='@s9s_mb_2u_lib.s9s_mb_2u(sch_1):page163_i48@pure_quanta.q_cap(chips)',
 PATH='I48',
 DRAWING='@S9S_MB_2U_LIB.S9S_MB_2U(SCH_1):PAGE237',
 PHYS_PAGE='163',
 XY='(470,6758)',
 ROT='0',
 VER='1',
 PACK_TYPE='C0402',
 LOCATION='PC2169',
 CDS_LIB='pure_quanta',
 CDS_PART_NAME='Q_CAP_C0402-1UF,25V,10%,EMPTY,A',
 TOLERANCE='10%',
 MATERIAL='EMPTY',
 VOLTAGE='25V',
 ROOM='NIC1_P3V3_BOM2',
 VALUE='1UF',
 PRIM_FILE='./archive_libs/logical/q_cap/chips/chips.prt';

PART_NAME
 PC2170 'Q_CAPP_SMLF-330UF,2.5V,+10/-35B':;

SECTION_NUMBER 1
 '@S9S_MB_2U_LIB.S9S_MB_2U(SCH_1):PAGE258_I70@PURE_QUANTA.Q_CAPP(CHIPS)':
 C_PATH='@s9s_mb_2u_lib.s9s_mb_2u(sch_1):page258_i70@pure_quanta.q_capp(chips)',
 P_PATH='@s9s_mb_2u_lib.s9s_mb_2u(sch_1):page272_i70@pure_quanta.q_capp(chips)',
 PATH='I70',
 DRAWING='@S9S_MB_2U_LIB.S9S_MB_2U(SCH_1):PAGE258',
 PHYS_PAGE='272',
 XY='(-3025,3500)',
 ROT='0',
 VER='1',
 PACK_TYPE='SMLF',
 LOCATION='PC2170',
 CDS_LIB='pure_quanta',
 CDS_PART_NAME='Q_CAPP_SMLF-330UF,2.5V,+10/-35B',
 TOLERANCE='+10/-35%',
 MATERIAL='SPCAP',
 VOLTAGE='2.5V',
 VALUE='330UF',
 PRIM_FILE='./archive_libs/logical/q_capp/chips/chips.prt';

PART_NAME
 PC2171 'Q_CAPP_SMLF-330UF,2.5V,+10/-35B':;

SECTION_NUMBER 1
 '@S9S_MB_2U_LIB.S9S_MB_2U(SCH_1):PAGE276_I73@PURE_QUANTA.Q_CAPP(CHIPS)':
 C_PATH='@s9s_mb_2u_lib.s9s_mb_2u(sch_1):page276_i73@pure_quanta.q_capp(chips)',
 P_PATH='@s9s_mb_2u_lib.s9s_mb_2u(sch_1):page290_i73@pure_quanta.q_capp(chips)',
 PATH='I73',
 DRAWING='@S9S_MB_2U_LIB.S9S_MB_2U(SCH_1):PAGE276',
 PHYS_PAGE='290',
 XY='(375,5175)',
 ROT='0',
 VER='1',
 PACK_TYPE='SMLF',
 LOCATION='PC2171',
 CDS_LIB='pure_quanta',
 CDS_PART_NAME='Q_CAPP_SMLF-330UF,2.5V,+10/-35B',
 TOLERANCE='+10/-35%',
 MATERIAL='SPCAP',
 VOLTAGE='2.5V',
 VALUE='330UF',
 PRIM_FILE='./archive_libs/logical/q_capp/chips/chips.prt';

PART_NAME
 PC2172 'Q_CAPP_SMLF-330UF,2.5V,+10/-35B':;

SECTION_NUMBER 1
 '@S9S_MB_2U_LIB.S9S_MB_2U(SCH_1):PAGE275_I72@PURE_QUANTA.Q_CAPP(CHIPS)':
 C_PATH='@s9s_mb_2u_lib.s9s_mb_2u(sch_1):page275_i72@pure_quanta.q_capp(chips)',
 P_PATH='@s9s_mb_2u_lib.s9s_mb_2u(sch_1):page289_i72@pure_quanta.q_capp(chips)',
 PATH='I72',
 DRAWING='@S9S_MB_2U_LIB.S9S_MB_2U(SCH_1):PAGE275',
 PHYS_PAGE='289',
 XY='(-2825,2800)',
 ROT='0',
 VER='1',
 PACK_TYPE='SMLF',
 LOCATION='PC2172',
 CDS_LIB='pure_quanta',
 CDS_PART_NAME='Q_CAPP_SMLF-330UF,2.5V,+10/-35B',
 TOLERANCE='+10/-35%',
 MATERIAL='SPCAP',
 VOLTAGE='2.5V',
 VALUE='330UF',
 PRIM_FILE='./archive_libs/logical/q_capp/chips/chips.prt';

PART_NAME
 PC2173 'Q_CAP_C0805-10UF,16V,10%,EMPTYB':
 ROOM='NIC1_P3V3_BOM2';

SECTION_NUMBER 1
 '@S9S_MB_2U_LIB.S9S_MB_2U(SCH_1):PAGE237_I56@PURE_QUANTA.Q_CAP(CHIPS)':
 C_PATH='@s9s_mb_2u_lib.s9s_mb_2u(sch_1):page237_i56@pure_quanta.q_cap(chips)',
 P_PATH='@s9s_mb_2u_lib.s9s_mb_2u(sch_1):page163_i56@pure_quanta.q_cap(chips)',
 PATH='I56',
 DRAWING='@S9S_MB_2U_LIB.S9S_MB_2U(SCH_1):PAGE237',
 PHYS_PAGE='163',
 XY='(2900,6350)',
 ROT='0',
 VER='1',
 PACK_TYPE='C0805',
 LOCATION='PC2173',
 CDS_LIB='pure_quanta',
 CDS_PART_NAME='Q_CAP_C0805-10UF,16V,10%,EMPTYB',
 TOLERANCE='10%',
 MATERIAL='EMPTY',
 VOLTAGE='16V',
 ROOM='NIC1_P3V3_BOM2',
 VALUE='10UF',
 PRIM_FILE='./archive_libs/logical/q_cap/chips/chips.prt';

PART_NAME
 PC2174 'Q_CAP_0402-0.1UF,25V,10%,X7R,CA':
 ROOM='NIC1_P12V_MPS_MAM_BOM3';

SECTION_NUMBER 1
 '@S9S_MB_2U_LIB.S9S_MB_2U(SCH_1):PAGE237_I91@PURE_QUANTA.Q_CAP(CHIPS)':
 C_PATH='@s9s_mb_2u_lib.s9s_mb_2u(sch_1):page237_i91@pure_quanta.q_cap(chips)',
 P_PATH='@s9s_mb_2u_lib.s9s_mb_2u(sch_1):page163_i91@pure_quanta.q_cap(chips)',
 PATH='I91',
 DRAWING='@S9S_MB_2U_LIB.S9S_MB_2U(SCH_1):PAGE237',
 ROOM1='NIC1_P12V_MPS_TIC_BOM4',
 PHYS_PAGE='163',
 XY='(475,3325)',
 ROT='2',
 VER='1',
 PACK_TYPE='0402',
 LOCATION='PC2174',
 CDS_LIB='pure_quanta',
 CDS_PART_NAME='Q_CAP_0402-0.1UF,25V,10%,X7R,CA',
 TOLERANCE='10%',
 MATERIAL='X7R',
 VOLTAGE='25V',
 ROOM='NIC1_P12V_MPS_MAM_BOM3',
 VALUE='0.1UF',
 PRIM_FILE='./archive_libs/logical/q_cap/chips/chips.prt';

PART_NAME
 PC2180 'Q_CAPP_THLF-560UF,2.5V,20%,OSCA':;

SECTION_NUMBER 1
 '@S9S_MB_2U_LIB.S9S_MB_2U(SCH_1):PAGE262_I33@PURE_QUANTA.Q_CAPP(CHIPS)':
 C_PATH='@s9s_mb_2u_lib.s9s_mb_2u(sch_1):page262_i33@pure_quanta.q_capp(chips)',
 P_PATH='@s9s_mb_2u_lib.s9s_mb_2u(sch_1):page276_i33@pure_quanta.q_capp(chips)',
 PATH='I33',
 DRAWING='@S9S_MB_2U_LIB.S9S_MB_2U(SCH_1):PAGE262',
 PHYS_PAGE='276',
 XY='(-3925,3350)',
 ROT='0',
 VER='1',
 PACK_TYPE='THLF',
 LOCATION='PC2180',
 CDS_LIB='pure_quanta',
 CDS_PART_NAME='Q_CAPP_THLF-560UF,2.5V,20%,OSCA',
 TOLERANCE='20%',
 MATERIAL='OSCON',
 VOLTAGE='2.5V',
 VALUE='560UF',
 PRIM_FILE='./archive_libs/logical/q_capp/chips/chips.prt';

PART_NAME
 PC2181 'Q_CAP_C0402-1UF,25V,10%,X6S,CHA':
 ROOM='HSC1_BOM1';

SECTION_NUMBER 1
 '@S9S_MB_2U_LIB.S9S_MB_2U(SCH_1):PAGE301_I4@PURE_QUANTA.Q_CAP(CHIPS)':
 C_PATH='@s9s_mb_2u_lib.s9s_mb_2u(sch_1):page301_i4@pure_quanta.q_cap(chips)',
 P_PATH='@s9s_mb_2u_lib.s9s_mb_2u(sch_1):page302_i4@pure_quanta.q_cap(chips)',
 PATH='I4',
 DRAWING='@S9S_MB_2U_LIB.S9S_MB_2U(SCH_1):PAGE301',
 PHYS_PAGE='302',
 XY='(-3700,-1375)',
 ROT='0',
 VER='1',
 PACK_TYPE='C0402',
 LOCATION='PC2181',
 CDS_LIB='pure_quanta',
 CDS_PART_NAME='Q_CAP_C0402-1UF,25V,10%,X6S,CHA',
 TOLERANCE='10%',
 MATERIAL='X6S',
 VOLTAGE='25V',
 ROOM='HSC1_BOM1',
 VALUE='1UF',
 PRIM_FILE='./archive_libs/logical/q_cap/chips/chips.prt';

PART_NAME
 PC2182 'Q_CAP_0402-220PF,50V,10%,X7R,TA':
 ROOM='HSC1_BOM1';

SECTION_NUMBER 1
 '@S9S_MB_2U_LIB.S9S_MB_2U(SCH_1):PAGE301_I23@PURE_QUANTA.Q_CAP(CHIPS)':
 C_PATH='@s9s_mb_2u_lib.s9s_mb_2u(sch_1):page301_i23@pure_quanta.q_cap(chips)',
 P_PATH='@s9s_mb_2u_lib.s9s_mb_2u(sch_1):page302_i23@pure_quanta.q_cap(chips)',
 PATH='I23',
 DRAWING='@S9S_MB_2U_LIB.S9S_MB_2U(SCH_1):PAGE301',
 PHYS_PAGE='302',
 XY='(-2900,775)',
 ROT='0',
 VER='1',
 PACK_TYPE='0402',
 LOCATION='PC2182',
 CDS_LIB='pure_quanta',
 CDS_PART_NAME='Q_CAP_0402-220PF,50V,10%,X7R,TA',
 TOLERANCE='10%',
 MATERIAL='X7R',
 VOLTAGE='50V',
 ROOM='HSC1_BOM1',
 VALUE='220PF',
 PRIM_FILE='./archive_libs/logical/q_cap/chips/chips.prt';

PART_NAME
 PC2183 'Q_CAP_0402-220PF,50V,10%,EMPTYA':;

SECTION_NUMBER 1
 '@S9S_MB_2U_LIB.S9S_MB_2U(SCH_1):PAGE301_I2@PURE_QUANTA.Q_CAP(CHIPS)':
 C_PATH='@s9s_mb_2u_lib.s9s_mb_2u(sch_1):page301_i2@pure_quanta.q_cap(chips)',
 P_PATH='@s9s_mb_2u_lib.s9s_mb_2u(sch_1):page302_i2@pure_quanta.q_cap(chips)',
 PATH='I2',
 DRAWING='@S9S_MB_2U_LIB.S9S_MB_2U(SCH_1):PAGE301',
 PHYS_PAGE='302',
 XY='(-2875,-2025)',
 ROT='0',
 VER='1',
 PACK_TYPE='0402',
 LOCATION='PC2183',
 CDS_LIB='pure_quanta',
 CDS_PART_NAME='Q_CAP_0402-220PF,50V,10%,EMPTYA',
 TOLERANCE='10%',
 MATERIAL='EMPTY',
 VOLTAGE='50V',
 VALUE='220PF',
 PRIM_FILE='./archive_libs/logical/q_cap/chips/chips.prt';

PART_NAME
 PC2184 'Q_CAP_0402-0.068UF,16V,10%,X7RA':
 ROOM='HSC1_BOM1';

SECTION_NUMBER 1
 '@S9S_MB_2U_LIB.S9S_MB_2U(SCH_1):PAGE301_I47@PURE_QUANTA.Q_CAP(CHIPS)':
 C_PATH='@s9s_mb_2u_lib.s9s_mb_2u(sch_1):page301_i47@pure_quanta.q_cap(chips)',
 P_PATH='@s9s_mb_2u_lib.s9s_mb_2u(sch_1):page302_i47@pure_quanta.q_cap(chips)',
 PATH='I47',
 DRAWING='@S9S_MB_2U_LIB.S9S_MB_2U(SCH_1):PAGE301',
 PHYS_PAGE='302',
 XY='(750,800)',
 ROT='0',
 VER='1',
 PACK_TYPE='0402',
 LOCATION='PC2184',
 CDS_LIB='pure_quanta',
 CDS_PART_NAME='Q_CAP_0402-0.068UF,16V,10%,X7RA',
 TOLERANCE='10%',
 MATERIAL='X7R',
 VOLTAGE='16V',
 ROOM='HSC1_BOM1',
 VALUE='0.068UF',
 PRIM_FILE='./archive_libs/logical/q_cap/chips/chips.prt';

PART_NAME
 PC2185 'Q_CAP_0402-0.068UF,16V,10%,X7RA':
 ROOM='HSC1_BOM1';

SECTION_NUMBER 1
 '@S9S_MB_2U_LIB.S9S_MB_2U(SCH_1):PAGE301_I37@PURE_QUANTA.Q_CAP(CHIPS)':
 C_PATH='@s9s_mb_2u_lib.s9s_mb_2u(sch_1):page301_i37@pure_quanta.q_cap(chips)',
 P_PATH='@s9s_mb_2u_lib.s9s_mb_2u(sch_1):page302_i37@pure_quanta.q_cap(chips)',
 PATH='I37',
 DRAWING='@S9S_MB_2U_LIB.S9S_MB_2U(SCH_1):PAGE301',
 PHYS_PAGE='302',
 XY='(750,-2000)',
 ROT='0',
 VER='1',
 PACK_TYPE='0402',
 LOCATION='PC2185',
 CDS_LIB='pure_quanta',
 CDS_PART_NAME='Q_CAP_0402-0.068UF,16V,10%,X7RA',
 TOLERANCE='10%',
 MATERIAL='X7R',
 VOLTAGE='16V',
 ROOM='HSC1_BOM1',
 VALUE='0.068UF',
 PRIM_FILE='./archive_libs/logical/q_cap/chips/chips.prt';

PART_NAME
 PC2186 'Q_CAP_C0402-1UF,25V,10%,X6S,CHA':
 ROOM='HSC1_BOM1';

SECTION_NUMBER 1
 '@S9S_MB_2U_LIB.S9S_MB_2U(SCH_1):PAGE303_I14@PURE_QUANTA.Q_CAP(CHIPS)':
 C_PATH='@s9s_mb_2u_lib.s9s_mb_2u(sch_1):page303_i14@pure_quanta.q_cap(chips)',
 P_PATH='@s9s_mb_2u_lib.s9s_mb_2u(sch_1):page301_i14@pure_quanta.q_cap(chips)',
 PATH='I14',
 DRAWING='@S9S_MB_2U_LIB.S9S_MB_2U(SCH_1):PAGE303',
 PHYS_PAGE='301',
 XY='(-17150,4325)',
 ROT='0',
 VER='1',
 PACK_TYPE='C0402',
 LOCATION='PC2186',
 CDS_LIB='pure_quanta',
 CDS_PART_NAME='Q_CAP_C0402-1UF,25V,10%,X6S,CHA',
 TOLERANCE='10%',
 MATERIAL='X6S',
 VOLTAGE='25V',
 ROOM='HSC1_BOM1',
 VALUE='1UF',
 PRIM_FILE='./archive_libs/logical/q_cap/chips/chips.prt';

PART_NAME
 PC2187 'Q_CAP_C0402-1UF,25V,10%,X6S,CHA':
 ROOM='HSC1_BOM1';

SECTION_NUMBER 1
 '@S9S_MB_2U_LIB.S9S_MB_2U(SCH_1):PAGE303_I23@PURE_QUANTA.Q_CAP(CHIPS)':
 C_PATH='@s9s_mb_2u_lib.s9s_mb_2u(sch_1):page303_i23@pure_quanta.q_cap(chips)',
 P_PATH='@s9s_mb_2u_lib.s9s_mb_2u(sch_1):page301_i23@pure_quanta.q_cap(chips)',
 PATH='I23',
 DRAWING='@S9S_MB_2U_LIB.S9S_MB_2U(SCH_1):PAGE303',
 PHYS_PAGE='301',
 XY='(-16650,4300)',
 ROT='0',
 VER='1',
 PACK_TYPE='C0402',
 LOCATION='PC2187',
 CDS_LIB='pure_quanta',
 CDS_PART_NAME='Q_CAP_C0402-1UF,25V,10%,X6S,CHA',
 TOLERANCE='10%',
 MATERIAL='X6S',
 VOLTAGE='25V',
 ROOM='HSC1_BOM1',
 VALUE='1UF',
 PRIM_FILE='./archive_libs/logical/q_cap/chips/chips.prt';

PART_NAME
 PC2188 'Q_CAP_C0402-1UF,25V,10%,X6S,CHA':
 ROOM='HSC1_BOM1';

SECTION_NUMBER 1
 '@S9S_MB_2U_LIB.S9S_MB_2U(SCH_1):PAGE303_I51@PURE_QUANTA.Q_CAP(CHIPS)':
 C_PATH='@s9s_mb_2u_lib.s9s_mb_2u(sch_1):page303_i51@pure_quanta.q_cap(chips)',
 P_PATH='@s9s_mb_2u_lib.s9s_mb_2u(sch_1):page301_i51@pure_quanta.q_cap(chips)',
 PATH='I51',
 DRAWING='@S9S_MB_2U_LIB.S9S_MB_2U(SCH_1):PAGE303',
 PHYS_PAGE='301',
 XY='(-15950,5050)',
 ROT='0',
 VER='1',
 PACK_TYPE='C0402',
 LOCATION='PC2188',
 CDS_LIB='pure_quanta',
 CDS_PART_NAME='Q_CAP_C0402-1UF,25V,10%,X6S,CHA',
 TOLERANCE='10%',
 MATERIAL='X6S',
 VOLTAGE='25V',
 ROOM='HSC1_BOM1',
 VALUE='1UF',
 PRIM_FILE='./archive_libs/logical/q_cap/chips/chips.prt';

PART_NAME
 PC2189 'Q_CAP_C0402-0.01UF,50V,10%,X7RA':
 ROOM='HSC1_BOM1';

SECTION_NUMBER 1
 '@S9S_MB_2U_LIB.S9S_MB_2U(SCH_1):PAGE303_I45@PURE_QUANTA.Q_CAP(CHIPS)':
 C_PATH='@s9s_mb_2u_lib.s9s_mb_2u(sch_1):page303_i45@pure_quanta.q_cap(chips)',
 P_PATH='@s9s_mb_2u_lib.s9s_mb_2u(sch_1):page301_i45@pure_quanta.q_cap(chips)',
 PATH='I45',
 DRAWING='@S9S_MB_2U_LIB.S9S_MB_2U(SCH_1):PAGE303',
 PHYS_PAGE='301',
 XY='(-14900,4600)',
 ROT='0',
 VER='1',
 PACK_TYPE='C0402',
 LOCATION='PC2189',
 CDS_LIB='pure_quanta',
 CDS_PART_NAME='Q_CAP_C0402-0.01UF,50V,10%,X7RA',
 TOLERANCE='10%',
 MATERIAL='X7R',
 VOLTAGE='50V',
 ROOM='HSC1_BOM1',
 VALUE='0.01UF',
 PRIM_FILE='./archive_libs/logical/q_cap/chips/chips.prt';

PART_NAME
 PC2190 'Q_CAP_C0402-0.01UF,50V,10%,X7RA':
 ROOM='HSC1_BOM1';

SECTION_NUMBER 1
 '@S9S_MB_2U_LIB.S9S_MB_2U(SCH_1):PAGE303_I75@PURE_QUANTA.Q_CAP(CHIPS)':
 C_PATH='@s9s_mb_2u_lib.s9s_mb_2u(sch_1):page303_i75@pure_quanta.q_cap(chips)',
 P_PATH='@s9s_mb_2u_lib.s9s_mb_2u(sch_1):page301_i75@pure_quanta.q_cap(chips)',
 PATH='I75',
 DRAWING='@S9S_MB_2U_LIB.S9S_MB_2U(SCH_1):PAGE303',
 PHYS_PAGE='301',
 XY='(-11500,4675)',
 ROT='0',
 VER='1',
 PACK_TYPE='C0402',
 LOCATION='PC2190',
 CDS_LIB='pure_quanta',
 CDS_PART_NAME='Q_CAP_C0402-0.01UF,50V,10%,X7RA',
 TOLERANCE='10%',
 MATERIAL='X7R',
 VOLTAGE='50V',
 ROOM='HSC1_BOM1',
 VALUE='0.01UF',
 PRIM_FILE='./archive_libs/logical/q_cap/chips/chips.prt';

PART_NAME
 PC2191 'Q_CAP_0402-0.068UF,16V,10%,X7RA':
 ROOM='HSC1_BOM1';

SECTION_NUMBER 1
 '@S9S_MB_2U_LIB.S9S_MB_2U(SCH_1):PAGE303_I69@PURE_QUANTA.Q_CAP(CHIPS)':
 C_PATH='@s9s_mb_2u_lib.s9s_mb_2u(sch_1):page303_i69@pure_quanta.q_cap(chips)',
 P_PATH='@s9s_mb_2u_lib.s9s_mb_2u(sch_1):page301_i69@pure_quanta.q_cap(chips)',
 PATH='I69',
 DRAWING='@S9S_MB_2U_LIB.S9S_MB_2U(SCH_1):PAGE303',
 PHYS_PAGE='301',
 XY='(-11225,2875)',
 ROT='0',
 VER='1',
 PACK_TYPE='0402',
 LOCATION='PC2191',
 CDS_LIB='pure_quanta',
 CDS_PART_NAME='Q_CAP_0402-0.068UF,16V,10%,X7RA',
 TOLERANCE='10%',
 MATERIAL='X7R',
 VOLTAGE='16V',
 ROOM='HSC1_BOM1',
 VALUE='0.068UF',
 PRIM_FILE='./archive_libs/logical/q_cap/chips/chips.prt';

PART_NAME
 PC2192 'Q_CAP_C0402-0.001UF,50V,10%,X7A':
 ROOM='HSC1_BOM1';

SECTION_NUMBER 1
 '@S9S_MB_2U_LIB.S9S_MB_2U(SCH_1):PAGE303_I77@PURE_QUANTA.Q_CAP(CHIPS)':
 C_PATH='@s9s_mb_2u_lib.s9s_mb_2u(sch_1):page303_i77@pure_quanta.q_cap(chips)',
 P_PATH='@s9s_mb_2u_lib.s9s_mb_2u(sch_1):page301_i77@pure_quanta.q_cap(chips)',
 PATH='I77',
 DRAWING='@S9S_MB_2U_LIB.S9S_MB_2U(SCH_1):PAGE303',
 PHYS_PAGE='301',
 XY='(-10650,3125)',
 ROT='0',
 VER='1',
 PACK_TYPE='C0402',
 LOCATION='PC2192',
 CDS_LIB='pure_quanta',
 CDS_PART_NAME='Q_CAP_C0402-0.001UF,50V,10%,X7A',
 TOLERANCE='10%',
 MATERIAL='X7R',
 VOLTAGE='50V',
 ROOM='HSC1_BOM1',
 VALUE='0.001UF',
 PRIM_FILE='./archive_libs/logical/q_cap/chips/chips.prt';

PART_NAME
 PC2193 'Q_CAP_C0402-0.047UF,25V,10%,X7A':
 ROOM='HSC1_BOM1';

SECTION_NUMBER 1
 '@S9S_MB_2U_LIB.S9S_MB_2U(SCH_1):PAGE303_I89@PURE_QUANTA.Q_CAP(CHIPS)':
 C_PATH='@s9s_mb_2u_lib.s9s_mb_2u(sch_1):page303_i89@pure_quanta.q_cap(chips)',
 P_PATH='@s9s_mb_2u_lib.s9s_mb_2u(sch_1):page301_i89@pure_quanta.q_cap(chips)',
 PATH='I89',
 DRAWING='@S9S_MB_2U_LIB.S9S_MB_2U(SCH_1):PAGE303',
 PHYS_PAGE='301',
 XY='(-9825,3550)',
 ROT='0',
 VER='1',
 PACK_TYPE='C0402',
 LOCATION='PC2193',
 CDS_LIB='pure_quanta',
 CDS_PART_NAME='Q_CAP_C0402-0.047UF,25V,10%,X7A',
 TOLERANCE='10%',
 MATERIAL='X7R',
 VOLTAGE='25V',
 ROOM='HSC1_BOM1',
 VALUE='0.047UF',
 PRIM_FILE='./archive_libs/logical/q_cap/chips/chips.prt';

PART_NAME
 PC2196 'Q_CAP_0402-0.22UF,16V,10%,X7R,A':
 ROOM='E1S1_P12V_MPS_MAM_BOM3';

SECTION_NUMBER 1
 '@S9S_MB_2U_LIB.S9S_MB_2U(SCH_1):PAGE323_I37@PURE_QUANTA.Q_CAP(CHIPS)':
 C_PATH='@s9s_mb_2u_lib.s9s_mb_2u(sch_1):page323_i37@pure_quanta.q_cap(chips)',
 P_PATH='@s9s_mb_2u_lib.s9s_mb_2u(sch_1):page193_i37@pure_quanta.q_cap(chips)',
 PATH='I37',
 DRAWING='@S9S_MB_2U_LIB.S9S_MB_2U(SCH_1):PAGE323',
 ROOM1='E1S1_P12V_MPS_TIC_BOM4',
 PHYS_PAGE='193',
 XY='(-2200,725)',
 ROT='0',
 VER='1',
 PACK_TYPE='0402',
 LOCATION='PC2196',
 CDS_LIB='pure_quanta',
 CDS_PART_NAME='Q_CAP_0402-0.22UF,16V,10%,X7R,A',
 TOLERANCE='10%',
 MATERIAL='X7R',
 VOLTAGE='16V',
 ROOM='E1S1_P12V_MPS_MAM_BOM3',
 VALUE='0.22UF',
 PRIM_FILE='./archive_libs/logical/q_cap/chips/chips.prt';

PART_NAME
 PC2197 'Q_CAP_C0402-39PF,50V,5%,EMPTY,A':
 ROOM='E1S1_P3V3_BOM2';

SECTION_NUMBER 1
 '@S9S_MB_2U_LIB.S9S_MB_2U(SCH_1):PAGE323_I3@PURE_QUANTA.Q_CAP(CHIPS)':
 C_PATH='@s9s_mb_2u_lib.s9s_mb_2u(sch_1):page323_i3@pure_quanta.q_cap(chips)',
 P_PATH='@s9s_mb_2u_lib.s9s_mb_2u(sch_1):page193_i3@pure_quanta.q_cap(chips)',
 PATH='I3',
 DRAWING='@S9S_MB_2U_LIB.S9S_MB_2U(SCH_1):PAGE323',
 PHYS_PAGE='193',
 XY='(-1100,-1625)',
 ROT='0',
 VER='1',
 PACK_TYPE='C0402',
 LOCATION='PC2197',
 CDS_LIB='pure_quanta',
 CDS_PART_NAME='Q_CAP_C0402-39PF,50V,5%,EMPTY,A',
 TOLERANCE='5%',
 MATERIAL='EMPTY',
 VOLTAGE='50V',
 ROOM='E1S1_P3V3_BOM2',
 VALUE='39PF',
 PRIM_FILE='./archive_libs/logical/q_cap/chips/chips.prt';

PART_NAME
 PC2198 'Q_CAP_C0402-1UF,25V,10%,X6S,CHA':
 ROOM='E1S1_P12V_MPS_MAM_BOM3';

SECTION_NUMBER 1
 '@S9S_MB_2U_LIB.S9S_MB_2U(SCH_1):PAGE323_I51@PURE_QUANTA.Q_CAP(CHIPS)':
 C_PATH='@s9s_mb_2u_lib.s9s_mb_2u(sch_1):page323_i51@pure_quanta.q_cap(chips)',
 P_PATH='@s9s_mb_2u_lib.s9s_mb_2u(sch_1):page193_i51@pure_quanta.q_cap(chips)',
 PATH='I51',
 DRAWING='@S9S_MB_2U_LIB.S9S_MB_2U(SCH_1):PAGE323',
 ROOM1='E1S1_P12V_MPS_TIC_BOM4',
 PHYS_PAGE='193',
 XY='(-975,1575)',
 ROT='0',
 VER='1',
 PACK_TYPE='C0402',
 LOCATION='PC2198',
 CDS_LIB='pure_quanta',
 CDS_PART_NAME='Q_CAP_C0402-1UF,25V,10%,X6S,CHA',
 TOLERANCE='10%',
 MATERIAL='X6S',
 VOLTAGE='25V',
 ROOM='E1S1_P12V_MPS_MAM_BOM3',
 VALUE='1UF',
 PRIM_FILE='./archive_libs/logical/q_cap/chips/chips.prt';

PART_NAME
 PC2199 'Q_CAPP_THLF-560UF,2.5V,20%,OSCA':;

SECTION_NUMBER 1
 '@S9S_MB_2U_LIB.S9S_MB_2U(SCH_1):PAGE280_I32@PURE_QUANTA.Q_CAPP(CHIPS)':
 C_PATH='@s9s_mb_2u_lib.s9s_mb_2u(sch_1):page280_i32@pure_quanta.q_capp(chips)',
 P_PATH='@s9s_mb_2u_lib.s9s_mb_2u(sch_1):page294_i32@pure_quanta.q_capp(chips)',
 PATH='I32',
 DRAWING='@S9S_MB_2U_LIB.S9S_MB_2U(SCH_1):PAGE280',
 PHYS_PAGE='294',
 XY='(-775,9000)',
 ROT='0',
 VER='1',
 PACK_TYPE='THLF',
 LOCATION='PC2199',
 CDS_LIB='pure_quanta',
 CDS_PART_NAME='Q_CAPP_THLF-560UF,2.5V,20%,OSCA',
 TOLERANCE='20%',
 MATERIAL='OSCON',
 VOLTAGE='2.5V',
 VALUE='560UF',
 PRIM_FILE='./archive_libs/logical/q_capp/chips/chips.prt';

PART_NAME
 PC2200 'Q_CAP_C0402-1UF,25V,10%,EMPTY,A':
 ROOM='E1S1_P3V3_BOM2';

SECTION_NUMBER 1
 '@S9S_MB_2U_LIB.S9S_MB_2U(SCH_1):PAGE323_I9@PURE_QUANTA.Q_CAP(CHIPS)':
 C_PATH='@s9s_mb_2u_lib.s9s_mb_2u(sch_1):page323_i9@pure_quanta.q_cap(chips)',
 P_PATH='@s9s_mb_2u_lib.s9s_mb_2u(sch_1):page193_i9@pure_quanta.q_cap(chips)',
 PATH='I9',
 DRAWING='@S9S_MB_2U_LIB.S9S_MB_2U(SCH_1):PAGE323',
 PHYS_PAGE='193',
 XY='(-450,-1050)',
 ROT='0',
 VER='1',
 PACK_TYPE='C0402',
 LOCATION='PC2200',
 CDS_LIB='pure_quanta',
 CDS_PART_NAME='Q_CAP_C0402-1UF,25V,10%,EMPTY,A',
 TOLERANCE='10%',
 MATERIAL='EMPTY',
 VOLTAGE='25V',
 ROOM='E1S1_P3V3_BOM2',
 VALUE='1UF',
 PRIM_FILE='./archive_libs/logical/q_cap/chips/chips.prt';

PART_NAME
 PC2201 'Q_CAP_0402-0.068UF,16V,10%,EMPA':
 ROOM='E1S1_P3V3_BOM2';

SECTION_NUMBER 1
 '@S9S_MB_2U_LIB.S9S_MB_2U(SCH_1):PAGE323_I30@PURE_QUANTA.Q_CAP(CHIPS)':
 C_PATH='@s9s_mb_2u_lib.s9s_mb_2u(sch_1):page323_i30@pure_quanta.q_cap(chips)',
 P_PATH='@s9s_mb_2u_lib.s9s_mb_2u(sch_1):page193_i30@pure_quanta.q_cap(chips)',
 PATH='I30',
 DRAWING='@S9S_MB_2U_LIB.S9S_MB_2U(SCH_1):PAGE323',
 PHYS_PAGE='193',
 XY='(125,-1700)',
 ROT='0',
 VER='1',
 PACK_TYPE='0402',
 LOCATION='PC2201',
 CDS_LIB='pure_quanta',
 CDS_PART_NAME='Q_CAP_0402-0.068UF,16V,10%,EMPA',
 TOLERANCE='10%',
 MATERIAL='EMPTY',
 VOLTAGE='16V',
 ROOM='E1S1_P3V3_BOM2',
 VALUE='0.068UF',
 PRIM_FILE='./archive_libs/logical/q_cap/chips/chips.prt';

PART_NAME
 PC2202 'Q_CAP_C0402-100NF,50V,10%,X7R,A':
 ROOM='E1S1_P12V_MPS_MAM_BOM3';

SECTION_NUMBER 1
 '@S9S_MB_2U_LIB.S9S_MB_2U(SCH_1):PAGE323_I56@PURE_QUANTA.Q_CAP(CHIPS)':
 C_PATH='@s9s_mb_2u_lib.s9s_mb_2u(sch_1):page323_i56@pure_quanta.q_cap(chips)',
 P_PATH='@s9s_mb_2u_lib.s9s_mb_2u(sch_1):page193_i56@pure_quanta.q_cap(chips)',
 PATH='I56',
 DRAWING='@S9S_MB_2U_LIB.S9S_MB_2U(SCH_1):PAGE323',
 ROOM1='E1S1_P12V_MPS_TIC_BOM4',
 PHYS_PAGE='193',
 XY='(975,300)',
 ROT='0',
 VER='1',
 PACK_TYPE='C0402',
 LOCATION='PC2202',
 CDS_LIB='pure_quanta',
 CDS_PART_NAME='Q_CAP_C0402-100NF,50V,10%,X7R,A',
 TOLERANCE='10%',
 MATERIAL='X7R',
 VOLTAGE='50V',
 ROOM='E1S1_P12V_MPS_MAM_BOM3',
 VALUE='100NF',
 PRIM_FILE='./archive_libs/logical/q_cap/chips/chips.prt';

PART_NAME
 PC2203 'Q_CAP_0402-100PF,50V,5%,EMPTY,A':
 ROOM='E1S1_P3V3_BOM2';

SECTION_NUMBER 1
 '@S9S_MB_2U_LIB.S9S_MB_2U(SCH_1):PAGE323_I32@PURE_QUANTA.Q_CAP(CHIPS)':
 C_PATH='@s9s_mb_2u_lib.s9s_mb_2u(sch_1):page323_i32@pure_quanta.q_cap(chips)',
 P_PATH='@s9s_mb_2u_lib.s9s_mb_2u(sch_1):page193_i32@pure_quanta.q_cap(chips)',
 PATH='I32',
 DRAWING='@S9S_MB_2U_LIB.S9S_MB_2U(SCH_1):PAGE323',
 PHYS_PAGE='193',
 XY='(1625,-1775)',
 ROT='0',
 VER='1',
 PACK_TYPE='0402',
 LOCATION='PC2203',
 CDS_LIB='pure_quanta',
 CDS_PART_NAME='Q_CAP_0402-100PF,50V,5%,EMPTY,A',
 TOLERANCE='5%',
 MATERIAL='EMPTY',
 VOLTAGE='50V',
 ROOM='E1S1_P3V3_BOM2',
 VALUE='100PF',
 PRIM_FILE='./archive_libs/logical/q_cap/chips/chips.prt';

PART_NAME
 PC2204 'Q_CAP_C0805-10UF,16V,10%,EMPTYB':
 ROOM='E1S1_P3V3_BOM2';

SECTION_NUMBER 1
 '@S9S_MB_2U_LIB.S9S_MB_2U(SCH_1):PAGE323_I34@PURE_QUANTA.Q_CAP(CHIPS)':
 C_PATH='@s9s_mb_2u_lib.s9s_mb_2u(sch_1):page323_i34@pure_quanta.q_cap(chips)',
 P_PATH='@s9s_mb_2u_lib.s9s_mb_2u(sch_1):page193_i34@pure_quanta.q_cap(chips)',
 PATH='I34',
 DRAWING='@S9S_MB_2U_LIB.S9S_MB_2U(SCH_1):PAGE323',
 PHYS_PAGE='193',
 XY='(2225,-1550)',
 ROT='0',
 VER='1',
 PACK_TYPE='C0805',
 LOCATION='PC2204',
 CDS_LIB='pure_quanta',
 CDS_PART_NAME='Q_CAP_C0805-10UF,16V,10%,EMPTYB',
 TOLERANCE='10%',
 MATERIAL='EMPTY',
 VOLTAGE='16V',
 ROOM='E1S1_P3V3_BOM2',
 VALUE='10UF',
 PRIM_FILE='./archive_libs/logical/q_cap/chips/chips.prt';

PART_NAME
 PC2205 'Q_CAP_C0603-2.2UF,16V,20%,X7R,A':
 ROOM='E1S1_P12V_MPS_MAM_BOM3';

SECTION_NUMBER 1
 '@S9S_MB_2U_LIB.S9S_MB_2U(SCH_1):PAGE323_I69@PURE_QUANTA.Q_CAP(CHIPS)':
 C_PATH='@s9s_mb_2u_lib.s9s_mb_2u(sch_1):page323_i69@pure_quanta.q_cap(chips)',
 P_PATH='@s9s_mb_2u_lib.s9s_mb_2u(sch_1):page193_i69@pure_quanta.q_cap(chips)',
 PATH='I69',
 DRAWING='@S9S_MB_2U_LIB.S9S_MB_2U(SCH_1):PAGE323',
 ROOM1='E1S1_P12V_MPS_TIC_BOM4',
 PHYS_PAGE='193',
 XY='(2425,650)',
 ROT='0',
 VER='1',
 PACK_TYPE='C0603',
 LOCATION='PC2205',
 CDS_LIB='pure_quanta',
 CDS_PART_NAME='Q_CAP_C0603-2.2UF,16V,20%,X7R,A',
 TOLERANCE='20%',
 MATERIAL='X7R',
 VOLTAGE='16V',
 ROOM='E1S1_P12V_MPS_MAM_BOM3',
 VALUE='2.2UF',
 PRIM_FILE='./archive_libs/logical/q_cap/chips/chips.prt';

PART_NAME
 PC2206 'Q_CAP_0402-0.1UF,25V,10%,X7R,CA':
 ROOM='E1S1_P12V_MPS_MAM_BOM3';

SECTION_NUMBER 1
 '@S9S_MB_2U_LIB.S9S_MB_2U(SCH_1):PAGE323_I73@PURE_QUANTA.Q_CAP(CHIPS)':
 C_PATH='@s9s_mb_2u_lib.s9s_mb_2u(sch_1):page323_i73@pure_quanta.q_cap(chips)',
 P_PATH='@s9s_mb_2u_lib.s9s_mb_2u(sch_1):page193_i73@pure_quanta.q_cap(chips)',
 PATH='I73',
 DRAWING='@S9S_MB_2U_LIB.S9S_MB_2U(SCH_1):PAGE323',
 ROOM1='E1S1_P12V_MPS_TIC_BOM4',
 PHYS_PAGE='193',
 XY='(2775,1500)',
 ROT='2',
 VER='1',
 PACK_TYPE='0402',
 LOCATION='PC2206',
 CDS_LIB='pure_quanta',
 CDS_PART_NAME='Q_CAP_0402-0.1UF,25V,10%,X7R,CA',
 TOLERANCE='10%',
 MATERIAL='X7R',
 VOLTAGE='25V',
 ROOM='E1S1_P12V_MPS_MAM_BOM3',
 VALUE='0.1UF',
 PRIM_FILE='./archive_libs/logical/q_cap/chips/chips.prt';

PART_NAME
 PC2207 'Q_CAP_C0402-1UF,25V,10%,X6S,CHA':;

SECTION_NUMBER 1
 '@S9S_MB_2U_LIB.S9S_MB_2U(SCH_1):PAGE324_I31@PURE_QUANTA.Q_CAP(CHIPS)':
 C_PATH='@s9s_mb_2u_lib.s9s_mb_2u(sch_1):page324_i31@pure_quanta.q_cap(chips)',
 P_PATH='@s9s_mb_2u_lib.s9s_mb_2u(sch_1):page192_i31@pure_quanta.q_cap(chips)',
 PATH='I31',
 DRAWING='@S9S_MB_2U_LIB.S9S_MB_2U(SCH_1):PAGE324',
 PHYS_PAGE='192',
 XY='(-500,1625)',
 ROT='0',
 VER='1',
 PACK_TYPE='C0402',
 LOCATION='PC2207',
 CDS_LIB='pure_quanta',
 CDS_PART_NAME='Q_CAP_C0402-1UF,25V,10%,X6S,CHA',
 TOLERANCE='10%',
 MATERIAL='X6S',
 VOLTAGE='25V',
 VALUE='1UF',
 PRIM_FILE='./archive_libs/logical/q_cap/chips/chips.prt';

PART_NAME
 PC2208 'Q_CAP_C0402-1UF,25V,10%,X6S,CHA':
 ROOM='E1S1_P3V3_BOM1';

SECTION_NUMBER 1
 '@S9S_MB_2U_LIB.S9S_MB_2U(SCH_1):PAGE324_I17@PURE_QUANTA.Q_CAP(CHIPS)':
 C_PATH='@s9s_mb_2u_lib.s9s_mb_2u(sch_1):page324_i17@pure_quanta.q_cap(chips)',
 P_PATH='@s9s_mb_2u_lib.s9s_mb_2u(sch_1):page192_i17@pure_quanta.q_cap(chips)',
 PATH='I17',
 DRAWING='@S9S_MB_2U_LIB.S9S_MB_2U(SCH_1):PAGE324',
 PHYS_PAGE='192',
 XY='(-475,-1100)',
 ROT='0',
 VER='1',
 PACK_TYPE='C0402',
 LOCATION='PC2208',
 CDS_LIB='pure_quanta',
 CDS_PART_NAME='Q_CAP_C0402-1UF,25V,10%,X6S,CHA',
 TOLERANCE='10%',
 MATERIAL='X6S',
 VOLTAGE='25V',
 ROOM='E1S1_P3V3_BOM1',
 VALUE='1UF',
 PRIM_FILE='./archive_libs/logical/q_cap/chips/chips.prt';

PART_NAME
 PC2209 'Q_CAP_C0402-1UF,25V,10%,EMPTY,A':
 ROOM='E1S1_P12V_MAM_MAM_BOM1';

SECTION_NUMBER 1
 '@S9S_MB_2U_LIB.S9S_MB_2U(SCH_1):PAGE324_I60@PURE_QUANTA.Q_CAP(CHIPS)':
 C_PATH='@s9s_mb_2u_lib.s9s_mb_2u(sch_1):page324_i60@pure_quanta.q_cap(chips)',
 P_PATH='@s9s_mb_2u_lib.s9s_mb_2u(sch_1):page192_i60@pure_quanta.q_cap(chips)',
 PATH='I60',
 DRAWING='@S9S_MB_2U_LIB.S9S_MB_2U(SCH_1):PAGE324',
 ROOM1='E1S1_P12V_MAM_TIC_BOM2',
 PHYS_PAGE='192',
 XY='(175,1200)',
 ROT='0',
 VER='1',
 PACK_TYPE='C0402',
 LOCATION='PC2209',
 CDS_LIB='pure_quanta',
 CDS_PART_NAME='Q_CAP_C0402-1UF,25V,10%,EMPTY,A',
 TOLERANCE='10%',
 MATERIAL='EMPTY',
 VOLTAGE='25V',
 ROOM='E1S1_P12V_MAM_MAM_BOM1',
 VALUE='1UF',
 PRIM_FILE='./archive_libs/logical/q_cap/chips/chips.prt';

PART_NAME
 PC2210 'Q_CAP_C0402-1UF,25V,10%,X6S,CHA':
 ROOM='E1S1_P3V3_BOM1';

SECTION_NUMBER 1
 '@S9S_MB_2U_LIB.S9S_MB_2U(SCH_1):PAGE324_I37@PURE_QUANTA.Q_CAP(CHIPS)':
 C_PATH='@s9s_mb_2u_lib.s9s_mb_2u(sch_1):page324_i37@pure_quanta.q_cap(chips)',
 P_PATH='@s9s_mb_2u_lib.s9s_mb_2u(sch_1):page192_i37@pure_quanta.q_cap(chips)',
 PATH='I37',
 DRAWING='@S9S_MB_2U_LIB.S9S_MB_2U(SCH_1):PAGE324',
 PHYS_PAGE='192',
 XY='(200,-1525)',
 ROT='0',
 VER='1',
 PACK_TYPE='C0402',
 LOCATION='PC2210',
 CDS_LIB='pure_quanta',
 CDS_PART_NAME='Q_CAP_C0402-1UF,25V,10%,X6S,CHA',
 TOLERANCE='10%',
 MATERIAL='X6S',
 VOLTAGE='25V',
 ROOM='E1S1_P3V3_BOM1',
 VALUE='1UF',
 PRIM_FILE='./archive_libs/logical/q_cap/chips/chips.prt';

PART_NAME
 PC2211 'Q_CAP_C0402-1UF,25V,10%,EMPTY,A':
 ROOM='E1S1_P12V_MAM_MAM_BOM1';

SECTION_NUMBER 1
 '@S9S_MB_2U_LIB.S9S_MB_2U(SCH_1):PAGE324_I57@PURE_QUANTA.Q_CAP(CHIPS)':
 C_PATH='@s9s_mb_2u_lib.s9s_mb_2u(sch_1):page324_i57@pure_quanta.q_cap(chips)',
 P_PATH='@s9s_mb_2u_lib.s9s_mb_2u(sch_1):page192_i57@pure_quanta.q_cap(chips)',
 PATH='I57',
 DRAWING='@S9S_MB_2U_LIB.S9S_MB_2U(SCH_1):PAGE324',
 ROOM1='E1S1_P12V_MAM_TIC_BOM2',
 PHYS_PAGE='192',
 XY='(400,900)',
 ROT='1',
 VER='1',
 PACK_TYPE='C0402',
 LOCATION='PC2211',
 CDS_LIB='pure_quanta',
 CDS_PART_NAME='Q_CAP_C0402-1UF,25V,10%,EMPTY,A',
 TOLERANCE='10%',
 MATERIAL='EMPTY',
 VOLTAGE='25V',
 ROOM='E1S1_P12V_MAM_MAM_BOM1',
 VALUE='1UF',
 PRIM_FILE='./archive_libs/logical/q_cap/chips/chips.prt';

PART_NAME
 PC2212 'Q_CAP_C0402-1UF,25V,10%,X6S,CHA':
 ROOM='E1S1_P3V3_BOM1';

SECTION_NUMBER 1
 '@S9S_MB_2U_LIB.S9S_MB_2U(SCH_1):PAGE324_I38@PURE_QUANTA.Q_CAP(CHIPS)':
 C_PATH='@s9s_mb_2u_lib.s9s_mb_2u(sch_1):page324_i38@pure_quanta.q_cap(chips)',
 P_PATH='@s9s_mb_2u_lib.s9s_mb_2u(sch_1):page192_i38@pure_quanta.q_cap(chips)',
 PATH='I38',
 DRAWING='@S9S_MB_2U_LIB.S9S_MB_2U(SCH_1):PAGE324',
 PHYS_PAGE='192',
 XY='(425,-1825)',
 ROT='1',
 VER='1',
 PACK_TYPE='C0402',
 LOCATION='PC2212',
 CDS_LIB='pure_quanta',
 CDS_PART_NAME='Q_CAP_C0402-1UF,25V,10%,X6S,CHA',
 TOLERANCE='10%',
 MATERIAL='X6S',
 VOLTAGE='25V',
 ROOM='E1S1_P3V3_BOM1',
 VALUE='1UF',
 PRIM_FILE='./archive_libs/logical/q_cap/chips/chips.prt';

PART_NAME
 PC2213 'Q_CAP_C0402-0.01UF,50V,10%,EMPA':;

SECTION_NUMBER 1
 '@S9S_MB_2U_LIB.S9S_MB_2U(SCH_1):PAGE324_I42@PURE_QUANTA.Q_CAP(CHIPS)':
 C_PATH='@s9s_mb_2u_lib.s9s_mb_2u(sch_1):page324_i42@pure_quanta.q_cap(chips)',
 P_PATH='@s9s_mb_2u_lib.s9s_mb_2u(sch_1):page192_i42@pure_quanta.q_cap(chips)',
 PATH='I42',
 DRAWING='@S9S_MB_2U_LIB.S9S_MB_2U(SCH_1):PAGE324',
 PHYS_PAGE='192',
 XY='(2275,-1500)',
 ROT='0',
 VER='1',
 PACK_TYPE='C0402',
 LOCATION='PC2213',
 CDS_LIB='pure_quanta',
 CDS_PART_NAME='Q_CAP_C0402-0.01UF,50V,10%,EMPA',
 TOLERANCE='10%',
 MATERIAL='EMPTY',
 VOLTAGE='50V',
 VALUE='0.01UF',
 PRIM_FILE='./archive_libs/logical/q_cap/chips/chips.prt';

PART_NAME
 PC2214 'Q_CAP_C0402-0.01UF,50V,10%,EMPA':;

SECTION_NUMBER 1
 '@S9S_MB_2U_LIB.S9S_MB_2U(SCH_1):PAGE324_I69@PURE_QUANTA.Q_CAP(CHIPS)':
 C_PATH='@s9s_mb_2u_lib.s9s_mb_2u(sch_1):page324_i69@pure_quanta.q_cap(chips)',
 P_PATH='@s9s_mb_2u_lib.s9s_mb_2u(sch_1):page192_i69@pure_quanta.q_cap(chips)',
 PATH='I69',
 DRAWING='@S9S_MB_2U_LIB.S9S_MB_2U(SCH_1):PAGE324',
 PHYS_PAGE='192',
 XY='(2250,1225)',
 ROT='0',
 VER='1',
 PACK_TYPE='C0402',
 LOCATION='PC2214',
 CDS_LIB='pure_quanta',
 CDS_PART_NAME='Q_CAP_C0402-0.01UF,50V,10%,EMPA',
 TOLERANCE='10%',
 MATERIAL='EMPTY',
 VOLTAGE='50V',
 VALUE='0.01UF',
 PRIM_FILE='./archive_libs/logical/q_cap/chips/chips.prt';

PART_NAME
 PC2215 'Q_CAP_C0402-3900PF,50V,10%,EMPA':
 ROOM='E1S1_P12V_MAM_MAM_BOM1';

SECTION_NUMBER 1
 '@S9S_MB_2U_LIB.S9S_MB_2U(SCH_1):PAGE324_I66@PURE_QUANTA.Q_CAP(CHIPS)':
 C_PATH='@s9s_mb_2u_lib.s9s_mb_2u(sch_1):page324_i66@pure_quanta.q_cap(chips)',
 P_PATH='@s9s_mb_2u_lib.s9s_mb_2u(sch_1):page192_i66@pure_quanta.q_cap(chips)',
 PATH='I66',
 DRAWING='@S9S_MB_2U_LIB.S9S_MB_2U(SCH_1):PAGE324',
 ROOM1='E1S1_P12V_MAM_TIC_BOM2',
 PHYS_PAGE='192',
 XY='(2800,1000)',
 ROT='1',
 VER='1',
 PACK_TYPE='C0402',
 LOCATION='PC2215',
 CDS_LIB='pure_quanta',
 CDS_PART_NAME='Q_CAP_C0402-3900PF,50V,10%,EMPA',
 TOLERANCE='10%',
 MATERIAL='EMPTY',
 VOLTAGE='50V',
 ROOM='E1S1_P12V_MAM_MAM_BOM1',
 VALUE='3900PF',
 PRIM_FILE='./archive_libs/logical/q_cap/chips/chips.prt';

PART_NAME
 PC2216 'Q_CAP_C0402-6800PF,50V,10%,X7RA':
 ROOM='E1S1_P3V3_BOM1';

SECTION_NUMBER 1
 '@S9S_MB_2U_LIB.S9S_MB_2U(SCH_1):PAGE324_I45@PURE_QUANTA.Q_CAP(CHIPS)':
 C_PATH='@s9s_mb_2u_lib.s9s_mb_2u(sch_1):page324_i45@pure_quanta.q_cap(chips)',
 P_PATH='@s9s_mb_2u_lib.s9s_mb_2u(sch_1):page192_i45@pure_quanta.q_cap(chips)',
 PATH='I45',
 DRAWING='@S9S_MB_2U_LIB.S9S_MB_2U(SCH_1):PAGE324',
 PHYS_PAGE='192',
 XY='(3025,-1725)',
 ROT='1',
 VER='1',
 PACK_TYPE='C0402',
 LOCATION='PC2216',
 CDS_LIB='pure_quanta',
 CDS_PART_NAME='Q_CAP_C0402-6800PF,50V,10%,X7RA',
 TOLERANCE='10%',
 MATERIAL='X7R',
 VOLTAGE='50V',
 ROOM='E1S1_P3V3_BOM1',
 VALUE='6800PF',
 PRIM_FILE='./archive_libs/logical/q_cap/chips/chips.prt';

PART_NAME
 PC2217 'Q_CAP_0402-0.1UF,25V,10%,X7R,CA':;

SECTION_NUMBER 1
 '@S9S_MB_2U_LIB.S9S_MB_2U(SCH_1):PAGE324_I75@PURE_QUANTA.Q_CAP(CHIPS)':
 C_PATH='@s9s_mb_2u_lib.s9s_mb_2u(sch_1):page324_i75@pure_quanta.q_cap(chips)',
 P_PATH='@s9s_mb_2u_lib.s9s_mb_2u(sch_1):page192_i75@pure_quanta.q_cap(chips)',
 PATH='I75',
 DRAWING='@S9S_MB_2U_LIB.S9S_MB_2U(SCH_1):PAGE324',
 PHYS_PAGE='192',
 XY='(3150,1825)',
 ROT='0',
 VER='1',
 PACK_TYPE='0402',
 LOCATION='PC2217',
 CDS_LIB='pure_quanta',
 CDS_PART_NAME='Q_CAP_0402-0.1UF,25V,10%,X7R,CA',
 TOLERANCE='10%',
 MATERIAL='X7R',
 VOLTAGE='25V',
 VALUE='0.1UF',
 PRIM_FILE='./archive_libs/logical/q_cap/chips/chips.prt';

PART_NAME
 PC2218 'Q_CAP_0402-0.1UF,25V,10%,X7R,CA':;

SECTION_NUMBER 1
 '@S9S_MB_2U_LIB.S9S_MB_2U(SCH_1):PAGE324_I52@PURE_QUANTA.Q_CAP(CHIPS)':
 C_PATH='@s9s_mb_2u_lib.s9s_mb_2u(sch_1):page324_i52@pure_quanta.q_cap(chips)',
 P_PATH='@s9s_mb_2u_lib.s9s_mb_2u(sch_1):page192_i52@pure_quanta.q_cap(chips)',
 PATH='I52',
 DRAWING='@S9S_MB_2U_LIB.S9S_MB_2U(SCH_1):PAGE324',
 PHYS_PAGE='192',
 XY='(3200,-900)',
 ROT='0',
 VER='1',
 PACK_TYPE='0402',
 LOCATION='PC2218',
 CDS_LIB='pure_quanta',
 CDS_PART_NAME='Q_CAP_0402-0.1UF,25V,10%,X7R,CA',
 TOLERANCE='10%',
 MATERIAL='X7R',
 VOLTAGE='25V',
 VALUE='0.1UF',
 PRIM_FILE='./archive_libs/logical/q_cap/chips/chips.prt';

PART_NAME
 PC2219 'Q_CAP_C0805-10UF,16V,10%,X6S,CC':;

SECTION_NUMBER 1
 '@S9S_MB_2U_LIB.S9S_MB_2U(SCH_1):PAGE324_I78@PURE_QUANTA.Q_CAP(CHIPS)':
 C_PATH='@s9s_mb_2u_lib.s9s_mb_2u(sch_1):page324_i78@pure_quanta.q_cap(chips)',
 P_PATH='@s9s_mb_2u_lib.s9s_mb_2u(sch_1):page192_i78@pure_quanta.q_cap(chips)',
 PATH='I78',
 DRAWING='@S9S_MB_2U_LIB.S9S_MB_2U(SCH_1):PAGE324',
 PHYS_PAGE='192',
 XY='(3575,1825)',
 ROT='0',
 VER='1',
 PACK_TYPE='C0805',
 LOCATION='PC2219',
 CDS_LIB='pure_quanta',
 CDS_PART_NAME='Q_CAP_C0805-10UF,16V,10%,X6S,CB',
 TOLERANCE='10%',
 MATERIAL='X6S',
 VOLTAGE='16V',
 VALUE='10UF',
 PRIM_FILE='./archive_libs/logical/q_cap/chips/chips.prt';

PART_NAME
 PC2220 'Q_CAP_C0805-10UF,16V,10%,X6S,CB':;

SECTION_NUMBER 1
 '@S9S_MB_2U_LIB.S9S_MB_2U(SCH_1):PAGE324_I53@PURE_QUANTA.Q_CAP(CHIPS)':
 C_PATH='@s9s_mb_2u_lib.s9s_mb_2u(sch_1):page324_i53@pure_quanta.q_cap(chips)',
 P_PATH='@s9s_mb_2u_lib.s9s_mb_2u(sch_1):page192_i53@pure_quanta.q_cap(chips)',
 PATH='I53',
 DRAWING='@S9S_MB_2U_LIB.S9S_MB_2U(SCH_1):PAGE324',
 PHYS_PAGE='192',
 XY='(3775,-900)',
 ROT='0',
 VER='1',
 PACK_TYPE='C0805',
 LOCATION='PC2220',
 CDS_LIB='pure_quanta',
 CDS_PART_NAME='Q_CAP_C0805-10UF,16V,10%,X6S,CC',
 TOLERANCE='10%',
 MATERIAL='X6S',
 VOLTAGE='16V',
 VALUE='10UF',
 PRIM_FILE='./archive_libs/logical/q_cap/chips/chips.prt';

PART_NAME
 PC2221 'Q_CAP_C0402-1UF,25V,10%,X6S,CHA':;

SECTION_NUMBER 1
 '@S9S_MB_2U_LIB.S9S_MB_2U(SCH_1):PAGE268_I7@PURE_QUANTA.Q_CAP(CHIPS)':
 C_PATH='@s9s_mb_2u_lib.s9s_mb_2u(sch_1):page268_i7@pure_quanta.q_cap(chips)',
 P_PATH='@s9s_mb_2u_lib.s9s_mb_2u(sch_1):page282_i7@pure_quanta.q_cap(chips)',
 PATH='I7',
 DRAWING='@S9S_MB_2U_LIB.S9S_MB_2U(SCH_1):PAGE268',
 PHYS_PAGE='282',
 XY='(-8225,8725)',
 ROT='0',
 VER='1',
 PACK_TYPE='C0402',
 LOCATION='PC2221',
 SEC='1',
 CDS_LIB='pure_quanta',
 CDS_PART_NAME='Q_CAP_C0402-1UF,25V,10%,X6S,CHA',
 SEC_TYPE='C0402',
 TOLERANCE='10%',
 MATERIAL='X6S',
 VOLTAGE='25V',
 VALUE='1UF',
 PRIM_FILE='./archive_libs/logical/q_cap/chips/chips.prt';

PART_NAME
 PC2222 'Q_CAP_C0402-1UF,25V,10%,X6S,CHA':;

SECTION_NUMBER 1
 '@S9S_MB_2U_LIB.S9S_MB_2U(SCH_1):PAGE286_I10@PURE_QUANTA.Q_CAP(CHIPS)':
 C_PATH='@s9s_mb_2u_lib.s9s_mb_2u(sch_1):page286_i10@pure_quanta.q_cap(chips)',
 P_PATH='@s9s_mb_2u_lib.s9s_mb_2u(sch_1):page300_i10@pure_quanta.q_cap(chips)',
 PATH='I10',
 DRAWING='@S9S_MB_2U_LIB.S9S_MB_2U(SCH_1):PAGE286',
 PHYS_PAGE='300',
 XY='(3625,6100)',
 ROT='0',
 VER='1',
 PACK_TYPE='C0402',
 LOCATION='PC2222',
 SEC='1',
 CDS_LIB='pure_quanta',
 CDS_PART_NAME='Q_CAP_C0402-1UF,25V,10%,X6S,CHA',
 SEC_TYPE='C0402',
 TOLERANCE='10%',
 MATERIAL='X6S',
 VOLTAGE='25V',
 VALUE='1UF',
 PRIM_FILE='./archive_libs/logical/q_cap/chips/chips.prt';

PART_NAME
 PC2223 'Q_CAP_C0402-1UF,25V,10%,X6S,CHA':
 ROOM='HSC1_BOM1';

SECTION_NUMBER 1
 '@S9S_MB_2U_LIB.S9S_MB_2U(SCH_1):PAGE325_I4@PURE_QUANTA.Q_CAP(CHIPS)':
 C_PATH='@s9s_mb_2u_lib.s9s_mb_2u(sch_1):page325_i4@pure_quanta.q_cap(chips)',
 P_PATH='@s9s_mb_2u_lib.s9s_mb_2u(sch_1):page303_i4@pure_quanta.q_cap(chips)',
 PATH='I4',
 DRAWING='@S9S_MB_2U_LIB.S9S_MB_2U(SCH_1):PAGE325',
 PHYS_PAGE='303',
 XY='(-2750,-1175)',
 ROT='0',
 VER='1',
 PACK_TYPE='C0402',
 LOCATION='PC2223',
 CDS_LIB='pure_quanta',
 CDS_PART_NAME='Q_CAP_C0402-1UF,25V,10%,X6S,CHA',
 TOLERANCE='10%',
 MATERIAL='X6S',
 VOLTAGE='25V',
 ROOM='HSC1_BOM1',
 VALUE='1UF',
 PRIM_FILE='./archive_libs/logical/q_cap/chips/chips.prt';

PART_NAME
 PC2224 'Q_CAP_0402-220PF,50V,10%,EMPTYA':;

SECTION_NUMBER 1
 '@S9S_MB_2U_LIB.S9S_MB_2U(SCH_1):PAGE325_I23@PURE_QUANTA.Q_CAP(CHIPS)':
 C_PATH='@s9s_mb_2u_lib.s9s_mb_2u(sch_1):page325_i23@pure_quanta.q_cap(chips)',
 P_PATH='@s9s_mb_2u_lib.s9s_mb_2u(sch_1):page303_i23@pure_quanta.q_cap(chips)',
 PATH='I23',
 DRAWING='@S9S_MB_2U_LIB.S9S_MB_2U(SCH_1):PAGE325',
 PHYS_PAGE='303',
 XY='(-1875,950)',
 ROT='0',
 VER='1',
 PACK_TYPE='0402',
 LOCATION='PC2224',
 CDS_LIB='pure_quanta',
 CDS_PART_NAME='Q_CAP_0402-220PF,50V,10%,EMPTYA',
 TOLERANCE='10%',
 MATERIAL='EMPTY',
 VOLTAGE='50V',
 VALUE='220PF',
 PRIM_FILE='./archive_libs/logical/q_cap/chips/chips.prt';

PART_NAME
 PC2225 'Q_CAP_0402-220PF,50V,10%,EMPTYA':;

SECTION_NUMBER 1
 '@S9S_MB_2U_LIB.S9S_MB_2U(SCH_1):PAGE325_I2@PURE_QUANTA.Q_CAP(CHIPS)':
 C_PATH='@s9s_mb_2u_lib.s9s_mb_2u(sch_1):page325_i2@pure_quanta.q_cap(chips)',
 P_PATH='@s9s_mb_2u_lib.s9s_mb_2u(sch_1):page303_i2@pure_quanta.q_cap(chips)',
 PATH='I2',
 DRAWING='@S9S_MB_2U_LIB.S9S_MB_2U(SCH_1):PAGE325',
 PHYS_PAGE='303',
 XY='(-1875,-1825)',
 ROT='0',
 VER='1',
 PACK_TYPE='0402',
 LOCATION='PC2225',
 CDS_LIB='pure_quanta',
 CDS_PART_NAME='Q_CAP_0402-220PF,50V,10%,EMPTYA',
 TOLERANCE='10%',
 MATERIAL='EMPTY',
 VOLTAGE='50V',
 VALUE='220PF',
 PRIM_FILE='./archive_libs/logical/q_cap/chips/chips.prt';

PART_NAME
 PC2226 'Q_CAP_0402-0.068UF,16V,10%,X7RA':
 ROOM='HSC1_BOM1';

SECTION_NUMBER 1
 '@S9S_MB_2U_LIB.S9S_MB_2U(SCH_1):PAGE325_I48@PURE_QUANTA.Q_CAP(CHIPS)':
 C_PATH='@s9s_mb_2u_lib.s9s_mb_2u(sch_1):page325_i48@pure_quanta.q_cap(chips)',
 P_PATH='@s9s_mb_2u_lib.s9s_mb_2u(sch_1):page303_i48@pure_quanta.q_cap(chips)',
 PATH='I48',
 DRAWING='@S9S_MB_2U_LIB.S9S_MB_2U(SCH_1):PAGE325',
 PHYS_PAGE='303',
 XY='(1825,975)',
 ROT='0',
 VER='1',
 PACK_TYPE='0402',
 LOCATION='PC2226',
 CDS_LIB='pure_quanta',
 CDS_PART_NAME='Q_CAP_0402-0.068UF,16V,10%,X7RA',
 TOLERANCE='10%',
 MATERIAL='X7R',
 VOLTAGE='16V',
 ROOM='HSC1_BOM1',
 VALUE='0.068UF',
 PRIM_FILE='./archive_libs/logical/q_cap/chips/chips.prt';

PART_NAME
 PC2227 'Q_CAP_0402-0.068UF,16V,10%,X7RA':
 ROOM='HSC1_BOM1';

SECTION_NUMBER 1
 '@S9S_MB_2U_LIB.S9S_MB_2U(SCH_1):PAGE325_I38@PURE_QUANTA.Q_CAP(CHIPS)':
 C_PATH='@s9s_mb_2u_lib.s9s_mb_2u(sch_1):page325_i38@pure_quanta.q_cap(chips)',
 P_PATH='@s9s_mb_2u_lib.s9s_mb_2u(sch_1):page303_i38@pure_quanta.q_cap(chips)',
 PATH='I38',
 DRAWING='@S9S_MB_2U_LIB.S9S_MB_2U(SCH_1):PAGE325',
 PHYS_PAGE='303',
 XY='(1825,-1800)',
 ROT='0',
 VER='1',
 PACK_TYPE='0402',
 LOCATION='PC2227',
 CDS_LIB='pure_quanta',
 CDS_PART_NAME='Q_CAP_0402-0.068UF,16V,10%,X7RA',
 TOLERANCE='10%',
 MATERIAL='X7R',
 VOLTAGE='16V',
 ROOM='HSC1_BOM1',
 VALUE='0.068UF',
 PRIM_FILE='./archive_libs/logical/q_cap/chips/chips.prt';

PART_NAME
 PC2229 'Q_CAP_0402-0.22UF,16V,10%,X7R,A':
 ROOM='SCM_P12V_BOM2';

SECTION_NUMBER 1
 '@S9S_MB_2U_LIB.S9S_MB_2U(SCH_1):PAGE229_I8@PURE_QUANTA.Q_CAP(CHIPS)':
 C_PATH='@s9s_mb_2u_lib.s9s_mb_2u(sch_1):page229_i8@pure_quanta.q_cap(chips)',
 P_PATH='@s9s_mb_2u_lib.s9s_mb_2u(sch_1):page242_i8@pure_quanta.q_cap(chips)',
 PATH='I8',
 DRAWING='@S9S_MB_2U_LIB.S9S_MB_2U(SCH_1):PAGE229',
 PHYS_PAGE='242',
 XY='(-1125,-1750)',
 ROT='0',
 VER='1',
 PACK_TYPE='0402',
 LOCATION='PC2229',
 CDS_LIB='pure_quanta',
 CDS_PART_NAME='Q_CAP_0402-0.22UF,16V,10%,X7R,A',
 TOLERANCE='10%',
 MATERIAL='X7R',
 VOLTAGE='16V',
 ROOM='SCM_P12V_BOM2',
 VALUE='0.22UF',
 PRIM_FILE='./archive_libs/logical/q_cap/chips/chips.prt';

PART_NAME
 PC2230 'Q_CAP_C0402-1UF,25V,10%,X6S,CHA':;

SECTION_NUMBER 1
 '@S9S_MB_2U_LIB.S9S_MB_2U(SCH_1):PAGE229_I31@PURE_QUANTA.Q_CAP(CHIPS)':
 C_PATH='@s9s_mb_2u_lib.s9s_mb_2u(sch_1):page229_i31@pure_quanta.q_cap(chips)',
 P_PATH='@s9s_mb_2u_lib.s9s_mb_2u(sch_1):page242_i31@pure_quanta.q_cap(chips)',
 PATH='I31',
 DRAWING='@S9S_MB_2U_LIB.S9S_MB_2U(SCH_1):PAGE229',
 PHYS_PAGE='242',
 XY='(-275,2225)',
 ROT='0',
 VER='1',
 PACK_TYPE='C0402',
 LOCATION='PC2230',
 CDS_LIB='pure_quanta',
 CDS_PART_NAME='Q_CAP_C0402-1UF,25V,10%,X6S,CHA',
 TOLERANCE='10%',
 MATERIAL='X6S',
 VOLTAGE='25V',
 VALUE='1UF',
 PRIM_FILE='./archive_libs/logical/q_cap/chips/chips.prt';

PART_NAME
 PC2231 'Q_CAP_C0402-1UF,25V,10%,X6S,CHA':
 ROOM='SCM_P12V_BOM2';

SECTION_NUMBER 1
 '@S9S_MB_2U_LIB.S9S_MB_2U(SCH_1):PAGE229_I37@PURE_QUANTA.Q_CAP(CHIPS)':
 C_PATH='@s9s_mb_2u_lib.s9s_mb_2u(sch_1):page229_i37@pure_quanta.q_cap(chips)',
 P_PATH='@s9s_mb_2u_lib.s9s_mb_2u(sch_1):page242_i37@pure_quanta.q_cap(chips)',
 PATH='I37',
 DRAWING='@S9S_MB_2U_LIB.S9S_MB_2U(SCH_1):PAGE229',
 PHYS_PAGE='242',
 XY='(150,-850)',
 ROT='0',
 VER='1',
 PACK_TYPE='C0402',
 LOCATION='PC2231',
 CDS_LIB='pure_quanta',
 CDS_PART_NAME='Q_CAP_C0402-1UF,25V,10%,X6S,CHA',
 TOLERANCE='10%',
 MATERIAL='X6S',
 VOLTAGE='25V',
 ROOM='SCM_P12V_BOM2',
 VALUE='1UF',
 PRIM_FILE='./archive_libs/logical/q_cap/chips/chips.prt';

PART_NAME
 PC2232 'Q_CAP_C0402-0.047UF,25V,10%,X7A':
 ROOM='SCM_P12V_BOM2';

SECTION_NUMBER 1
 '@S9S_MB_2U_LIB.S9S_MB_2U(SCH_1):PAGE229_I33@PURE_QUANTA.Q_CAP(CHIPS)':
 C_PATH='@s9s_mb_2u_lib.s9s_mb_2u(sch_1):page229_i33@pure_quanta.q_cap(chips)',
 P_PATH='@s9s_mb_2u_lib.s9s_mb_2u(sch_1):page242_i33@pure_quanta.q_cap(chips)',
 PATH='I33',
 DRAWING='@S9S_MB_2U_LIB.S9S_MB_2U(SCH_1):PAGE229',
 PHYS_PAGE='242',
 XY='(225,-1925)',
 ROT='0',
 VER='1',
 PACK_TYPE='C0402',
 LOCATION='PC2232',
 CDS_LIB='pure_quanta',
 CDS_PART_NAME='Q_CAP_C0402-0.047UF,25V,10%,X7A',
 TOLERANCE='10%',
 MATERIAL='X7R',
 VOLTAGE='25V',
 ROOM='SCM_P12V_BOM2',
 VALUE='0.047UF',
 PRIM_FILE='./archive_libs/logical/q_cap/chips/chips.prt';

PART_NAME
 PC2233 'Q_CAP_C0402-1UF,25V,10%,EMPTY,A':
 ROOM='SCM_P12V_BOM1';

SECTION_NUMBER 1
 '@S9S_MB_2U_LIB.S9S_MB_2U(SCH_1):PAGE229_I68@PURE_QUANTA.Q_CAP(CHIPS)':
 C_PATH='@s9s_mb_2u_lib.s9s_mb_2u(sch_1):page229_i68@pure_quanta.q_cap(chips)',
 P_PATH='@s9s_mb_2u_lib.s9s_mb_2u(sch_1):page242_i68@pure_quanta.q_cap(chips)',
 PATH='I68',
 DRAWING='@S9S_MB_2U_LIB.S9S_MB_2U(SCH_1):PAGE229',
 PHYS_PAGE='242',
 XY='(400,1800)',
 ROT='0',
 VER='1',
 PACK_TYPE='C0402',
 LOCATION='PC2233',
 CDS_LIB='pure_quanta',
 CDS_PART_NAME='Q_CAP_C0402-1UF,25V,10%,EMPTY,A',
 TOLERANCE='10%',
 MATERIAL='EMPTY',
 VOLTAGE='25V',
 ROOM='SCM_P12V_BOM1',
 VALUE='1UF',
 PRIM_FILE='./archive_libs/logical/q_cap/chips/chips.prt';

PART_NAME
 PC2234 'Q_CAP_C0402-1UF,25V,10%,EMPTY,A':
 ROOM='SCM_P12V_BOM1';

SECTION_NUMBER 1
 '@S9S_MB_2U_LIB.S9S_MB_2U(SCH_1):PAGE229_I66@PURE_QUANTA.Q_CAP(CHIPS)':
 C_PATH='@s9s_mb_2u_lib.s9s_mb_2u(sch_1):page229_i66@pure_quanta.q_cap(chips)',
 P_PATH='@s9s_mb_2u_lib.s9s_mb_2u(sch_1):page242_i66@pure_quanta.q_cap(chips)',
 PATH='I66',
 DRAWING='@S9S_MB_2U_LIB.S9S_MB_2U(SCH_1):PAGE229',
 PHYS_PAGE='242',
 XY='(625,1500)',
 ROT='1',
 VER='1',
 PACK_TYPE='C0402',
 LOCATION='PC2234',
 CDS_LIB='pure_quanta',
 CDS_PART_NAME='Q_CAP_C0402-1UF,25V,10%,EMPTY,A',
 TOLERANCE='10%',
 MATERIAL='EMPTY',
 VOLTAGE='25V',
 ROOM='SCM_P12V_BOM1',
 VALUE='1UF',
 PRIM_FILE='./archive_libs/logical/q_cap/chips/chips.prt';

PART_NAME
 PC2235 'Q_CAP_C0402-100NF,50V,10%,X7R,A':
 ROOM='SCM_P12V_BOM2';

SECTION_NUMBER 1
 '@S9S_MB_2U_LIB.S9S_MB_2U(SCH_1):PAGE229_I42@PURE_QUANTA.Q_CAP(CHIPS)':
 C_PATH='@s9s_mb_2u_lib.s9s_mb_2u(sch_1):page229_i42@pure_quanta.q_cap(chips)',
 P_PATH='@s9s_mb_2u_lib.s9s_mb_2u(sch_1):page242_i42@pure_quanta.q_cap(chips)',
 PATH='I42',
 DRAWING='@S9S_MB_2U_LIB.S9S_MB_2U(SCH_1):PAGE229',
 PHYS_PAGE='242',
 XY='(2100,-2125)',
 ROT='0',
 VER='1',
 PACK_TYPE='C0402',
 LOCATION='PC2235',
 CDS_LIB='pure_quanta',
 CDS_PART_NAME='Q_CAP_C0402-100NF,50V,10%,X7R,A',
 TOLERANCE='10%',
 MATERIAL='X7R',
 VOLTAGE='50V',
 ROOM='SCM_P12V_BOM2',
 VALUE='100NF',
 PRIM_FILE='./archive_libs/logical/q_cap/chips/chips.prt';

PART_NAME
 PC2236 'Q_CAP_C0402-0.01UF,50V,10%,EMPA':;

SECTION_NUMBER 1
 '@S9S_MB_2U_LIB.S9S_MB_2U(SCH_1):PAGE229_I73@PURE_QUANTA.Q_CAP(CHIPS)':
 C_PATH='@s9s_mb_2u_lib.s9s_mb_2u(sch_1):page229_i73@pure_quanta.q_cap(chips)',
 P_PATH='@s9s_mb_2u_lib.s9s_mb_2u(sch_1):page242_i73@pure_quanta.q_cap(chips)',
 PATH='I73',
 DRAWING='@S9S_MB_2U_LIB.S9S_MB_2U(SCH_1):PAGE229',
 PHYS_PAGE='242',
 XY='(2475,1825)',
 ROT='0',
 VER='1',
 PACK_TYPE='C0402',
 LOCATION='PC2236',
 CDS_LIB='pure_quanta',
 CDS_PART_NAME='Q_CAP_C0402-0.01UF,50V,10%,EMPA',
 TOLERANCE='10%',
 MATERIAL='EMPTY',
 VOLTAGE='50V',
 VALUE='0.01UF',
 PRIM_FILE='./archive_libs/logical/q_cap/chips/chips.prt';

PART_NAME
 PC2237 'Q_CAP_C0402-3900PF,50V,10%,EMPA':
 ROOM='SCM_P12V_BOM1';

SECTION_NUMBER 1
 '@S9S_MB_2U_LIB.S9S_MB_2U(SCH_1):PAGE229_I75@PURE_QUANTA.Q_CAP(CHIPS)':
 C_PATH='@s9s_mb_2u_lib.s9s_mb_2u(sch_1):page229_i75@pure_quanta.q_cap(chips)',
 P_PATH='@s9s_mb_2u_lib.s9s_mb_2u(sch_1):page242_i75@pure_quanta.q_cap(chips)',
 PATH='I75',
 DRAWING='@S9S_MB_2U_LIB.S9S_MB_2U(SCH_1):PAGE229',
 PHYS_PAGE='242',
 XY='(3075,1600)',
 ROT='1',
 VER='1',
 PACK_TYPE='C0402',
 LOCATION='PC2237',
 CDS_LIB='pure_quanta',
 CDS_PART_NAME='Q_CAP_C0402-3900PF,50V,10%,EMPA',
 TOLERANCE='10%',
 MATERIAL='EMPTY',
 VOLTAGE='50V',
 ROOM='SCM_P12V_BOM1',
 VALUE='3900PF',
 PRIM_FILE='./archive_libs/logical/q_cap/chips/chips.prt';

PART_NAME
 PC2238 'Q_CAP_0402-0.1UF,25V,10%,X7R,CA':;

SECTION_NUMBER 1
 '@S9S_MB_2U_LIB.S9S_MB_2U(SCH_1):PAGE229_I83@PURE_QUANTA.Q_CAP(CHIPS)':
 C_PATH='@s9s_mb_2u_lib.s9s_mb_2u(sch_1):page229_i83@pure_quanta.q_cap(chips)',
 P_PATH='@s9s_mb_2u_lib.s9s_mb_2u(sch_1):page242_i83@pure_quanta.q_cap(chips)',
 PATH='I83',
 DRAWING='@S9S_MB_2U_LIB.S9S_MB_2U(SCH_1):PAGE229',
 PHYS_PAGE='242',
 XY='(3375,2425)',
 ROT='0',
 VER='1',
 PACK_TYPE='0402',
 LOCATION='PC2238',
 CDS_LIB='pure_quanta',
 CDS_PART_NAME='Q_CAP_0402-0.1UF,25V,10%,X7R,CA',
 TOLERANCE='10%',
 MATERIAL='X7R',
 VOLTAGE='25V',
 VALUE='0.1UF',
 PRIM_FILE='./archive_libs/logical/q_cap/chips/chips.prt';

PART_NAME
 PC2239 'Q_CAP_C0603-2.2UF,16V,20%,X7R,A':
 ROOM='SCM_P12V_BOM2';

SECTION_NUMBER 1
 '@S9S_MB_2U_LIB.S9S_MB_2U(SCH_1):PAGE229_I53@PURE_QUANTA.Q_CAP(CHIPS)':
 C_PATH='@s9s_mb_2u_lib.s9s_mb_2u(sch_1):page229_i53@pure_quanta.q_cap(chips)',
 P_PATH='@s9s_mb_2u_lib.s9s_mb_2u(sch_1):page242_i53@pure_quanta.q_cap(chips)',
 PATH='I53',
 DRAWING='@S9S_MB_2U_LIB.S9S_MB_2U(SCH_1):PAGE229',
 PHYS_PAGE='242',
 XY='(3550,-1775)',
 ROT='0',
 VER='1',
 PACK_TYPE='C0603',
 LOCATION='PC2239',
 CDS_LIB='pure_quanta',
 CDS_PART_NAME='Q_CAP_C0603-2.2UF,16V,20%,X7R,A',
 TOLERANCE='20%',
 MATERIAL='X7R',
 VOLTAGE='16V',
 ROOM='SCM_P12V_BOM2',
 VALUE='2.2UF',
 PRIM_FILE='./archive_libs/logical/q_cap/chips/chips.prt';

PART_NAME
 PC2240 'Q_CAP_C0805-10UF,16V,10%,X6S,CC':;

SECTION_NUMBER 1
 '@S9S_MB_2U_LIB.S9S_MB_2U(SCH_1):PAGE229_I84@PURE_QUANTA.Q_CAP(CHIPS)':
 C_PATH='@s9s_mb_2u_lib.s9s_mb_2u(sch_1):page229_i84@pure_quanta.q_cap(chips)',
 P_PATH='@s9s_mb_2u_lib.s9s_mb_2u(sch_1):page242_i84@pure_quanta.q_cap(chips)',
 PATH='I84',
 DRAWING='@S9S_MB_2U_LIB.S9S_MB_2U(SCH_1):PAGE229',
 PHYS_PAGE='242',
 XY='(3800,2425)',
 ROT='0',
 VER='1',
 PACK_TYPE='C0805',
 LOCATION='PC2240',
 CDS_LIB='pure_quanta',
 CDS_PART_NAME='Q_CAP_C0805-10UF,16V,10%,X6S,CB',
 TOLERANCE='10%',
 MATERIAL='X6S',
 VOLTAGE='16V',
 VALUE='10UF',
 PRIM_FILE='./archive_libs/logical/q_cap/chips/chips.prt';

PART_NAME
 PC2241 'Q_CAP_0402-0.1UF,25V,10%,X7R,CA':
 ROOM='SCM_P12V_BOM2';

SECTION_NUMBER 1
 '@S9S_MB_2U_LIB.S9S_MB_2U(SCH_1):PAGE229_I57@PURE_QUANTA.Q_CAP(CHIPS)':
 C_PATH='@s9s_mb_2u_lib.s9s_mb_2u(sch_1):page229_i57@pure_quanta.q_cap(chips)',
 P_PATH='@s9s_mb_2u_lib.s9s_mb_2u(sch_1):page242_i57@pure_quanta.q_cap(chips)',
 PATH='I57',
 DRAWING='@S9S_MB_2U_LIB.S9S_MB_2U(SCH_1):PAGE229',
 PHYS_PAGE='242',
 XY='(3900,-925)',
 ROT='2',
 VER='1',
 PACK_TYPE='0402',
 LOCATION='PC2241',
 CDS_LIB='pure_quanta',
 CDS_PART_NAME='Q_CAP_0402-0.1UF,25V,10%,X7R,CA',
 TOLERANCE='10%',
 MATERIAL='X7R',
 VOLTAGE='25V',
 ROOM='SCM_P12V_BOM2',
 VALUE='0.1UF',
 PRIM_FILE='./archive_libs/logical/q_cap/chips/chips.prt';

PART_NAME
 PC2242 'Q_CAP_C0805-22UF,16V,20%,X6S,CC':;

SECTION_NUMBER 1
 '@S9S_MB_2U_LIB.S9S_MB_2U(SCH_1):PAGE229_I88@PURE_QUANTA.Q_CAP(CHIPS)':
 C_PATH='@s9s_mb_2u_lib.s9s_mb_2u(sch_1):page229_i88@pure_quanta.q_cap(chips)',
 P_PATH='@s9s_mb_2u_lib.s9s_mb_2u(sch_1):page242_i88@pure_quanta.q_cap(chips)',
 PATH='I88',
 DRAWING='@S9S_MB_2U_LIB.S9S_MB_2U(SCH_1):PAGE229',
 PHYS_PAGE='242',
 XY='(4200,2425)',
 ROT='0',
 VER='1',
 PACK_TYPE='C0805',
 LOCATION='PC2242',
 CDS_LIB='pure_quanta',
 CDS_PART_NAME='Q_CAP_C0805-22UF,16V,20%,X6S,CC',
 TOLERANCE='20%',
 MATERIAL='X6S',
 VOLTAGE='16V',
 VALUE='22UF',
 PRIM_FILE='./archive_libs/logical/q_cap/chips/chips.prt';

PART_NAME
 PC2260 'Q_CAP_C0805-22UF,16V,20%,X6S,CA':;

SECTION_NUMBER 1
 '@S9S_MB_2U_LIB.S9S_MB_2U(SCH_1):PAGE245_I100@PURE_QUANTA.Q_CAP(CHIPS)':
 C_PATH='@s9s_mb_2u_lib.s9s_mb_2u(sch_1):page245_i100@pure_quanta.q_cap(chips)',
 P_PATH='@s9s_mb_2u_lib.s9s_mb_2u(sch_1):page259_i100@pure_quanta.q_cap(chips)',
 PATH='I100',
 DRAWING='@S9S_MB_2U_LIB.S9S_MB_2U(SCH_1):PAGE245',
 PHYS_PAGE='259',
 XY='(-4050,200)',
 ROT='0',
 VER='1',
 PACK_TYPE='C0805',
 LOCATION='PC2260',
 CDS_LIB='pure_quanta',
 CDS_PART_NAME='Q_CAP_C0805-22UF,16V,20%,X6S,CA',
 TOLERANCE='20%',
 MATERIAL='X6S',
 VOLTAGE='16V',
 VALUE='22UF',
 PRIM_FILE='./archive_libs/logical/q_cap/chips/chips.prt';

PART_NAME
 PC2261 'Q_CAP_C0805-22UF,16V,20%,X6S,CA':;

SECTION_NUMBER 1
 '@S9S_MB_2U_LIB.S9S_MB_2U(SCH_1):PAGE245_I101@PURE_QUANTA.Q_CAP(CHIPS)':
 C_PATH='@s9s_mb_2u_lib.s9s_mb_2u(sch_1):page245_i101@pure_quanta.q_cap(chips)',
 P_PATH='@s9s_mb_2u_lib.s9s_mb_2u(sch_1):page259_i101@pure_quanta.q_cap(chips)',
 PATH='I101',
 DRAWING='@S9S_MB_2U_LIB.S9S_MB_2U(SCH_1):PAGE245',
 PHYS_PAGE='259',
 XY='(-3725,200)',
 ROT='0',
 VER='1',
 PACK_TYPE='C0805',
 LOCATION='PC2261',
 CDS_LIB='pure_quanta',
 CDS_PART_NAME='Q_CAP_C0805-22UF,16V,20%,X6S,CA',
 TOLERANCE='20%',
 MATERIAL='X6S',
 VOLTAGE='16V',
 VALUE='22UF',
 PRIM_FILE='./archive_libs/logical/q_cap/chips/chips.prt';

PART_NAME
 PC2262 'Q_CAP_C0805-22UF,16V,20%,X6S,CA':;

SECTION_NUMBER 1
 '@S9S_MB_2U_LIB.S9S_MB_2U(SCH_1):PAGE245_I105@PURE_QUANTA.Q_CAP(CHIPS)':
 C_PATH='@s9s_mb_2u_lib.s9s_mb_2u(sch_1):page245_i105@pure_quanta.q_cap(chips)',
 P_PATH='@s9s_mb_2u_lib.s9s_mb_2u(sch_1):page259_i105@pure_quanta.q_cap(chips)',
 PATH='I105',
 DRAWING='@S9S_MB_2U_LIB.S9S_MB_2U(SCH_1):PAGE245',
 PHYS_PAGE='259',
 XY='(-3400,200)',
 ROT='0',
 VER='1',
 PACK_TYPE='C0805',
 LOCATION='PC2262',
 CDS_LIB='pure_quanta',
 CDS_PART_NAME='Q_CAP_C0805-22UF,16V,20%,X6S,CA',
 TOLERANCE='20%',
 MATERIAL='X6S',
 VOLTAGE='16V',
 VALUE='22UF',
 PRIM_FILE='./archive_libs/logical/q_cap/chips/chips.prt';

PART_NAME
 PC2263 'Q_CAP_C0805-22UF,16V,20%,X6S,CA':;

SECTION_NUMBER 1
 '@S9S_MB_2U_LIB.S9S_MB_2U(SCH_1):PAGE245_I107@PURE_QUANTA.Q_CAP(CHIPS)':
 C_PATH='@s9s_mb_2u_lib.s9s_mb_2u(sch_1):page245_i107@pure_quanta.q_cap(chips)',
 P_PATH='@s9s_mb_2u_lib.s9s_mb_2u(sch_1):page259_i107@pure_quanta.q_cap(chips)',
 PATH='I107',
 DRAWING='@S9S_MB_2U_LIB.S9S_MB_2U(SCH_1):PAGE245',
 PHYS_PAGE='259',
 XY='(-3075,200)',
 ROT='0',
 VER='1',
 PACK_TYPE='C0805',
 LOCATION='PC2263',
 CDS_LIB='pure_quanta',
 CDS_PART_NAME='Q_CAP_C0805-22UF,16V,20%,X6S,CA',
 TOLERANCE='20%',
 MATERIAL='X6S',
 VOLTAGE='16V',
 VALUE='22UF',
 PRIM_FILE='./archive_libs/logical/q_cap/chips/chips.prt';

PART_NAME
 PC2277 'Q_CAP_0402-0.01UF,25V,10%,X7R,A':;

SECTION_NUMBER 1
 '@S9S_MB_2U_LIB.S9S_MB_2U(SCH_1):PAGE286_I40@PURE_QUANTA.Q_CAP(CHIPS)':
 C_PATH='@s9s_mb_2u_lib.s9s_mb_2u(sch_1):page286_i40@pure_quanta.q_cap(chips)',
 P_PATH='@s9s_mb_2u_lib.s9s_mb_2u(sch_1):page300_i40@pure_quanta.q_cap(chips)',
 PATH='I40',
 DRAWING='@S9S_MB_2U_LIB.S9S_MB_2U(SCH_1):PAGE286',
 PHYS_PAGE='300',
 XY='(8775,6100)',
 ROT='0',
 VER='1',
 PACK_TYPE='0402',
 LOCATION='PC2277',
 CDS_LIB='pure_quanta',
 CDS_PART_NAME='Q_CAP_0402-0.01UF,25V,10%,X7R,A',
 TOLERANCE='10%',
 MATERIAL='X7R',
 VOLTAGE='25V',
 VALUE='0.01UF',
 PRIM_FILE='./archive_libs/logical/q_cap/chips/chips.prt';

PART_NAME
 PC2279 'Q_CAP_0402-0.01UF,25V,10%,X7R,A':;

SECTION_NUMBER 1
 '@S9S_MB_2U_LIB.S9S_MB_2U(SCH_1):PAGE248_I37@PURE_QUANTA.Q_CAP(CHIPS)':
 C_PATH='@s9s_mb_2u_lib.s9s_mb_2u(sch_1):page248_i37@pure_quanta.q_cap(chips)',
 P_PATH='@s9s_mb_2u_lib.s9s_mb_2u(sch_1):page262_i37@pure_quanta.q_cap(chips)',
 PATH='I37',
 DRAWING='@S9S_MB_2U_LIB.S9S_MB_2U(SCH_1):PAGE248',
 PHYS_PAGE='262',
 XY='(2325,-1250)',
 ROT='0',
 VER='1',
 PACK_TYPE='0402',
 LOCATION='PC2279',
 CDS_LIB='pure_quanta',
 CDS_PART_NAME='Q_CAP_0402-0.01UF,25V,10%,X7R,A',
 TOLERANCE='10%',
 MATERIAL='X7R',
 VOLTAGE='25V',
 VALUE='0.01UF',
 PRIM_FILE='./archive_libs/logical/q_cap/chips/chips.prt';

PART_NAME
 PC2280 'Q_CAP_C0805-10UF,16V,10%,X6S,CC':;

SECTION_NUMBER 1
 '@S9S_MB_2U_LIB.S9S_MB_2U(SCH_1):PAGE324_I79@PURE_QUANTA.Q_CAP(CHIPS)':
 C_PATH='@s9s_mb_2u_lib.s9s_mb_2u(sch_1):page324_i79@pure_quanta.q_cap(chips)',
 P_PATH='@s9s_mb_2u_lib.s9s_mb_2u(sch_1):page192_i79@pure_quanta.q_cap(chips)',
 PATH='I79',
 DRAWING='@S9S_MB_2U_LIB.S9S_MB_2U(SCH_1):PAGE324',
 PHYS_PAGE='192',
 XY='(3975,1825)',
 ROT='0',
 VER='1',
 PACK_TYPE='C0805',
 LOCATION='PC2280',
 CDS_LIB='pure_quanta',
 CDS_PART_NAME='Q_CAP_C0805-10UF,16V,10%,X6S,CB',
 TOLERANCE='10%',
 MATERIAL='X6S',
 VOLTAGE='16V',
 VALUE='10UF',
 PRIM_FILE='./archive_libs/logical/q_cap/chips/chips.prt';

PART_NAME
 PC2281 'Q_CAP_C0402-0.047UF,25V,10%,X7A':
 ROOM='E1S1_P12V_MPS_MAM_BOM3';

SECTION_NUMBER 1
 '@S9S_MB_2U_LIB.S9S_MB_2U(SCH_1):PAGE323_I47@PURE_QUANTA.Q_CAP(CHIPS)':
 C_PATH='@s9s_mb_2u_lib.s9s_mb_2u(sch_1):page323_i47@pure_quanta.q_cap(chips)',
 P_PATH='@s9s_mb_2u_lib.s9s_mb_2u(sch_1):page193_i47@pure_quanta.q_cap(chips)',
 PATH='I47',
 DRAWING='@S9S_MB_2U_LIB.S9S_MB_2U(SCH_1):PAGE323',
 ROOM1='E1S1_P12V_MPS_TIC_BOM4',
 PHYS_PAGE='193',
 XY='(-900,500)',
 ROT='0',
 VER='1',
 PACK_TYPE='C0402',
 LOCATION='PC2281',
 CDS_LIB='pure_quanta',
 CDS_PART_NAME='Q_CAP_C0402-0.047UF,25V,10%,X7A',
 TOLERANCE='10%',
 MATERIAL='X7R',
 VOLTAGE='25V',
 ROOM='E1S1_P12V_MPS_MAM_BOM3',
 VALUE='0.047UF',
 PRIM_FILE='./archive_libs/logical/q_cap/chips/chips.prt';

PART_NAME
 PC2282 'Q_CAP_0402-0.01UF,25V,10%,X7R,A':;

SECTION_NUMBER 1
 '@S9S_MB_2U_LIB.S9S_MB_2U(SCH_1):PAGE285_I32@PURE_QUANTA.Q_CAP(CHIPS)':
 C_PATH='@s9s_mb_2u_lib.s9s_mb_2u(sch_1):page285_i32@pure_quanta.q_cap(chips)',
 P_PATH='@s9s_mb_2u_lib.s9s_mb_2u(sch_1):page299_i32@pure_quanta.q_cap(chips)',
 PATH='I32',
 DRAWING='@S9S_MB_2U_LIB.S9S_MB_2U(SCH_1):PAGE285',
 PHYS_PAGE='299',
 XY='(-4400,1925)',
 ROT='0',
 VER='1',
 PACK_TYPE='0402',
 LOCATION='PC2282',
 CDS_LIB='pure_quanta',
 CDS_PART_NAME='Q_CAP_0402-0.01UF,25V,10%,X7R,A',
 TOLERANCE='10%',
 MATERIAL='X7R',
 VOLTAGE='25V',
 VALUE='0.01UF',
 PRIM_FILE='./archive_libs/logical/q_cap/chips/chips.prt';

PART_NAME
 PC2286 'Q_CAP_0402-1000PF,50V,5%,EMPTYA':;

SECTION_NUMBER 1
 '@S9S_MB_2U_LIB.S9S_MB_2U(SCH_1):PAGE248_I8@PURE_QUANTA.Q_CAP(CHIPS)':
 C_PATH='@s9s_mb_2u_lib.s9s_mb_2u(sch_1):page248_i8@pure_quanta.q_cap(chips)',
 P_PATH='@s9s_mb_2u_lib.s9s_mb_2u(sch_1):page262_i8@pure_quanta.q_cap(chips)',
 PATH='I8',
 DRAWING='@S9S_MB_2U_LIB.S9S_MB_2U(SCH_1):PAGE248',
 PHYS_PAGE='262',
 XY='(-2450,-575)',
 ROT='2',
 VER='1',
 PACK_TYPE='0402',
 LOCATION='PC2286',
 CDS_LIB='pure_quanta',
 CDS_PART_NAME='Q_CAP_0402-1000PF,50V,5%,EMPTYA',
 TOLERANCE='5%',
 MATERIAL='EMPTY',
 VOLTAGE='50V',
 VALUE='1000PF',
 PRIM_FILE='./archive_libs/logical/q_cap/chips/chips.prt';

PART_NAME
 PC2336 'Q_CAPP_SMLF-330UF,2.5V,+10/-35A':;

SECTION_NUMBER 1
 '@S9S_MB_2U_LIB.S9S_MB_2U(SCH_1):PAGE253_I60@PURE_QUANTA.Q_CAPP(CHIPS)':
 C_PATH='@s9s_mb_2u_lib.s9s_mb_2u(sch_1):page253_i60@pure_quanta.q_capp(chips)',
 P_PATH='@s9s_mb_2u_lib.s9s_mb_2u(sch_1):page267_i60@pure_quanta.q_capp(chips)',
 PATH='I60',
 DRAWING='@S9S_MB_2U_LIB.S9S_MB_2U(SCH_1):PAGE253',
 PHYS_PAGE='267',
 XY='(2525,-1425)',
 ROT='0',
 VER='1',
 PACK_TYPE='SMLF',
 LOCATION='PC2336',
 CDS_LIB='pure_quanta',
 CDS_PART_NAME='Q_CAPP_SMLF-330UF,2.5V,+10/-35A',
 TOLERANCE='+10/-35%',
 MATERIAL='EMPTY',
 VOLTAGE='2.5V',
 VALUE='330UF',
 PRIM_FILE='./archive_libs/logical/q_capp/chips/chips.prt';

PART_NAME
 PC2340 'Q_CAP_C0402-560PF,50V,10%,X7R,A':
 ROOM='SCM_P12V_BOM2';

SECTION_NUMBER 1
 '@S9S_MB_2U_LIB.S9S_MB_2U(SCH_1):PAGE229_I7@PURE_QUANTA.Q_CAP(CHIPS)':
 C_PATH='@s9s_mb_2u_lib.s9s_mb_2u(sch_1):page229_i7@pure_quanta.q_cap(chips)',
 P_PATH='@s9s_mb_2u_lib.s9s_mb_2u(sch_1):page242_i7@pure_quanta.q_cap(chips)',
 PATH='I7',
 DRAWING='@S9S_MB_2U_LIB.S9S_MB_2U(SCH_1):PAGE229',
 PHYS_PAGE='242',
 XY='(-250,-2150)',
 ROT='0',
 VER='1',
 PACK_TYPE='C0402',
 LOCATION='PC2340',
 CDS_LIB='pure_quanta',
 CDS_PART_NAME='Q_CAP_C0402-560PF,50V,10%,X7R,A',
 TOLERANCE='10%',
 MATERIAL='X7R',
 VOLTAGE='50V',
 ROOM='SCM_P12V_BOM2',
 VALUE='560PF',
 PRIM_FILE='./archive_libs/logical/q_cap/chips/chips.prt';

PART_NAME
 PC2341 'Q_CAP_C0402-560PF,50V,10%,X7R,A':
 ROOM='E1S1_P12V_MPS_MAM_BOM3';

SECTION_NUMBER 1
 '@S9S_MB_2U_LIB.S9S_MB_2U(SCH_1):PAGE323_I42@PURE_QUANTA.Q_CAP(CHIPS)':
 C_PATH='@s9s_mb_2u_lib.s9s_mb_2u(sch_1):page323_i42@pure_quanta.q_cap(chips)',
 P_PATH='@s9s_mb_2u_lib.s9s_mb_2u(sch_1):page193_i42@pure_quanta.q_cap(chips)',
 PATH='I42',
 DRAWING='@S9S_MB_2U_LIB.S9S_MB_2U(SCH_1):PAGE323',
 ROOM1='E1S1_P12V_MPS_TIC_BOM4',
 PHYS_PAGE='193',
 XY='(-1425,275)',
 ROT='0',
 VER='1',
 PACK_TYPE='C0402',
 LOCATION='PC2341',
 CDS_LIB='pure_quanta',
 CDS_PART_NAME='Q_CAP_C0402-560PF,50V,10%,X7R,A',
 TOLERANCE='10%',
 MATERIAL='X7R',
 VOLTAGE='50V',
 ROOM='E1S1_P12V_MPS_MAM_BOM3',
 VALUE='560PF',
 PRIM_FILE='./archive_libs/logical/q_cap/chips/chips.prt';

PART_NAME
 PC2342 'Q_CAP_C0805-22UF,16V,20%,X6S,CA':;

SECTION_NUMBER 1
 '@S9S_MB_2U_LIB.S9S_MB_2U(SCH_1):PAGE245_I108@PURE_QUANTA.Q_CAP(CHIPS)':
 C_PATH='@s9s_mb_2u_lib.s9s_mb_2u(sch_1):page245_i108@pure_quanta.q_cap(chips)',
 P_PATH='@s9s_mb_2u_lib.s9s_mb_2u(sch_1):page259_i108@pure_quanta.q_cap(chips)',
 PATH='I108',
 DRAWING='@S9S_MB_2U_LIB.S9S_MB_2U(SCH_1):PAGE245',
 PHYS_PAGE='259',
 XY='(-2750,200)',
 ROT='0',
 VER='1',
 PACK_TYPE='C0805',
 LOCATION='PC2342',
 CDS_LIB='pure_quanta',
 CDS_PART_NAME='Q_CAP_C0805-22UF,16V,20%,X6S,CA',
 TOLERANCE='20%',
 MATERIAL='X6S',
 VOLTAGE='16V',
 VALUE='22UF',
 PRIM_FILE='./archive_libs/logical/q_cap/chips/chips.prt';

PART_NAME
 PC2343 'Q_CAP_C0805-22UF,16V,20%,X6S,CA':;

SECTION_NUMBER 1
 '@S9S_MB_2U_LIB.S9S_MB_2U(SCH_1):PAGE245_I111@PURE_QUANTA.Q_CAP(CHIPS)':
 C_PATH='@s9s_mb_2u_lib.s9s_mb_2u(sch_1):page245_i111@pure_quanta.q_cap(chips)',
 P_PATH='@s9s_mb_2u_lib.s9s_mb_2u(sch_1):page259_i111@pure_quanta.q_cap(chips)',
 PATH='I111',
 DRAWING='@S9S_MB_2U_LIB.S9S_MB_2U(SCH_1):PAGE245',
 PHYS_PAGE='259',
 XY='(-2425,200)',
 ROT='0',
 VER='1',
 PACK_TYPE='C0805',
 LOCATION='PC2343',
 CDS_LIB='pure_quanta',
 CDS_PART_NAME='Q_CAP_C0805-22UF,16V,20%,X6S,CA',
 TOLERANCE='20%',
 MATERIAL='X6S',
 VOLTAGE='16V',
 VALUE='22UF',
 PRIM_FILE='./archive_libs/logical/q_cap/chips/chips.prt';

PART_NAME
 PC2344 'Q_CAP_C0805-22UF,16V,20%,X6S,CA':;

SECTION_NUMBER 1
 '@S9S_MB_2U_LIB.S9S_MB_2U(SCH_1):PAGE245_I112@PURE_QUANTA.Q_CAP(CHIPS)':
 C_PATH='@s9s_mb_2u_lib.s9s_mb_2u(sch_1):page245_i112@pure_quanta.q_cap(chips)',
 P_PATH='@s9s_mb_2u_lib.s9s_mb_2u(sch_1):page259_i112@pure_quanta.q_cap(chips)',
 PATH='I112',
 DRAWING='@S9S_MB_2U_LIB.S9S_MB_2U(SCH_1):PAGE245',
 PHYS_PAGE='259',
 XY='(-2100,200)',
 ROT='0',
 VER='1',
 PACK_TYPE='C0805',
 LOCATION='PC2344',
 CDS_LIB='pure_quanta',
 CDS_PART_NAME='Q_CAP_C0805-22UF,16V,20%,X6S,CA',
 TOLERANCE='20%',
 MATERIAL='X6S',
 VOLTAGE='16V',
 VALUE='22UF',
 PRIM_FILE='./archive_libs/logical/q_cap/chips/chips.prt';

PART_NAME
 PC2345 'Q_CAPP_THLF-270UF,16V,20%,OSCOA':;

SECTION_NUMBER 1
 '@S9S_MB_2U_LIB.S9S_MB_2U(SCH_1):PAGE253_I95@PURE_QUANTA.Q_CAPP(CHIPS)':
 C_PATH='@s9s_mb_2u_lib.s9s_mb_2u(sch_1):page253_i95@pure_quanta.q_capp(chips)',
 P_PATH='@s9s_mb_2u_lib.s9s_mb_2u(sch_1):page267_i95@pure_quanta.q_capp(chips)',
 PATH='I95',
 DRAWING='@S9S_MB_2U_LIB.S9S_MB_2U(SCH_1):PAGE253',
 PHYS_PAGE='267',
 XY='(3950,1825)',
 ROT='0',
 VER='1',
 PACK_TYPE='THLF',
 LOCATION='PC2345',
 CDS_LIB='pure_quanta',
 CDS_PART_NAME='Q_CAPP_THLF-270UF,16V,20%,OSCOA',
 TOLERANCE='20%',
 MATERIAL='OSCON',
 VOLTAGE='16V',
 VALUE='270UF',
 PRIM_FILE='./archive_libs/logical/q_capp/chips/chips.prt';

PART_NAME
 PC2346 'Q_CAPP_THLF-270UF,16V,20%,OSCOA':;

SECTION_NUMBER 1
 '@S9S_MB_2U_LIB.S9S_MB_2U(SCH_1):PAGE271_I96@PURE_QUANTA.Q_CAPP(CHIPS)':
 C_PATH='@s9s_mb_2u_lib.s9s_mb_2u(sch_1):page271_i96@pure_quanta.q_capp(chips)',
 P_PATH='@s9s_mb_2u_lib.s9s_mb_2u(sch_1):page285_i96@pure_quanta.q_capp(chips)',
 PATH='I96',
 DRAWING='@S9S_MB_2U_LIB.S9S_MB_2U(SCH_1):PAGE271',
 PHYS_PAGE='285',
 XY='(4100,2250)',
 ROT='0',
 VER='1',
 PACK_TYPE='THLF',
 LOCATION='PC2346',
 CDS_LIB='pure_quanta',
 CDS_PART_NAME='Q_CAPP_THLF-270UF,16V,20%,OSCOA',
 TOLERANCE='20%',
 MATERIAL='OSCON',
 VOLTAGE='16V',
 VALUE='270UF',
 PRIM_FILE='./archive_libs/logical/q_capp/chips/chips.prt';

PART_NAME
 PC2347 'Q_CAP_0402-1NF,50V,10%,EMPTY,CA':;

SECTION_NUMBER 1
 '@S9S_MB_2U_LIB.S9S_MB_2U(SCH_1):PAGE301_I29@PURE_QUANTA.Q_CAP(CHIPS)':
 C_PATH='@s9s_mb_2u_lib.s9s_mb_2u(sch_1):page301_i29@pure_quanta.q_cap(chips)',
 P_PATH='@s9s_mb_2u_lib.s9s_mb_2u(sch_1):page302_i29@pure_quanta.q_cap(chips)',
 PATH='I29',
 DRAWING='@S9S_MB_2U_LIB.S9S_MB_2U(SCH_1):PAGE301',
 PHYS_PAGE='302',
 XY='(-2225,775)',
 ROT='0',
 VER='1',
 PACK_TYPE='0402',
 LOCATION='PC2347',
 CDS_LIB='pure_quanta',
 CDS_PART_NAME='Q_CAP_0402-1NF,50V,10%,EMPTY,CA',
 TOLERANCE='10%',
 MATERIAL='EMPTY',
 VOLTAGE='50V',
 VALUE='1NF',
 PRIM_FILE='./archive_libs/logical/q_cap/chips/chips.prt';

PART_NAME
 PC2348 'Q_CAP_0402-1NF,50V,10%,EMPTY,CA':;

SECTION_NUMBER 1
 '@S9S_MB_2U_LIB.S9S_MB_2U(SCH_1):PAGE301_I11@PURE_QUANTA.Q_CAP(CHIPS)':
 C_PATH='@s9s_mb_2u_lib.s9s_mb_2u(sch_1):page301_i11@pure_quanta.q_cap(chips)',
 P_PATH='@s9s_mb_2u_lib.s9s_mb_2u(sch_1):page302_i11@pure_quanta.q_cap(chips)',
 PATH='I11',
 DRAWING='@S9S_MB_2U_LIB.S9S_MB_2U(SCH_1):PAGE301',
 PHYS_PAGE='302',
 XY='(-2200,-2025)',
 ROT='0',
 VER='1',
 PACK_TYPE='0402',
 LOCATION='PC2348',
 CDS_LIB='pure_quanta',
 CDS_PART_NAME='Q_CAP_0402-1NF,50V,10%,EMPTY,CA',
 TOLERANCE='10%',
 MATERIAL='EMPTY',
 VOLTAGE='50V',
 VALUE='1NF',
 PRIM_FILE='./archive_libs/logical/q_cap/chips/chips.prt';

PART_NAME
 PC2349 'Q_CAP_0402-1NF,50V,10%,EMPTY,CA':;

SECTION_NUMBER 1
 '@S9S_MB_2U_LIB.S9S_MB_2U(SCH_1):PAGE325_I11@PURE_QUANTA.Q_CAP(CHIPS)':
 C_PATH='@s9s_mb_2u_lib.s9s_mb_2u(sch_1):page325_i11@pure_quanta.q_cap(chips)',
 P_PATH='@s9s_mb_2u_lib.s9s_mb_2u(sch_1):page303_i11@pure_quanta.q_cap(chips)',
 PATH='I11',
 DRAWING='@S9S_MB_2U_LIB.S9S_MB_2U(SCH_1):PAGE325',
 PHYS_PAGE='303',
 XY='(-1150,-1825)',
 ROT='0',
 VER='1',
 PACK_TYPE='0402',
 LOCATION='PC2349',
 CDS_LIB='pure_quanta',
 CDS_PART_NAME='Q_CAP_0402-1NF,50V,10%,EMPTY,CA',
 TOLERANCE='10%',
 MATERIAL='EMPTY',
 VOLTAGE='50V',
 VALUE='1NF',
 PRIM_FILE='./archive_libs/logical/q_cap/chips/chips.prt';

PART_NAME
 PC2350 'Q_CAP_0402-1NF,50V,10%,EMPTY,CA':;

SECTION_NUMBER 1
 '@S9S_MB_2U_LIB.S9S_MB_2U(SCH_1):PAGE325_I29@PURE_QUANTA.Q_CAP(CHIPS)':
 C_PATH='@s9s_mb_2u_lib.s9s_mb_2u(sch_1):page325_i29@pure_quanta.q_cap(chips)',
 P_PATH='@s9s_mb_2u_lib.s9s_mb_2u(sch_1):page303_i29@pure_quanta.q_cap(chips)',
 PATH='I29',
 DRAWING='@S9S_MB_2U_LIB.S9S_MB_2U(SCH_1):PAGE325',
 PHYS_PAGE='303',
 XY='(-1125,950)',
 ROT='0',
 VER='1',
 PACK_TYPE='0402',
 LOCATION='PC2350',
 CDS_LIB='pure_quanta',
 CDS_PART_NAME='Q_CAP_0402-1NF,50V,10%,EMPTY,CA',
 TOLERANCE='10%',
 MATERIAL='EMPTY',
 VOLTAGE='50V',
 VALUE='1NF',
 PRIM_FILE='./archive_libs/logical/q_cap/chips/chips.prt';

PART_NAME
 PC2361 'Q_CAP_0402-0.1UF,25V,10%,EMPTYA':;

SECTION_NUMBER 1
 '@S9S_MB_2U_LIB.S9S_MB_2U(SCH_1):PAGE252_I136@PURE_QUANTA.Q_CAP(CHIPS)':
 C_PATH='@s9s_mb_2u_lib.s9s_mb_2u(sch_1):page252_i136@pure_quanta.q_cap(chips)',
 P_PATH='@s9s_mb_2u_lib.s9s_mb_2u(sch_1):page266_i136@pure_quanta.q_cap(chips)',
 PATH='I136',
 DRAWING='@S9S_MB_2U_LIB.S9S_MB_2U(SCH_1):PAGE252',
 PHYS_PAGE='266',
 XY='(-1825,6350)',
 ROT='0',
 VER='1',
 PACK_TYPE='0402',
 LOCATION='PC2361',
 CDS_LIB='pure_quanta',
 CDS_PART_NAME='Q_CAP_0402-0.1UF,25V,10%,EMPTYA',
 TOLERANCE='10%',
 MATERIAL='EMPTY',
 VOLTAGE='25V',
 VALUE='0.1UF',
 PRIM_FILE='./archive_libs/logical/q_cap/chips/chips.prt';

PART_NAME
 PC2362 'Q_CAP_0402-0.1UF,25V,10%,EMPTYA':;

SECTION_NUMBER 1
 '@S9S_MB_2U_LIB.S9S_MB_2U(SCH_1):PAGE260_I110@PURE_QUANTA.Q_CAP(CHIPS)':
 C_PATH='@s9s_mb_2u_lib.s9s_mb_2u(sch_1):page260_i110@pure_quanta.q_cap(chips)',
 P_PATH='@s9s_mb_2u_lib.s9s_mb_2u(sch_1):page274_i110@pure_quanta.q_cap(chips)',
 PATH='I110',
 DRAWING='@S9S_MB_2U_LIB.S9S_MB_2U(SCH_1):PAGE260',
 PHYS_PAGE='274',
 XY='(-5925,7375)',
 ROT='0',
 VER='1',
 PACK_TYPE='0402',
 LOCATION='PC2362',
 CDS_LIB='pure_quanta',
 CDS_PART_NAME='Q_CAP_0402-0.1UF,25V,10%,EMPTYA',
 TOLERANCE='10%',
 MATERIAL='EMPTY',
 VOLTAGE='25V',
 VALUE='0.1UF',
 PRIM_FILE='./archive_libs/logical/q_cap/chips/chips.prt';

PART_NAME
 PC2365 'Q_CAP_0402-0.1UF,25V,10%,EMPTYA':;

SECTION_NUMBER 1
 '@S9S_MB_2U_LIB.S9S_MB_2U(SCH_1):PAGE264_I96@PURE_QUANTA.Q_CAP(CHIPS)':
 C_PATH='@s9s_mb_2u_lib.s9s_mb_2u(sch_1):page264_i96@pure_quanta.q_cap(chips)',
 P_PATH='@s9s_mb_2u_lib.s9s_mb_2u(sch_1):page278_i96@pure_quanta.q_cap(chips)',
 PATH='I96',
 DRAWING='@S9S_MB_2U_LIB.S9S_MB_2U(SCH_1):PAGE264',
 PHYS_PAGE='278',
 XY='(-6575,8750)',
 ROT='0',
 VER='1',
 PACK_TYPE='0402',
 LOCATION='PC2365',
 CDS_LIB='pure_quanta',
 CDS_PART_NAME='Q_CAP_0402-0.1UF,25V,10%,EMPTYA',
 TOLERANCE='10%',
 MATERIAL='EMPTY',
 VOLTAGE='25V',
 VALUE='0.1UF',
 PRIM_FILE='./archive_libs/logical/q_cap/chips/chips.prt';

PART_NAME
 PC2366 'Q_CAP_0402-0.1UF,25V,10%,EMPTYA':;

SECTION_NUMBER 1
 '@S9S_MB_2U_LIB.S9S_MB_2U(SCH_1):PAGE270_I128@PURE_QUANTA.Q_CAP(CHIPS)':
 C_PATH='@s9s_mb_2u_lib.s9s_mb_2u(sch_1):page270_i128@pure_quanta.q_cap(chips)',
 P_PATH='@s9s_mb_2u_lib.s9s_mb_2u(sch_1):page284_i128@pure_quanta.q_cap(chips)',
 PATH='I128',
 DRAWING='@S9S_MB_2U_LIB.S9S_MB_2U(SCH_1):PAGE270',
 PHYS_PAGE='284',
 XY='(1100,2825)',
 ROT='0',
 VER='1',
 PACK_TYPE='0402',
 LOCATION='PC2366',
 CDS_LIB='pure_quanta',
 CDS_PART_NAME='Q_CAP_0402-0.1UF,25V,10%,EMPTYA',
 TOLERANCE='10%',
 MATERIAL='EMPTY',
 VOLTAGE='25V',
 VALUE='0.1UF',
 PRIM_FILE='./archive_libs/logical/q_cap/chips/chips.prt';

PART_NAME
 PC2367 'Q_CAP_0402-0.1UF,25V,10%,EMPTYA':;

SECTION_NUMBER 1
 '@S9S_MB_2U_LIB.S9S_MB_2U(SCH_1):PAGE278_I111@PURE_QUANTA.Q_CAP(CHIPS)':
 C_PATH='@s9s_mb_2u_lib.s9s_mb_2u(sch_1):page278_i111@pure_quanta.q_cap(chips)',
 P_PATH='@s9s_mb_2u_lib.s9s_mb_2u(sch_1):page292_i111@pure_quanta.q_cap(chips)',
 PATH='I111',
 DRAWING='@S9S_MB_2U_LIB.S9S_MB_2U(SCH_1):PAGE278',
 PHYS_PAGE='292',
 XY='(4450,8950)',
 ROT='0',
 VER='1',
 PACK_TYPE='0402',
 LOCATION='PC2367',
 CDS_LIB='pure_quanta',
 CDS_PART_NAME='Q_CAP_0402-0.1UF,25V,10%,EMPTYA',
 TOLERANCE='10%',
 MATERIAL='EMPTY',
 VOLTAGE='25V',
 VALUE='0.1UF',
 PRIM_FILE='./archive_libs/logical/q_cap/chips/chips.prt';

PART_NAME
 PC2368 'Q_CAP_0402-0.1UF,25V,10%,EMPTYA':;

SECTION_NUMBER 1
 '@S9S_MB_2U_LIB.S9S_MB_2U(SCH_1):PAGE282_I96@PURE_QUANTA.Q_CAP(CHIPS)':
 C_PATH='@s9s_mb_2u_lib.s9s_mb_2u(sch_1):page282_i96@pure_quanta.q_cap(chips)',
 P_PATH='@s9s_mb_2u_lib.s9s_mb_2u(sch_1):page296_i96@pure_quanta.q_cap(chips)',
 PATH='I96',
 DRAWING='@S9S_MB_2U_LIB.S9S_MB_2U(SCH_1):PAGE282',
 PHYS_PAGE='296',
 XY='(-2050,5250)',
 ROT='0',
 VER='1',
 PACK_TYPE='0402',
 LOCATION='PC2368',
 CDS_LIB='pure_quanta',
 CDS_PART_NAME='Q_CAP_0402-0.1UF,25V,10%,EMPTYA',
 TOLERANCE='10%',
 MATERIAL='EMPTY',
 VOLTAGE='25V',
 VALUE='0.1UF',
 PRIM_FILE='./archive_libs/logical/q_cap/chips/chips.prt';

PART_NAME
 PC2643 'Q_CAP_C0402-1UF,25V,10%,X6S,CHA':;

SECTION_NUMBER 1
 '@S9S_MB_2U_LIB.S9S_MB_2U(SCH_1):PAGE267_I4@PURE_QUANTA.Q_CAP(CHIPS)':
 C_PATH='@s9s_mb_2u_lib.s9s_mb_2u(sch_1):page267_i4@pure_quanta.q_cap(chips)',
 P_PATH='@s9s_mb_2u_lib.s9s_mb_2u(sch_1):page281_i4@pure_quanta.q_cap(chips)',
 PATH='I4',
 DRAWING='@S9S_MB_2U_LIB.S9S_MB_2U(SCH_1):PAGE267',
 BOM_COST='VR_PCH',
 PHYS_PAGE='281',
 XY='(-10850,2550)',
 ROT='0',
 VER='1',
 PACK_TYPE='C0402',
 LOCATION='PC2643',
 SEC='1',
 CDS_LIB='pure_quanta',
 CDS_PART_NAME='Q_CAP_C0402-1UF,25V,10%,X6S,CHA',
 SEC_TYPE='C0402',
 TOLERANCE='10%',
 MATERIAL='X6S',
 VOLTAGE='25V',
 VALUE='1UF',
 PRIM_FILE='./archive_libs/logical/q_cap/chips/chips.prt';

PART_NAME
 PC2645 'Q_CAPP_SMLF-330UF,2.5V,+10/-35B':;

SECTION_NUMBER 1
 '@S9S_MB_2U_LIB.S9S_MB_2U(SCH_1):PAGE257_I67@PURE_QUANTA.Q_CAPP(CHIPS)':
 C_PATH='@s9s_mb_2u_lib.s9s_mb_2u(sch_1):page257_i67@pure_quanta.q_capp(chips)',
 P_PATH='@s9s_mb_2u_lib.s9s_mb_2u(sch_1):page271_i67@pure_quanta.q_capp(chips)',
 PATH='I67',
 DRAWING='@S9S_MB_2U_LIB.S9S_MB_2U(SCH_1):PAGE257',
 PHYS_PAGE='271',
 XY='(3175,3325)',
 ROT='0',
 VER='1',
 PACK_TYPE='SMLF',
 LOCATION='PC2645',
 CDS_LIB='pure_quanta',
 CDS_PART_NAME='Q_CAPP_SMLF-330UF,2.5V,+10/-35B',
 TOLERANCE='+10/-35%',
 MATERIAL='SPCAP',
 VOLTAGE='2.5V',
 VALUE='330UF',
 PRIM_FILE='./archive_libs/logical/q_capp/chips/chips.prt';

PART_NAME
 PC2946 'Q_CAP_C0402-2.2UF,10V,10%,X6S,A':;

SECTION_NUMBER 1
 '@S9S_MB_2U_LIB.S9S_MB_2U(SCH_1):PAGE261_I16@PURE_QUANTA.Q_CAP(CHIPS)':
 C_PATH='@s9s_mb_2u_lib.s9s_mb_2u(sch_1):page261_i16@pure_quanta.q_cap(chips)',
 P_PATH='@s9s_mb_2u_lib.s9s_mb_2u(sch_1):page275_i16@pure_quanta.q_cap(chips)',
 PATH='I16',
 DRAWING='@S9S_MB_2U_LIB.S9S_MB_2U(SCH_1):PAGE261',
 PHYS_PAGE='275',
 XY='(-9875,2900)',
 ROT='0',
 VER='1',
 PACK_TYPE='C0402',
 LOCATION='PC2946',
 CDS_LIB='pure_quanta',
 CDS_PART_NAME='Q_CAP_C0402-2.2UF,10V,10%,X6S,A',
 TOLERANCE='10%',
 MATERIAL='X6S',
 VOLTAGE='10V',
 VALUE='2.2UF',
 PRIM_FILE='./archive_libs/logical/q_cap/chips/chips.prt';

PART_NAME
 PC2947 'Q_CAP_C0402-2.2UF,10V,10%,X6S,A':;

SECTION_NUMBER 1
 '@S9S_MB_2U_LIB.S9S_MB_2U(SCH_1):PAGE261_I29@PURE_QUANTA.Q_CAP(CHIPS)':
 C_PATH='@s9s_mb_2u_lib.s9s_mb_2u(sch_1):page261_i29@pure_quanta.q_cap(chips)',
 P_PATH='@s9s_mb_2u_lib.s9s_mb_2u(sch_1):page275_i29@pure_quanta.q_cap(chips)',
 PATH='I29',
 DRAWING='@S9S_MB_2U_LIB.S9S_MB_2U(SCH_1):PAGE261',
 PHYS_PAGE='275',
 XY='(-9825,5650)',
 ROT='0',
 VER='1',
 PACK_TYPE='C0402',
 LOCATION='PC2947',
 CDS_LIB='pure_quanta',
 CDS_PART_NAME='Q_CAP_C0402-2.2UF,10V,10%,X6S,A',
 TOLERANCE='10%',
 MATERIAL='X6S',
 VOLTAGE='10V',
 VALUE='2.2UF',
 PRIM_FILE='./archive_libs/logical/q_cap/chips/chips.prt';

PART_NAME
 PC2948 'Q_CAP_C0402-2.2UF,10V,10%,X6S,A':;

SECTION_NUMBER 1
 '@S9S_MB_2U_LIB.S9S_MB_2U(SCH_1):PAGE265_I14@PURE_QUANTA.Q_CAP(CHIPS)':
 C_PATH='@s9s_mb_2u_lib.s9s_mb_2u(sch_1):page265_i14@pure_quanta.q_cap(chips)',
 P_PATH='@s9s_mb_2u_lib.s9s_mb_2u(sch_1):page279_i14@pure_quanta.q_cap(chips)',
 PATH='I14',
 DRAWING='@S9S_MB_2U_LIB.S9S_MB_2U(SCH_1):PAGE265',
 PHYS_PAGE='279',
 XY='(-7575,2800)',
 ROT='0',
 VER='1',
 PACK_TYPE='C0402',
 LOCATION='PC2948',
 CDS_LIB='pure_quanta',
 CDS_PART_NAME='Q_CAP_C0402-2.2UF,10V,10%,X6S,A',
 TOLERANCE='10%',
 MATERIAL='X6S',
 VOLTAGE='10V',
 VALUE='2.2UF',
 PRIM_FILE='./archive_libs/logical/q_cap/chips/chips.prt';

PART_NAME
 PC2949 'Q_CAP_C0402-2.2UF,10V,10%,X6S,A':;

SECTION_NUMBER 1
 '@S9S_MB_2U_LIB.S9S_MB_2U(SCH_1):PAGE279_I13@PURE_QUANTA.Q_CAP(CHIPS)':
 C_PATH='@s9s_mb_2u_lib.s9s_mb_2u(sch_1):page279_i13@pure_quanta.q_cap(chips)',
 P_PATH='@s9s_mb_2u_lib.s9s_mb_2u(sch_1):page293_i13@pure_quanta.q_cap(chips)',
 PATH='I13',
 DRAWING='@S9S_MB_2U_LIB.S9S_MB_2U(SCH_1):PAGE279',
 PHYS_PAGE='293',
 XY='(-7975,9300)',
 ROT='0',
 VER='1',
 PACK_TYPE='C0402',
 LOCATION='PC2949',
 CDS_LIB='pure_quanta',
 CDS_PART_NAME='Q_CAP_C0402-2.2UF,10V,10%,X6S,A',
 TOLERANCE='10%',
 MATERIAL='X6S',
 VOLTAGE='10V',
 VALUE='2.2UF',
 PRIM_FILE='./archive_libs/logical/q_cap/chips/chips.prt';

PART_NAME
 PC2950 'Q_CAP_C0402-2.2UF,10V,10%,X6S,A':;

SECTION_NUMBER 1
 '@S9S_MB_2U_LIB.S9S_MB_2U(SCH_1):PAGE279_I26@PURE_QUANTA.Q_CAP(CHIPS)':
 C_PATH='@s9s_mb_2u_lib.s9s_mb_2u(sch_1):page279_i26@pure_quanta.q_cap(chips)',
 P_PATH='@s9s_mb_2u_lib.s9s_mb_2u(sch_1):page293_i26@pure_quanta.q_cap(chips)',
 PATH='I26',
 DRAWING='@S9S_MB_2U_LIB.S9S_MB_2U(SCH_1):PAGE279',
 PHYS_PAGE='293',
 XY='(-7925,12050)',
 ROT='0',
 VER='1',
 PACK_TYPE='C0402',
 LOCATION='PC2950',
 CDS_LIB='pure_quanta',
 CDS_PART_NAME='Q_CAP_C0402-2.2UF,10V,10%,X6S,A',
 TOLERANCE='10%',
 MATERIAL='X6S',
 VOLTAGE='10V',
 VALUE='2.2UF',
 PRIM_FILE='./archive_libs/logical/q_cap/chips/chips.prt';

PART_NAME
 PC2951 'Q_CAP_C0402-2.2UF,10V,10%,X6S,A':;

SECTION_NUMBER 1
 '@S9S_MB_2U_LIB.S9S_MB_2U(SCH_1):PAGE283_I18@PURE_QUANTA.Q_CAP(CHIPS)':
 C_PATH='@s9s_mb_2u_lib.s9s_mb_2u(sch_1):page283_i18@pure_quanta.q_cap(chips)',
 P_PATH='@s9s_mb_2u_lib.s9s_mb_2u(sch_1):page297_i18@pure_quanta.q_cap(chips)',
 PATH='I18',
 DRAWING='@S9S_MB_2U_LIB.S9S_MB_2U(SCH_1):PAGE283',
 PHYS_PAGE='297',
 XY='(-7500,4525)',
 ROT='0',
 VER='1',
 PACK_TYPE='C0402',
 LOCATION='PC2951',
 CDS_LIB='pure_quanta',
 CDS_PART_NAME='Q_CAP_C0402-2.2UF,10V,10%,X6S,A',
 TOLERANCE='10%',
 MATERIAL='X6S',
 VOLTAGE='10V',
 VALUE='2.2UF',
 PRIM_FILE='./archive_libs/logical/q_cap/chips/chips.prt';

PART_NAME
 PC3272 'Q_CAP_C0402-1UF,25V,10%,X6S,CHA':
 ROOM='HSC1_BOM1';

SECTION_NUMBER 1
 '@S9S_MB_2U_LIB.S9S_MB_2U(SCH_1):PAGE325_I19@PURE_QUANTA.Q_CAP(CHIPS)':
 C_PATH='@s9s_mb_2u_lib.s9s_mb_2u(sch_1):page325_i19@pure_quanta.q_cap(chips)',
 P_PATH='@s9s_mb_2u_lib.s9s_mb_2u(sch_1):page303_i19@pure_quanta.q_cap(chips)',
 PATH='I19',
 DRAWING='@S9S_MB_2U_LIB.S9S_MB_2U(SCH_1):PAGE325',
 PHYS_PAGE='303',
 XY='(-2775,1600)',
 ROT='0',
 VER='1',
 PACK_TYPE='C0402',
 LOCATION='PC3272',
 CDS_LIB='pure_quanta',
 CDS_PART_NAME='Q_CAP_C0402-1UF,25V,10%,X6S,CHA',
 TOLERANCE='10%',
 MATERIAL='X6S',
 VOLTAGE='25V',
 ROOM='HSC1_BOM1',
 VALUE='1UF',
 PRIM_FILE='./archive_libs/logical/q_cap/chips/chips.prt';

PART_NAME
 PC4056 'Q_CAP_C0402-3900PF,50V,10%,EMPA':
 ROOM='NIC1_P12V_MAM_MAM_BOM1';

SECTION_NUMBER 1
 '@S9S_MB_2U_LIB.S9S_MB_2U(SCH_1):PAGE153_I83@PURE_QUANTA.Q_CAP(CHIPS)':
 C_PATH='@s9s_mb_2u_lib.s9s_mb_2u(sch_1):page153_i83@pure_quanta.q_cap(chips)',
 P_PATH='@s9s_mb_2u_lib.s9s_mb_2u(sch_1):page156_i83@pure_quanta.q_cap(chips)',
 PATH='I83',
 DRAWING='@S9S_MB_2U_LIB.S9S_MB_2U(SCH_1):PAGE153',
 ROOM1='NIC1_P12V_MAM_TIC_BOM2',
 PHYS_PAGE='156',
 XY='(8975,10800)',
 ROT='1',
 VER='1',
 PACK_TYPE='C0402',
 CDS_LIB='pure_quanta',
 CDS_PART_NAME='Q_CAP_C0402-3900PF,50V,10%,EMPA',
 TOLERANCE='10%',
 MATERIAL='EMPTY',
 VOLTAGE='50V',
 ROOM='NIC1_P12V_MAM_MAM_BOM1',
 VALUE='3900PF',
 PRIM_FILE='./archive_libs/logical/q_cap/chips/chips.prt';

PART_NAME
 PC5328 'Q_CAP_C0402-1UF,25V,10%,X6S,CHA':;

SECTION_NUMBER 1
 '@S9S_MB_2U_LIB.S9S_MB_2U(SCH_1):PAGE153_I66@PURE_QUANTA.Q_CAP(CHIPS)':
 C_PATH='@s9s_mb_2u_lib.s9s_mb_2u(sch_1):page153_i66@pure_quanta.q_cap(chips)',
 P_PATH='@s9s_mb_2u_lib.s9s_mb_2u(sch_1):page156_i66@pure_quanta.q_cap(chips)',
 PATH='I66',
 DRAWING='@S9S_MB_2U_LIB.S9S_MB_2U(SCH_1):PAGE153',
 PHYS_PAGE='156',
 XY='(5800,13525)',
 ROT='0',
 VER='1',
 PACK_TYPE='C0402',
 CDS_LIB='pure_quanta',
 CDS_PART_NAME='Q_CAP_C0402-1UF,25V,10%,X6S,CHA',
 TOLERANCE='10%',
 MATERIAL='X6S',
 VOLTAGE='25V',
 VALUE='1UF',
 PRIM_FILE='./archive_libs/logical/q_cap/chips/chips.prt';

PART_NAME
 PD15 'ZENER_AC-5.0SMDJ14A,SMLF,IC,BCA':;

SECTION_NUMBER 1
 '@S9S_MB_2U_LIB.S9S_MB_2U(SCH_1):PAGE328_I51@PURE_QUANTA.ZENER_AC(CHIPS)':
 C_PATH='@s9s_mb_2u_lib.s9s_mb_2u(sch_1):page328_i51@pure_quanta.zener_ac(chips)~
',
 P_PATH='@s9s_mb_2u_lib.s9s_mb_2u(sch_1):page304_i51@pure_quanta.zener_ac(chips)~
',
 PATH='I51',
 DRAWING='@S9S_MB_2U_LIB.S9S_MB_2U(SCH_1):PAGE328',
 PHYS_PAGE='304',
 XY='(-450,3775)',
 ROT='1',
 VER='1',
 LOCATION='PD15',
 CDS_LIB='pure_quanta',
 CDS_PART_NAME='ZENER_AC-5.0SMDJ14A,SMLF,IC,BCA',
 PART_TYPE='SMLF',
 MATERIAL='IC',
 VALUE='5.0SMDJ14A',
 PRIM_FILE='./archive_libs/logical/zener_ac/chips/chips.prt';

PART_NAME
 PD16 'ZENER_AC-5.0SMDJ14A,SMLF,IC,BCA':;

SECTION_NUMBER 1
 '@S9S_MB_2U_LIB.S9S_MB_2U(SCH_1):PAGE328_I53@PURE_QUANTA.ZENER_AC(CHIPS)':
 C_PATH='@s9s_mb_2u_lib.s9s_mb_2u(sch_1):page328_i53@pure_quanta.zener_ac(chips)~
',
 P_PATH='@s9s_mb_2u_lib.s9s_mb_2u(sch_1):page304_i53@pure_quanta.zener_ac(chips)~
',
 PATH='I53',
 DRAWING='@S9S_MB_2U_LIB.S9S_MB_2U(SCH_1):PAGE328',
 PHYS_PAGE='304',
 XY='(50,3775)',
 ROT='1',
 VER='1',
 LOCATION='PD16',
 CDS_LIB='pure_quanta',
 CDS_PART_NAME='ZENER_AC-5.0SMDJ14A,SMLF,IC,BCA',
 PART_TYPE='SMLF',
 MATERIAL='IC',
 VALUE='5.0SMDJ14A',
 PRIM_FILE='./archive_libs/logical/zener_ac/chips/chips.prt';

PART_NAME
 PD17 'SS15P3SM386A-SS15P3S-M3/86A,SMA':;

SECTION_NUMBER 1
 '@S9S_MB_2U_LIB.S9S_MB_2U(SCH_1):PAGE328_I72@PURE_QUANTA.SS15P3SM386A(CHIPS)':
 C_PATH='@s9s_mb_2u_lib.s9s_mb_2u(sch_1):page328_i72@pure_quanta.ss15p3sm386a(ch~
ips)',
 P_PATH='@s9s_mb_2u_lib.s9s_mb_2u(sch_1):page304_i72@pure_quanta.ss15p3sm386a(ch~
ips)',
 PATH='I72',
 DRAWING='@S9S_MB_2U_LIB.S9S_MB_2U(SCH_1):PAGE328',
 PHYS_PAGE='304',
 XY='(5200,475)',
 ROT='1',
 VER='1',
 LOCATION='PD17',
 CDS_LIB='pure_quanta',
 CDS_PART_NAME='SS15P3SM386A-SS15P3S-M3/86A,SMA',
 PART_TYPE='SMLF',
 MATERIAL='IC',
 VALUE='SS15P3S-M3/86A',
 PRIM_FILE='./archive_libs/logical/ss15p3sm386a/chips/chips.prt';

PART_NAME
 PD101 'DIODE_TVS-SMF14A,SMLF,IC,BCSMFA':;

SECTION_NUMBER 1
 '@S9S_MB_2U_LIB.S9S_MB_2U(SCH_1):PAGE153_I38@PURE_QUANTA.DIODE_TVS(CHIPS)':
 C_PATH='@s9s_mb_2u_lib.s9s_mb_2u(sch_1):page153_i38@pure_quanta.diode_tvs(chips~
)',
 P_PATH='@s9s_mb_2u_lib.s9s_mb_2u(sch_1):page156_i38@pure_quanta.diode_tvs(chips~
)',
 PATH='I38',
 DRAWING='@S9S_MB_2U_LIB.S9S_MB_2U(SCH_1):PAGE153',
 PIN_NAMES_ROTATE='True',
 PHYS_PAGE='156',
 XY='(5200,11425)',
 ROT='1',
 VER='1',
 LOCATION='PD101',
 CDS_LIB='pure_quanta',
 CDS_PART_NAME='DIODE_TVS-SMF14A,SMLF,IC,BCSMFA',
 PART_TYPE='SMLF',
 MATERIAL='IC',
 VALUE='SMF14A',
 PRIM_FILE='./archive_libs/logical/diode_tvs/chips/chips.prt';

PART_NAME
 PD102 'SCHOTTKY_AC-B340A-13-F,SMLF,ICA':;

SECTION_NUMBER 1
 '@S9S_MB_2U_LIB.S9S_MB_2U(SCH_1):PAGE153_I86@PURE_QUANTA.SCHOTTKY_AC(CHIPS)':
 C_PATH='@s9s_mb_2u_lib.s9s_mb_2u(sch_1):page153_i86@pure_quanta.schottky_ac(chi~
ps)',
 P_PATH='@s9s_mb_2u_lib.s9s_mb_2u(sch_1):page156_i86@pure_quanta.schottky_ac(chi~
ps)',
 PATH='I86',
 DRAWING='@S9S_MB_2U_LIB.S9S_MB_2U(SCH_1):PAGE153',
 PHYS_PAGE='156',
 XY='(8725,11675)',
 ROT='1',
 VER='1',
 LOCATION='PD102',
 CDS_LIB='pure_quanta',
 CDS_PART_NAME='SCHOTTKY_AC-B340A-13-F,SMLF,ICA',
 PART_TYPE='SMLF',
 MATERIAL='IC',
 VALUE='B340A-13-F',
 PRIM_FILE='./archive_libs/logical/schottky_ac/chips/chips.prt';

PART_NAME
 PD103 'SCHOTTKY_AC-B340A-13-F,SMLF,ICA':;

SECTION_NUMBER 1
 '@S9S_MB_2U_LIB.S9S_MB_2U(SCH_1):PAGE153_I104@PURE_QUANTA.SCHOTTKY_AC(CHIPS)':
 C_PATH='@s9s_mb_2u_lib.s9s_mb_2u(sch_1):page153_i104@pure_quanta.schottky_ac(ch~
ips)',
 P_PATH='@s9s_mb_2u_lib.s9s_mb_2u(sch_1):page156_i104@pure_quanta.schottky_ac(ch~
ips)',
 PATH='I104',
 DRAWING='@S9S_MB_2U_LIB.S9S_MB_2U(SCH_1):PAGE153',
 PHYS_PAGE='156',
 XY='(8950,13700)',
 ROT='1',
 VER='1',
 LOCATION='PD103',
 CDS_LIB='pure_quanta',
 CDS_PART_NAME='SCHOTTKY_AC-B340A-13-F,SMLF,ICA',
 PART_TYPE='SMLF',
 MATERIAL='IC',
 VALUE='B340A-13-F',
 PRIM_FILE='./archive_libs/logical/schottky_ac/chips/chips.prt';

PART_NAME
 PD107 'DIODE_TVS-SMF14A,SMLF,IC,BCSMFA':;

SECTION_NUMBER 1
 '@S9S_MB_2U_LIB.S9S_MB_2U(SCH_1):PAGE131_I44@PURE_QUANTA.DIODE_TVS(CHIPS)':
 C_PATH='@s9s_mb_2u_lib.s9s_mb_2u(sch_1):page131_i44@pure_quanta.diode_tvs(chips~
)',
 P_PATH='@s9s_mb_2u_lib.s9s_mb_2u(sch_1):page162_i44@pure_quanta.diode_tvs(chips~
)',
 PATH='I44',
 DRAWING='@S9S_MB_2U_LIB.S9S_MB_2U(SCH_1):PAGE131',
 PIN_NAMES_ROTATE='True',
 PHYS_PAGE='162',
 XY='(-900,200)',
 ROT='1',
 VER='1',
 LOCATION='PD107',
 CDS_LIB='pure_quanta',
 CDS_PART_NAME='DIODE_TVS-SMF14A,SMLF,IC,BCSMFA',
 PART_TYPE='SMLF',
 MATERIAL='IC',
 VALUE='SMF14A',
 PRIM_FILE='./archive_libs/logical/diode_tvs/chips/chips.prt';

PART_NAME
 PD108 'SCHOTTKY_AC-B340A-13-F,SMLF,ICA':;

SECTION_NUMBER 1
 '@S9S_MB_2U_LIB.S9S_MB_2U(SCH_1):PAGE131_I93@PURE_QUANTA.SCHOTTKY_AC(CHIPS)':
 C_PATH='@s9s_mb_2u_lib.s9s_mb_2u(sch_1):page131_i93@pure_quanta.schottky_ac(chi~
ps)',
 P_PATH='@s9s_mb_2u_lib.s9s_mb_2u(sch_1):page162_i93@pure_quanta.schottky_ac(chi~
ps)',
 PATH='I93',
 DRAWING='@S9S_MB_2U_LIB.S9S_MB_2U(SCH_1):PAGE131',
 PHYS_PAGE='162',
 XY='(2650,425)',
 ROT='1',
 VER='1',
 LOCATION='PD108',
 CDS_LIB='pure_quanta',
 CDS_PART_NAME='SCHOTTKY_AC-B340A-13-F,SMLF,ICA',
 PART_TYPE='SMLF',
 MATERIAL='IC',
 VALUE='B340A-13-F',
 PRIM_FILE='./archive_libs/logical/schottky_ac/chips/chips.prt';

PART_NAME
 PD109 'SCHOTTKY_AC-B340A-13-F,SMLF,ICA':;

SECTION_NUMBER 1
 '@S9S_MB_2U_LIB.S9S_MB_2U(SCH_1):PAGE131_I107@PURE_QUANTA.SCHOTTKY_AC(CHIPS)':
 C_PATH='@s9s_mb_2u_lib.s9s_mb_2u(sch_1):page131_i107@pure_quanta.schottky_ac(ch~
ips)',
 P_PATH='@s9s_mb_2u_lib.s9s_mb_2u(sch_1):page162_i107@pure_quanta.schottky_ac(ch~
ips)',
 PATH='I107',
 DRAWING='@S9S_MB_2U_LIB.S9S_MB_2U(SCH_1):PAGE131',
 PHYS_PAGE='162',
 XY='(2775,2750)',
 ROT='1',
 VER='1',
 LOCATION='PD109',
 CDS_LIB='pure_quanta',
 CDS_PART_NAME='SCHOTTKY_AC-B340A-13-F,SMLF,ICA',
 PART_TYPE='SMLF',
 MATERIAL='IC',
 VALUE='B340A-13-F',
 PRIM_FILE='./archive_libs/logical/schottky_ac/chips/chips.prt';

PART_NAME
 PD112 'SCHOTTKY_AC-B340A-13-F,SMLF,ICA':;

SECTION_NUMBER 1
 '@S9S_MB_2U_LIB.S9S_MB_2U(SCH_1):PAGE324_I71@PURE_QUANTA.SCHOTTKY_AC(CHIPS)':
 C_PATH='@s9s_mb_2u_lib.s9s_mb_2u(sch_1):page324_i71@pure_quanta.schottky_ac(chi~
ps)',
 P_PATH='@s9s_mb_2u_lib.s9s_mb_2u(sch_1):page192_i71@pure_quanta.schottky_ac(chi~
ps)',
 PATH='I71',
 DRAWING='@S9S_MB_2U_LIB.S9S_MB_2U(SCH_1):PAGE324',
 PHYS_PAGE='192',
 XY='(2675,1850)',
 ROT='1',
 VER='1',
 LOCATION='PD112',
 CDS_LIB='pure_quanta',
 CDS_PART_NAME='SCHOTTKY_AC-B340A-13-F,SMLF,ICA',
 PART_TYPE='SMLF',
 MATERIAL='IC',
 VALUE='B340A-13-F',
 PRIM_FILE='./archive_libs/logical/schottky_ac/chips/chips.prt';

PART_NAME
 PD113 'SCHOTTKY_AC-B340A-13-F,SMLF,ICA':;

SECTION_NUMBER 1
 '@S9S_MB_2U_LIB.S9S_MB_2U(SCH_1):PAGE324_I46@PURE_QUANTA.SCHOTTKY_AC(CHIPS)':
 C_PATH='@s9s_mb_2u_lib.s9s_mb_2u(sch_1):page324_i46@pure_quanta.schottky_ac(chi~
ps)',
 P_PATH='@s9s_mb_2u_lib.s9s_mb_2u(sch_1):page192_i46@pure_quanta.schottky_ac(chi~
ps)',
 PATH='I46',
 DRAWING='@S9S_MB_2U_LIB.S9S_MB_2U(SCH_1):PAGE324',
 PHYS_PAGE='192',
 XY='(2700,-875)',
 ROT='1',
 VER='1',
 LOCATION='PD113',
 CDS_LIB='pure_quanta',
 CDS_PART_NAME='SCHOTTKY_AC-B340A-13-F,SMLF,ICA',
 PART_TYPE='SMLF',
 MATERIAL='IC',
 VALUE='B340A-13-F',
 PRIM_FILE='./archive_libs/logical/schottky_ac/chips/chips.prt';

PART_NAME
 PD114 'DIODE_TVS-SMF14A,SMLF,IC,BCSMFA':;

SECTION_NUMBER 1
 '@S9S_MB_2U_LIB.S9S_MB_2U(SCH_1):PAGE324_I84@PURE_QUANTA.DIODE_TVS(CHIPS)':
 C_PATH='@s9s_mb_2u_lib.s9s_mb_2u(sch_1):page324_i84@pure_quanta.diode_tvs(chips~
)',
 P_PATH='@s9s_mb_2u_lib.s9s_mb_2u(sch_1):page192_i84@pure_quanta.diode_tvs(chips~
)',
 PATH='I84',
 DRAWING='@S9S_MB_2U_LIB.S9S_MB_2U(SCH_1):PAGE324',
 PIN_NAMES_ROTATE='TRUE',
 PHYS_PAGE='192',
 XY='(-925,1625)',
 ROT='1',
 VER='1',
 LOCATION='PD114',
 CDS_LIB='pure_quanta',
 CDS_PART_NAME='DIODE_TVS-SMF14A,SMLF,IC,BCSMFA',
 PART_TYPE='SMLF',
 MATERIAL='IC',
 VALUE='SMF14A',
 PRIM_FILE='./archive_libs/logical/diode_tvs/chips/chips.prt';

PART_NAME
 PD115 'DIODE_TVS-SMF14A,SMLF,IC,BCSMFA':;

SECTION_NUMBER 1
 '@S9S_MB_2U_LIB.S9S_MB_2U(SCH_1):PAGE229_I29@PURE_QUANTA.DIODE_TVS(CHIPS)':
 C_PATH='@s9s_mb_2u_lib.s9s_mb_2u(sch_1):page229_i29@pure_quanta.diode_tvs(chips~
)',
 P_PATH='@s9s_mb_2u_lib.s9s_mb_2u(sch_1):page242_i29@pure_quanta.diode_tvs(chips~
)',
 PATH='I29',
 DRAWING='@S9S_MB_2U_LIB.S9S_MB_2U(SCH_1):PAGE229',
 PIN_NAMES_ROTATE='TRUE',
 PHYS_PAGE='242',
 XY='(-650,2250)',
 ROT='1',
 VER='1',
 LOCATION='PD115',
 CDS_LIB='pure_quanta',
 CDS_PART_NAME='DIODE_TVS-SMF14A,SMLF,IC,BCSMFA',
 PART_TYPE='SMLF',
 MATERIAL='IC',
 VALUE='SMF14A',
 PRIM_FILE='./archive_libs/logical/diode_tvs/chips/chips.prt';

PART_NAME
 PD116 'SCHOTTKY_AC-B340A-13-F,SMLF,ICA':;

SECTION_NUMBER 1
 '@S9S_MB_2U_LIB.S9S_MB_2U(SCH_1):PAGE229_I82@PURE_QUANTA.SCHOTTKY_AC(CHIPS)':
 C_PATH='@s9s_mb_2u_lib.s9s_mb_2u(sch_1):page229_i82@pure_quanta.schottky_ac(chi~
ps)',
 P_PATH='@s9s_mb_2u_lib.s9s_mb_2u(sch_1):page242_i82@pure_quanta.schottky_ac(chi~
ps)',
 PATH='I82',
 DRAWING='@S9S_MB_2U_LIB.S9S_MB_2U(SCH_1):PAGE229',
 PHYS_PAGE='242',
 XY='(2900,2450)',
 ROT='1',
 VER='1',
 LOCATION='PD116',
 CDS_LIB='pure_quanta',
 CDS_PART_NAME='SCHOTTKY_AC-B340A-13-F,SMLF,ICA',
 PART_TYPE='SMLF',
 MATERIAL='IC',
 VALUE='B340A-13-F',
 PRIM_FILE='./archive_libs/logical/schottky_ac/chips/chips.prt';

PART_NAME
 PJ42 'SCONN21_9193031121LF-SCONN21_9A':
 ROOM='HSC1_BOM2';

SECTION_NUMBER 1
 '@S9S_MB_2U_LIB.S9S_MB_2U(SCH_1):PAGE327_I34@PURE_QUANTA.SCONN21_9193031121LF(CHIPS)':
 C_PATH='@s9s_mb_2u_lib.s9s_mb_2u(sch_1):page327_i34@pure_quanta.sconn21_9193031~
121lf(chips)',
 P_PATH='@s9s_mb_2u_lib.s9s_mb_2u(sch_1):page305_i34@pure_quanta.sconn21_9193031~
121lf(chips)',
 PATH='I34',
 DRAWING='@S9S_MB_2U_LIB.S9S_MB_2U(SCH_1):PAGE327',
 PHYS_PAGE='305',
 XY='(3650,2350)',
 ROT='2',
 VER='1',
 LOCATION='PJ42',
 CDS_LIB='pure_quanta',
 CDS_PART_NAME='SCONN21_9193031121LF-SCONN21_9A',
 PART_TYPE='SMLF',
 MATERIAL='EMPTY',
 ROOM='HSC1_BOM2',
 VALUE='SCONN21_91930-31121LF',
 PRIM_FILE='./archive_libs/logical/sconn21_9193031121lf/chips/chips.prt';

PART_NAME
 PJ45 'Q_SHORT_SM-EMPTY,SHORT6':;

SECTION_NUMBER 1
 '@S9S_MB_2U_LIB.S9S_MB_2U(SCH_1):PAGE260_I43@PURE_QUANTA.Q_SHORT(CHIPS)':
 C_PATH='@s9s_mb_2u_lib.s9s_mb_2u(sch_1):page260_i43@pure_quanta.q_short(chips)',
 P_PATH='@s9s_mb_2u_lib.s9s_mb_2u(sch_1):page274_i43@pure_quanta.q_short(chips)',
 PATH='I43',
 DRAWING='@S9S_MB_2U_LIB.S9S_MB_2U(SCH_1):PAGE260',
 PHYS_PAGE='274',
 XY='(-9900,5575)',
 ROT='0',
 VER='1',
 PACK_TYPE='SM',
 LOCATION='PJ45',
 CDS_LIB='pure_quanta',
 CDS_PART_NAME='Q_SHORT_SM-EMPTY,SHORT6',
 MATERIAL='EMPTY',
 PRIM_FILE='./archive_libs/logical/q_short/chips/chips.prt';

PART_NAME
 PJ46 'Q_SHORT_SM-EMPTY,SHORT6':;

SECTION_NUMBER 1
 '@S9S_MB_2U_LIB.S9S_MB_2U(SCH_1):PAGE260_I39@PURE_QUANTA.Q_SHORT(CHIPS)':
 C_PATH='@s9s_mb_2u_lib.s9s_mb_2u(sch_1):page260_i39@pure_quanta.q_short(chips)',
 P_PATH='@s9s_mb_2u_lib.s9s_mb_2u(sch_1):page274_i39@pure_quanta.q_short(chips)',
 PATH='I39',
 DRAWING='@S9S_MB_2U_LIB.S9S_MB_2U(SCH_1):PAGE260',
 PHYS_PAGE='274',
 XY='(-9900,4475)',
 ROT='0',
 VER='1',
 PACK_TYPE='SM',
 LOCATION='PJ46',
 CDS_LIB='pure_quanta',
 CDS_PART_NAME='Q_SHORT_SM-EMPTY,SHORT6',
 MATERIAL='EMPTY',
 PRIM_FILE='./archive_libs/logical/q_short/chips/chips.prt';

PART_NAME
 PJ47 'Q_SHORT_SM-EMPTY,SHORT6':;

SECTION_NUMBER 1
 '@S9S_MB_2U_LIB.S9S_MB_2U(SCH_1):PAGE252_I37@PURE_QUANTA.Q_SHORT(CHIPS)':
 C_PATH='@s9s_mb_2u_lib.s9s_mb_2u(sch_1):page252_i37@pure_quanta.q_short(chips)',
 P_PATH='@s9s_mb_2u_lib.s9s_mb_2u(sch_1):page266_i37@pure_quanta.q_short(chips)',
 PATH='I37',
 DRAWING='@S9S_MB_2U_LIB.S9S_MB_2U(SCH_1):PAGE252',
 PHYS_PAGE='266',
 XY='(-5825,4550)',
 ROT='0',
 VER='1',
 PACK_TYPE='SM',
 LOCATION='PJ47',
 CDS_LIB='pure_quanta',
 CDS_PART_NAME='Q_SHORT_SM-EMPTY,SHORT6',
 MATERIAL='EMPTY',
 PRIM_FILE='./archive_libs/logical/q_short/chips/chips.prt';

PART_NAME
 PJ48 'Q_SHORT_SM-EMPTY,SHORT6':;

SECTION_NUMBER 1
 '@S9S_MB_2U_LIB.S9S_MB_2U(SCH_1):PAGE282_I16@PURE_QUANTA.Q_SHORT(CHIPS)':
 C_PATH='@s9s_mb_2u_lib.s9s_mb_2u(sch_1):page282_i16@pure_quanta.q_short(chips)',
 P_PATH='@s9s_mb_2u_lib.s9s_mb_2u(sch_1):page296_i16@pure_quanta.q_short(chips)',
 PATH='I16',
 DRAWING='@S9S_MB_2U_LIB.S9S_MB_2U(SCH_1):PAGE282',
 PHYS_PAGE='296',
 XY='(-6025,3450)',
 ROT='0',
 VER='1',
 PACK_TYPE='SM',
 LOCATION='PJ48',
 CDS_LIB='pure_quanta',
 CDS_PART_NAME='Q_SHORT_SM-EMPTY,SHORT6',
 MATERIAL='EMPTY',
 PRIM_FILE='./archive_libs/logical/q_short/chips/chips.prt';

PART_NAME
 PJ49 'Q_SHORT_SM-EMPTY,SHORT6':;

SECTION_NUMBER 1
 '@S9S_MB_2U_LIB.S9S_MB_2U(SCH_1):PAGE270_I22@PURE_QUANTA.Q_SHORT(CHIPS)':
 C_PATH='@s9s_mb_2u_lib.s9s_mb_2u(sch_1):page270_i22@pure_quanta.q_short(chips)',
 P_PATH='@s9s_mb_2u_lib.s9s_mb_2u(sch_1):page284_i22@pure_quanta.q_short(chips)',
 PATH='I22',
 DRAWING='@S9S_MB_2U_LIB.S9S_MB_2U(SCH_1):PAGE270',
 PHYS_PAGE='284',
 XY='(-2875,-75)',
 ROT='0',
 VER='1',
 PACK_TYPE='SM',
 LOCATION='PJ49',
 CDS_LIB='pure_quanta',
 CDS_PART_NAME='Q_SHORT_SM-EMPTY,SHORT6',
 MATERIAL='EMPTY',
 PRIM_FILE='./archive_libs/logical/q_short/chips/chips.prt';

PART_NAME
 PJ50 'Q_SHORT_SM-EMPTY,SHORT6':;

SECTION_NUMBER 1
 '@S9S_MB_2U_LIB.S9S_MB_2U(SCH_1):PAGE278_I54@PURE_QUANTA.Q_SHORT(CHIPS)':
 C_PATH='@s9s_mb_2u_lib.s9s_mb_2u(sch_1):page278_i54@pure_quanta.q_short(chips)',
 P_PATH='@s9s_mb_2u_lib.s9s_mb_2u(sch_1):page292_i54@pure_quanta.q_short(chips)',
 PATH='I54',
 DRAWING='@S9S_MB_2U_LIB.S9S_MB_2U(SCH_1):PAGE278',
 PHYS_PAGE='292',
 XY='(475,7150)',
 ROT='0',
 VER='1',
 PACK_TYPE='SM',
 LOCATION='PJ50',
 CDS_LIB='pure_quanta',
 CDS_PART_NAME='Q_SHORT_SM-EMPTY,SHORT6',
 MATERIAL='EMPTY',
 PRIM_FILE='./archive_libs/logical/q_short/chips/chips.prt';

PART_NAME
 PJ51 'Q_SHORT_SM-EMPTY,SHORT6':;

SECTION_NUMBER 1
 '@S9S_MB_2U_LIB.S9S_MB_2U(SCH_1):PAGE278_I44@PURE_QUANTA.Q_SHORT(CHIPS)':
 C_PATH='@s9s_mb_2u_lib.s9s_mb_2u(sch_1):page278_i44@pure_quanta.q_short(chips)',
 P_PATH='@s9s_mb_2u_lib.s9s_mb_2u(sch_1):page292_i44@pure_quanta.q_short(chips)',
 PATH='I44',
 DRAWING='@S9S_MB_2U_LIB.S9S_MB_2U(SCH_1):PAGE278',
 PHYS_PAGE='292',
 XY='(475,6050)',
 ROT='0',
 VER='1',
 PACK_TYPE='SM',
 LOCATION='PJ51',
 CDS_LIB='pure_quanta',
 CDS_PART_NAME='Q_SHORT_SM-EMPTY,SHORT6',
 MATERIAL='EMPTY',
 PRIM_FILE='./archive_libs/logical/q_short/chips/chips.prt';

PART_NAME
 PJ52 'Q_SHORT_SM-EMPTY,SHORT6':;

SECTION_NUMBER 1
 '@S9S_MB_2U_LIB.S9S_MB_2U(SCH_1):PAGE270_I46@PURE_QUANTA.Q_SHORT(CHIPS)':
 C_PATH='@s9s_mb_2u_lib.s9s_mb_2u(sch_1):page270_i46@pure_quanta.q_short(chips)',
 P_PATH='@s9s_mb_2u_lib.s9s_mb_2u(sch_1):page284_i46@pure_quanta.q_short(chips)',
 PATH='I46',
 DRAWING='@S9S_MB_2U_LIB.S9S_MB_2U(SCH_1):PAGE270',
 PHYS_PAGE='284',
 XY='(-2875,1025)',
 ROT='0',
 VER='1',
 PACK_TYPE='SM',
 LOCATION='PJ52',
 CDS_LIB='pure_quanta',
 CDS_PART_NAME='Q_SHORT_SM-EMPTY,SHORT6',
 MATERIAL='EMPTY',
 PRIM_FILE='./archive_libs/logical/q_short/chips/chips.prt';

PART_NAME
 PJ53 'Q_SHORT_SM-EMPTY,SHORT6':;

SECTION_NUMBER 1
 '@S9S_MB_2U_LIB.S9S_MB_2U(SCH_1):PAGE252_I24@PURE_QUANTA.Q_SHORT(CHIPS)':
 C_PATH='@s9s_mb_2u_lib.s9s_mb_2u(sch_1):page252_i24@pure_quanta.q_short(chips)',
 P_PATH='@s9s_mb_2u_lib.s9s_mb_2u(sch_1):page266_i24@pure_quanta.q_short(chips)',
 PATH='I24',
 DRAWING='@S9S_MB_2U_LIB.S9S_MB_2U(SCH_1):PAGE252',
 PHYS_PAGE='266',
 XY='(-5825,3450)',
 ROT='0',
 VER='1',
 PACK_TYPE='SM',
 LOCATION='PJ53',
 CDS_LIB='pure_quanta',
 CDS_PART_NAME='Q_SHORT_SM-EMPTY,SHORT6',
 MATERIAL='EMPTY',
 PRIM_FILE='./archive_libs/logical/q_short/chips/chips.prt';

PART_NAME
 PJ54 'Q_SHORT_SM-EMPTY,SHORT6':;

SECTION_NUMBER 1
 '@S9S_MB_2U_LIB.S9S_MB_2U(SCH_1):PAGE264_I32@PURE_QUANTA.Q_SHORT(CHIPS)':
 C_PATH='@s9s_mb_2u_lib.s9s_mb_2u(sch_1):page264_i32@pure_quanta.q_short(chips)',
 P_PATH='@s9s_mb_2u_lib.s9s_mb_2u(sch_1):page278_i32@pure_quanta.q_short(chips)',
 PATH='I32',
 DRAWING='@S9S_MB_2U_LIB.S9S_MB_2U(SCH_1):PAGE264',
 PHYS_PAGE='278',
 XY='(-10550,6950)',
 ROT='0',
 VER='1',
 PACK_TYPE='SM',
 LOCATION='PJ54',
 CDS_LIB='pure_quanta',
 CDS_PART_NAME='Q_SHORT_SM-EMPTY,SHORT6',
 MATERIAL='EMPTY',
 PRIM_FILE='./archive_libs/logical/q_short/chips/chips.prt';

PART_NAME
 PJ62 'Q_SHORT_SM-EMPTY,SHORT6':;

SECTION_NUMBER 1
 '@S9S_MB_2U_LIB.S9S_MB_2U(SCH_1):PAGE248_I43@PURE_QUANTA.Q_SHORT(CHIPS)':
 C_PATH='@s9s_mb_2u_lib.s9s_mb_2u(sch_1):page248_i43@pure_quanta.q_short(chips)',
 P_PATH='@s9s_mb_2u_lib.s9s_mb_2u(sch_1):page262_i43@pure_quanta.q_short(chips)',
 PATH='I43',
 DRAWING='@S9S_MB_2U_LIB.S9S_MB_2U(SCH_1):PAGE248',
 BOM_COST='VR_PCH',
 PHYS_PAGE='262',
 XY='(3000,-1050)',
 ROT='0',
 VER='1',
 PACK_TYPE='SM',
 LOCATION='PJ62',
 CDS_LIB='pure_quanta',
 CDS_PART_NAME='Q_SHORT_SM-EMPTY,SHORT6',
 MATERIAL='EMPTY',
 PRIM_FILE='./archive_libs/logical/q_short/chips/chips.prt';

PART_NAME
 PJ63 'Q_SHORT_SM-EMPTY,SHORT6':;

SECTION_NUMBER 1
 '@S9S_MB_2U_LIB.S9S_MB_2U(SCH_1):PAGE248_I42@PURE_QUANTA.Q_SHORT(CHIPS)':
 C_PATH='@s9s_mb_2u_lib.s9s_mb_2u(sch_1):page248_i42@pure_quanta.q_short(chips)',
 P_PATH='@s9s_mb_2u_lib.s9s_mb_2u(sch_1):page262_i42@pure_quanta.q_short(chips)',
 PATH='I42',
 DRAWING='@S9S_MB_2U_LIB.S9S_MB_2U(SCH_1):PAGE248',
 BOM_COST='VR_PCH',
 PHYS_PAGE='262',
 XY='(3000,-1525)',
 ROT='0',
 VER='1',
 PACK_TYPE='SM',
 LOCATION='PJ63',
 CDS_LIB='pure_quanta',
 CDS_PART_NAME='Q_SHORT_SM-EMPTY,SHORT6',
 MATERIAL='EMPTY',
 PRIM_FILE='./archive_libs/logical/q_short/chips/chips.prt';

PART_NAME
 PJ64 'Q_SHORT_SM-EMPTY,SHORT6':;

SECTION_NUMBER 1
 '@S9S_MB_2U_LIB.S9S_MB_2U(SCH_1):PAGE267_I41@PURE_QUANTA.Q_SHORT(CHIPS)':
 C_PATH='@s9s_mb_2u_lib.s9s_mb_2u(sch_1):page267_i41@pure_quanta.q_short(chips)',
 P_PATH='@s9s_mb_2u_lib.s9s_mb_2u(sch_1):page281_i41@pure_quanta.q_short(chips)',
 PATH='I41',
 DRAWING='@S9S_MB_2U_LIB.S9S_MB_2U(SCH_1):PAGE267',
 BOM_COST='VR_PCH',
 PHYS_PAGE='281',
 XY='(-4600,2875)',
 ROT='0',
 VER='1',
 PACK_TYPE='SM',
 LOCATION='PJ64',
 CDS_LIB='pure_quanta',
 CDS_PART_NAME='Q_SHORT_SM-EMPTY,SHORT6',
 MATERIAL='EMPTY',
 PRIM_FILE='./archive_libs/logical/q_short/chips/chips.prt';

PART_NAME
 PJ65 'Q_SHORT_SM-EMPTY,SHORT6':;

SECTION_NUMBER 1
 '@S9S_MB_2U_LIB.S9S_MB_2U(SCH_1):PAGE267_I33@PURE_QUANTA.Q_SHORT(CHIPS)':
 C_PATH='@s9s_mb_2u_lib.s9s_mb_2u(sch_1):page267_i33@pure_quanta.q_short(chips)',
 P_PATH='@s9s_mb_2u_lib.s9s_mb_2u(sch_1):page281_i33@pure_quanta.q_short(chips)',
 PATH='I33',
 DRAWING='@S9S_MB_2U_LIB.S9S_MB_2U(SCH_1):PAGE267',
 BOM_COST='VR_PCH',
 PHYS_PAGE='281',
 XY='(-4600,1900)',
 ROT='0',
 VER='1',
 PACK_TYPE='SM',
 LOCATION='PJ65',
 CDS_LIB='pure_quanta',
 CDS_PART_NAME='Q_SHORT_SM-EMPTY,SHORT6',
 MATERIAL='EMPTY',
 PRIM_FILE='./archive_libs/logical/q_short/chips/chips.prt';

PART_NAME
 PJ66 'Q_SHORT_SM-EMPTY,SHORT6':;

SECTION_NUMBER 1
 '@S9S_MB_2U_LIB.S9S_MB_2U(SCH_1):PAGE285_I46@PURE_QUANTA.Q_SHORT(CHIPS)':
 C_PATH='@s9s_mb_2u_lib.s9s_mb_2u(sch_1):page285_i46@pure_quanta.q_short(chips)',
 P_PATH='@s9s_mb_2u_lib.s9s_mb_2u(sch_1):page299_i46@pure_quanta.q_short(chips)',
 PATH='I46',
 DRAWING='@S9S_MB_2U_LIB.S9S_MB_2U(SCH_1):PAGE285',
 BOM_COST='VR_PCH',
 PHYS_PAGE='299',
 XY='(-3950,2425)',
 ROT='0',
 VER='1',
 PACK_TYPE='SM',
 LOCATION='PJ66',
 CDS_LIB='pure_quanta',
 CDS_PART_NAME='Q_SHORT_SM-EMPTY,SHORT6',
 MATERIAL='EMPTY',
 PRIM_FILE='./archive_libs/logical/q_short/chips/chips.prt';

PART_NAME
 PJ67 'Q_SHORT_SM-EMPTY,SHORT6':;

SECTION_NUMBER 1
 '@S9S_MB_2U_LIB.S9S_MB_2U(SCH_1):PAGE285_I44@PURE_QUANTA.Q_SHORT(CHIPS)':
 C_PATH='@s9s_mb_2u_lib.s9s_mb_2u(sch_1):page285_i44@pure_quanta.q_short(chips)',
 P_PATH='@s9s_mb_2u_lib.s9s_mb_2u(sch_1):page299_i44@pure_quanta.q_short(chips)',
 PATH='I44',
 DRAWING='@S9S_MB_2U_LIB.S9S_MB_2U(SCH_1):PAGE285',
 BOM_COST='VR_PCH',
 PHYS_PAGE='299',
 XY='(-3950,1425)',
 ROT='0',
 VER='1',
 PACK_TYPE='SM',
 LOCATION='PJ67',
 CDS_LIB='pure_quanta',
 CDS_PART_NAME='Q_SHORT_SM-EMPTY,SHORT6',
 MATERIAL='EMPTY',
 PRIM_FILE='./archive_libs/logical/q_short/chips/chips.prt';

PART_NAME
 PJP1 'CONN3_210HP1030BR1-CONN3_210-HB':;

SECTION_NUMBER 1
 '@S9S_MB_2U_LIB.S9S_MB_2U(SCH_1):PAGE252_I32@PURE_QUANTA.CONN3_210HP1030BR1(CHIPS)':
 C_PATH='@s9s_mb_2u_lib.s9s_mb_2u(sch_1):page252_i32@pure_quanta.conn3_210hp1030~
br1(chips)',
 P_PATH='@s9s_mb_2u_lib.s9s_mb_2u(sch_1):page266_i32@pure_quanta.conn3_210hp1030~
br1(chips)',
 PATH='I32',
 DRAWING='@S9S_MB_2U_LIB.S9S_MB_2U(SCH_1):PAGE252',
 PHYS_PAGE='266',
 XY='(-6525,5600)',
 ROT='4',
 VER='1',
 LOCATION='PJP1',
 SEC='1',
 CDS_LIB='pure_quanta',
 CDS_PART_NAME='CONN3_210HP1030BR1-CONN3_210-HB',
 SEC_TYPE='',
 PART_TYPE='THLF',
 MATERIAL='IO',
 VALUE='CONN3_210-HP1-030BR1',
 PRIM_FILE='./archive_libs/logical/conn3_210hp1030br1/chips/chips.prt';

PART_NAME
 PL2 'Q_INDUCTOR_SMLF-130NH/106A,INDA':;

SECTION_NUMBER 1
 '@S9S_MB_2U_LIB.S9S_MB_2U(SCH_1):PAGE258_I51@PURE_QUANTA.Q_INDUCTOR(CHIPS)':
 C_PATH='@s9s_mb_2u_lib.s9s_mb_2u(sch_1):page258_i51@pure_quanta.q_inductor(chip~
s)',
 P_PATH='@s9s_mb_2u_lib.s9s_mb_2u(sch_1):page272_i51@pure_quanta.q_inductor(chip~
s)',
 PATH='I51',
 DRAWING='@S9S_MB_2U_LIB.S9S_MB_2U(SCH_1):PAGE258',
 PHYS_PAGE='272',
 XY='(-6475,4925)',
 ROT='0',
 VER='1',
 PACK_TYPE='SMLF',
 LOCATION='PL2',
 CDS_LIB='pure_quanta',
 CDS_PART_NAME='Q_INDUCTOR_SMLF-130NH/106A,INDA',
 MATERIAL='IND',
 VALUE='130NH/106A',
 PRIM_FILE='./archive_libs/logical/q_inductor/chips/chips.prt';

PART_NAME
 PL3 'Q_INDUCTOR_SMLF-300NH/33A,IND,A':;

SECTION_NUMBER 1
 '@S9S_MB_2U_LIB.S9S_MB_2U(SCH_1):PAGE262_I29@PURE_QUANTA.Q_INDUCTOR(CHIPS)':
 C_PATH='@s9s_mb_2u_lib.s9s_mb_2u(sch_1):page262_i29@pure_quanta.q_inductor(chip~
s)',
 P_PATH='@s9s_mb_2u_lib.s9s_mb_2u(sch_1):page276_i29@pure_quanta.q_inductor(chip~
s)',
 PATH='I29',
 DRAWING='@S9S_MB_2U_LIB.S9S_MB_2U(SCH_1):PAGE262',
 PHYS_PAGE='276',
 XY='(-5400,3575)',
 ROT='0',
 VER='1',
 PACK_TYPE='SMLF',
 LOCATION='PL3',
 CDS_LIB='pure_quanta',
 CDS_PART_NAME='Q_INDUCTOR_SMLF-300NH/33A,IND,A',
 MATERIAL='IND',
 VALUE='300NH/33A',
 PRIM_FILE='./archive_libs/logical/q_inductor/chips/chips.prt';

PART_NAME
 PL4 'Q_INDUCTOR_SMLF-120NH/69A,IND,A':;

SECTION_NUMBER 1
 '@S9S_MB_2U_LIB.S9S_MB_2U(SCH_1):PAGE261_I52@PURE_QUANTA.Q_INDUCTOR(CHIPS)':
 C_PATH='@s9s_mb_2u_lib.s9s_mb_2u(sch_1):page261_i52@pure_quanta.q_inductor(chip~
s)',
 P_PATH='@s9s_mb_2u_lib.s9s_mb_2u(sch_1):page275_i52@pure_quanta.q_inductor(chip~
s)',
 PATH='I52',
 DRAWING='@S9S_MB_2U_LIB.S9S_MB_2U(SCH_1):PAGE261',
 PHYS_PAGE='275',
 XY='(-6450,4800)',
 ROT='0',
 VER='1',
 PACK_TYPE='SMLF',
 LOCATION='PL4',
 CDS_LIB='pure_quanta',
 CDS_PART_NAME='Q_INDUCTOR_SMLF-120NH/69A,IND,A',
 MATERIAL='IND',
 VALUE='120NH/69A',
 PRIM_FILE='./archive_libs/logical/q_inductor/chips/chips.prt';

PART_NAME
 PL5 'Q_INDUCTOR_SMLF-120NH/69A,IND,A':;

SECTION_NUMBER 1
 '@S9S_MB_2U_LIB.S9S_MB_2U(SCH_1):PAGE261_I39@PURE_QUANTA.Q_INDUCTOR(CHIPS)':
 C_PATH='@s9s_mb_2u_lib.s9s_mb_2u(sch_1):page261_i39@pure_quanta.q_inductor(chip~
s)',
 P_PATH='@s9s_mb_2u_lib.s9s_mb_2u(sch_1):page275_i39@pure_quanta.q_inductor(chip~
s)',
 PATH='I39',
 DRAWING='@S9S_MB_2U_LIB.S9S_MB_2U(SCH_1):PAGE261',
 PHYS_PAGE='275',
 XY='(-6450,2000)',
 ROT='0',
 VER='1',
 PACK_TYPE='SMLF',
 LOCATION='PL5',
 CDS_LIB='pure_quanta',
 CDS_PART_NAME='Q_INDUCTOR_SMLF-120NH/69A,IND,A',
 MATERIAL='IND',
 VALUE='120NH/69A',
 PRIM_FILE='./archive_libs/logical/q_inductor/chips/chips.prt';

PART_NAME
 PL6 'Q_INDUCTOR_SMLF-100NH/16A,IND,A':;

SECTION_NUMBER 1
 '@S9S_MB_2U_LIB.S9S_MB_2U(SCH_1):PAGE261_I62@PURE_QUANTA.Q_INDUCTOR(CHIPS)':
 C_PATH='@s9s_mb_2u_lib.s9s_mb_2u(sch_1):page261_i62@pure_quanta.q_inductor(chip~
s)',
 P_PATH='@s9s_mb_2u_lib.s9s_mb_2u(sch_1):page275_i62@pure_quanta.q_inductor(chip~
s)',
 PATH='I62',
 DRAWING='@S9S_MB_2U_LIB.S9S_MB_2U(SCH_1):PAGE261',
 PHYS_PAGE='275',
 XY='(-4600,6125)',
 ROT='0',
 VER='1',
 PACK_TYPE='SMLF',
 LOCATION='PL6',
 CDS_LIB='pure_quanta',
 CDS_PART_NAME='Q_INDUCTOR_SMLF-100NH/16A,IND,A',
 MATERIAL='IND',
 VALUE='100NH/16A',
 PRIM_FILE='./archive_libs/logical/q_inductor/chips/chips.prt';

PART_NAME
 PL7 'Q_INDUCTOR4P_14-150NH,SMLF,INDA':;

SECTION_NUMBER 1
 '@S9S_MB_2U_LIB.S9S_MB_2U(SCH_1):PAGE256_I44@PURE_QUANTA.Q_INDUCTOR4P_14(CHIPS)':
 C_PATH='@s9s_mb_2u_lib.s9s_mb_2u(sch_1):page256_i44@pure_quanta.q_inductor4p_14~
(chips)',
 P_PATH='@s9s_mb_2u_lib.s9s_mb_2u(sch_1):page270_i44@pure_quanta.q_inductor4p_14~
(chips)',
 PATH='I44',
 DRAWING='@S9S_MB_2U_LIB.S9S_MB_2U(SCH_1):PAGE256',
 PHYS_PAGE='270',
 XY='(-3175,-5525)',
 ROT='0',
 VER='1',
 LOCATION='PL7',
 SEC='1',
 CDS_LIB='pure_quanta',
 CDS_PART_NAME='Q_INDUCTOR4P_14-150NH,SMLF,INDA',
 SEC_TYPE='',
 PART_TYPE='SMLF',
 MATERIAL='IND',
 VALUE='150NH',
 PRIM_FILE='./archive_libs/logical/q_inductor4p_14/chips/chips.prt';

PART_NAME
 PL8 'Q_INDUCTOR4P_14-150NH,SMLF,INDA':;

SECTION_NUMBER 1
 '@S9S_MB_2U_LIB.S9S_MB_2U(SCH_1):PAGE256_I58@PURE_QUANTA.Q_INDUCTOR4P_14(CHIPS)':
 C_PATH='@s9s_mb_2u_lib.s9s_mb_2u(sch_1):page256_i58@pure_quanta.q_inductor4p_14~
(chips)',
 P_PATH='@s9s_mb_2u_lib.s9s_mb_2u(sch_1):page270_i58@pure_quanta.q_inductor4p_14~
(chips)',
 PATH='I58',
 DRAWING='@S9S_MB_2U_LIB.S9S_MB_2U(SCH_1):PAGE256',
 PHYS_PAGE='270',
 XY='(-3350,-2700)',
 ROT='0',
 VER='1',
 LOCATION='PL8',
 SEC='1',
 CDS_LIB='pure_quanta',
 CDS_PART_NAME='Q_INDUCTOR4P_14-150NH,SMLF,INDA',
 SEC_TYPE='',
 PART_TYPE='SMLF',
 MATERIAL='IND',
 VALUE='150NH',
 PRIM_FILE='./archive_libs/logical/q_inductor4p_14/chips/chips.prt';

PART_NAME
 PL9 'Q_INDUCTOR4P_14-150NH,SMLF,INDA':;

SECTION_NUMBER 1
 '@S9S_MB_2U_LIB.S9S_MB_2U(SCH_1):PAGE255_I32@PURE_QUANTA.Q_INDUCTOR4P_14(CHIPS)':
 C_PATH='@s9s_mb_2u_lib.s9s_mb_2u(sch_1):page255_i32@pure_quanta.q_inductor4p_14~
(chips)',
 P_PATH='@s9s_mb_2u_lib.s9s_mb_2u(sch_1):page269_i32@pure_quanta.q_inductor4p_14~
(chips)',
 PATH='I32',
 DRAWING='@S9S_MB_2U_LIB.S9S_MB_2U(SCH_1):PAGE255',
 PHYS_PAGE='269',
 XY='(6025,1775)',
 ROT='0',
 VER='1',
 LOCATION='PL9',
 SEC='1',
 CDS_LIB='pure_quanta',
 CDS_PART_NAME='Q_INDUCTOR4P_14-150NH,SMLF,INDA',
 SEC_TYPE='',
 PART_TYPE='SMLF',
 MATERIAL='IND',
 VALUE='150NH',
 PRIM_FILE='./archive_libs/logical/q_inductor4p_14/chips/chips.prt';

PART_NAME
 PL10 'Q_INDUCTOR4P_14-150NH,SMLF,INDA':;

SECTION_NUMBER 1
 '@S9S_MB_2U_LIB.S9S_MB_2U(SCH_1):PAGE255_I50@PURE_QUANTA.Q_INDUCTOR4P_14(CHIPS)':
 C_PATH='@s9s_mb_2u_lib.s9s_mb_2u(sch_1):page255_i50@pure_quanta.q_inductor4p_14~
(chips)',
 P_PATH='@s9s_mb_2u_lib.s9s_mb_2u(sch_1):page269_i50@pure_quanta.q_inductor4p_14~
(chips)',
 PATH='I50',
 DRAWING='@S9S_MB_2U_LIB.S9S_MB_2U(SCH_1):PAGE255',
 PHYS_PAGE='269',
 XY='(6075,4600)',
 ROT='0',
 VER='1',
 LOCATION='PL10',
 SEC='1',
 CDS_LIB='pure_quanta',
 CDS_PART_NAME='Q_INDUCTOR4P_14-150NH,SMLF,INDA',
 SEC_TYPE='',
 PART_TYPE='SMLF',
 MATERIAL='IND',
 VALUE='150NH',
 PRIM_FILE='./archive_libs/logical/q_inductor4p_14/chips/chips.prt';

PART_NAME
 PL11 'Q_INDUCTOR4P_14-150NH,SMLF,INDA':;

SECTION_NUMBER 1
 '@S9S_MB_2U_LIB.S9S_MB_2U(SCH_1):PAGE254_I33@PURE_QUANTA.Q_INDUCTOR4P_14(CHIPS)':
 C_PATH='@s9s_mb_2u_lib.s9s_mb_2u(sch_1):page254_i33@pure_quanta.q_inductor4p_14~
(chips)',
 P_PATH='@s9s_mb_2u_lib.s9s_mb_2u(sch_1):page268_i33@pure_quanta.q_inductor4p_14~
(chips)',
 PATH='I33',
 DRAWING='@S9S_MB_2U_LIB.S9S_MB_2U(SCH_1):PAGE254',
 PHYS_PAGE='268',
 XY='(6950,1375)',
 ROT='0',
 VER='1',
 LOCATION='PL11',
 SEC='1',
 CDS_LIB='pure_quanta',
 CDS_PART_NAME='Q_INDUCTOR4P_14-150NH,SMLF,INDA',
 SEC_TYPE='',
 PART_TYPE='SMLF',
 MATERIAL='IND',
 VALUE='150NH',
 PRIM_FILE='./archive_libs/logical/q_inductor4p_14/chips/chips.prt';

PART_NAME
 PL12 'Q_INDUCTOR_SMLF-130NH/106A,INDA':;

SECTION_NUMBER 1
 '@S9S_MB_2U_LIB.S9S_MB_2U(SCH_1):PAGE276_I57@PURE_QUANTA.Q_INDUCTOR(CHIPS)':
 C_PATH='@s9s_mb_2u_lib.s9s_mb_2u(sch_1):page276_i57@pure_quanta.q_inductor(chip~
s)',
 P_PATH='@s9s_mb_2u_lib.s9s_mb_2u(sch_1):page290_i57@pure_quanta.q_inductor(chip~
s)',
 PATH='I57',
 DRAWING='@S9S_MB_2U_LIB.S9S_MB_2U(SCH_1):PAGE276',
 PHYS_PAGE='290',
 XY='(-3100,6650)',
 ROT='0',
 VER='1',
 PACK_TYPE='SMLF',
 LOCATION='PL12',
 CDS_LIB='pure_quanta',
 CDS_PART_NAME='Q_INDUCTOR_SMLF-130NH/106A,INDA',
 MATERIAL='IND',
 VALUE='130NH/106A',
 PRIM_FILE='./archive_libs/logical/q_inductor/chips/chips.prt';

PART_NAME
 PL13 'Q_INDUCTOR4P_14-150NH,SMLF,INDA':;

SECTION_NUMBER 1
 '@S9S_MB_2U_LIB.S9S_MB_2U(SCH_1):PAGE253_I21@PURE_QUANTA.Q_INDUCTOR4P_14(CHIPS)':
 C_PATH='@s9s_mb_2u_lib.s9s_mb_2u(sch_1):page253_i21@pure_quanta.q_inductor4p_14~
(chips)',
 P_PATH='@s9s_mb_2u_lib.s9s_mb_2u(sch_1):page267_i21@pure_quanta.q_inductor4p_14~
(chips)',
 PATH='I21',
 DRAWING='@S9S_MB_2U_LIB.S9S_MB_2U(SCH_1):PAGE253',
 PHYS_PAGE='267',
 XY='(250,-2250)',
 ROT='0',
 VER='1',
 LOCATION='PL13',
 SEC='1',
 CDS_LIB='pure_quanta',
 CDS_PART_NAME='Q_INDUCTOR4P_14-150NH,SMLF,INDA',
 SEC_TYPE='',
 PART_TYPE='SMLF',
 MATERIAL='IND',
 VALUE='150NH',
 PRIM_FILE='./archive_libs/logical/q_inductor4p_14/chips/chips.prt';

PART_NAME
 PL14 'Q_INDUCTOR_SMLF-100NH/16A,IND,A':;

SECTION_NUMBER 1
 '@S9S_MB_2U_LIB.S9S_MB_2U(SCH_1):PAGE276_I64@PURE_QUANTA.Q_INDUCTOR(CHIPS)':
 C_PATH='@s9s_mb_2u_lib.s9s_mb_2u(sch_1):page276_i64@pure_quanta.q_inductor(chip~
s)',
 P_PATH='@s9s_mb_2u_lib.s9s_mb_2u(sch_1):page290_i64@pure_quanta.q_inductor(chip~
s)',
 PATH='I64',
 DRAWING='@S9S_MB_2U_LIB.S9S_MB_2U(SCH_1):PAGE276',
 PHYS_PAGE='290',
 XY='(-1650,7525)',
 ROT='0',
 VER='1',
 PACK_TYPE='SMLF',
 LOCATION='PL14',
 CDS_LIB='pure_quanta',
 CDS_PART_NAME='Q_INDUCTOR_SMLF-100NH/16A,IND,A',
 MATERIAL='IND',
 VALUE='100NH/16A',
 PRIM_FILE='./archive_libs/logical/q_inductor/chips/chips.prt';

PART_NAME
 PL15 'Q_INDUCTOR_SMLF-50NH/148A,IND,A':;

SECTION_NUMBER 1
 '@S9S_MB_2U_LIB.S9S_MB_2U(SCH_1):PAGE253_I82@PURE_QUANTA.Q_INDUCTOR(CHIPS)':
 C_PATH='@s9s_mb_2u_lib.s9s_mb_2u(sch_1):page253_i82@pure_quanta.q_inductor(chip~
s)',
 P_PATH='@s9s_mb_2u_lib.s9s_mb_2u(sch_1):page267_i82@pure_quanta.q_inductor(chip~
s)',
 PATH='I82',
 DRAWING='@S9S_MB_2U_LIB.S9S_MB_2U(SCH_1):PAGE253',
 PHYS_PAGE='267',
 XY='(1875,2050)',
 ROT='0',
 VER='1',
 PACK_TYPE='SMLF',
 LOCATION='PL15',
 CDS_LIB='pure_quanta',
 CDS_PART_NAME='Q_INDUCTOR_SMLF-50NH/148A,IND,A',
 MATERIAL='IND',
 VALUE='50NH/148A',
 PRIM_FILE='./archive_libs/logical/q_inductor/chips/chips.prt';

PART_NAME
 PL16 'Q_INDUCTOR_SMLF-BLM18SN220TN1DA':;

SECTION_NUMBER 1
 '@S9S_MB_2U_LIB.S9S_MB_2U(SCH_1):PAGE249_I16@PURE_QUANTA.Q_INDUCTOR(CHIPS)':
 C_PATH='@s9s_mb_2u_lib.s9s_mb_2u(sch_1):page249_i16@pure_quanta.q_inductor(chip~
s)',
 P_PATH='@s9s_mb_2u_lib.s9s_mb_2u(sch_1):page263_i16@pure_quanta.q_inductor(chip~
s)',
 PATH='I16',
 DRAWING='@S9S_MB_2U_LIB.S9S_MB_2U(SCH_1):PAGE249',
 PHYS_PAGE='263',
 XY='(-5975,7250)',
 ROT='0',
 VER='1',
 PACK_TYPE='SMLF',
 LOCATION='PL16',
 CDS_LIB='pure_quanta',
 CDS_PART_NAME='Q_INDUCTOR_SMLF-BLM18SN220TN1DA',
 MATERIAL='IND',
 VALUE='BLM18SN220TN1D/8000MA',
 PRIM_FILE='./archive_libs/logical/q_inductor/chips/chips.prt';

PART_NAME
 PL17 'Q_INDUCTOR_SMLF-120NH/69A,IND,A':;

SECTION_NUMBER 1
 '@S9S_MB_2U_LIB.S9S_MB_2U(SCH_1):PAGE283_I14@PURE_QUANTA.Q_INDUCTOR(CHIPS)':
 C_PATH='@s9s_mb_2u_lib.s9s_mb_2u(sch_1):page283_i14@pure_quanta.q_inductor(chip~
s)',
 P_PATH='@s9s_mb_2u_lib.s9s_mb_2u(sch_1):page297_i14@pure_quanta.q_inductor(chip~
s)',
 PATH='I14',
 DRAWING='@S9S_MB_2U_LIB.S9S_MB_2U(SCH_1):PAGE283',
 PHYS_PAGE='297',
 XY='(-4025,3650)',
 ROT='0',
 VER='1',
 PACK_TYPE='SMLF',
 LOCATION='PL17',
 CDS_LIB='pure_quanta',
 CDS_PART_NAME='Q_INDUCTOR_SMLF-120NH/69A,IND,A',
 MATERIAL='IND',
 VALUE='120NH/69A',
 PRIM_FILE='./archive_libs/logical/q_inductor/chips/chips.prt';

PART_NAME
 PL18 'Q_INDUCTOR_SMLF-130NH/106A,INDA':;

SECTION_NUMBER 1
 '@S9S_MB_2U_LIB.S9S_MB_2U(SCH_1):PAGE275_I55@PURE_QUANTA.Q_INDUCTOR(CHIPS)':
 C_PATH='@s9s_mb_2u_lib.s9s_mb_2u(sch_1):page275_i55@pure_quanta.q_inductor(chip~
s)',
 P_PATH='@s9s_mb_2u_lib.s9s_mb_2u(sch_1):page289_i55@pure_quanta.q_inductor(chip~
s)',
 PATH='I55',
 DRAWING='@S9S_MB_2U_LIB.S9S_MB_2U(SCH_1):PAGE275',
 PHYS_PAGE='289',
 XY='(-6025,4700)',
 ROT='0',
 VER='1',
 PACK_TYPE='SMLF',
 LOCATION='PL18',
 CDS_LIB='pure_quanta',
 CDS_PART_NAME='Q_INDUCTOR_SMLF-130NH/106A,INDA',
 MATERIAL='IND',
 VALUE='130NH/106A',
 PRIM_FILE='./archive_libs/logical/q_inductor/chips/chips.prt';

PART_NAME
 PL19 'Q_INDUCTOR_SMLF-130NH/106A,INDA':;

SECTION_NUMBER 1
 '@S9S_MB_2U_LIB.S9S_MB_2U(SCH_1):PAGE275_I44@PURE_QUANTA.Q_INDUCTOR(CHIPS)':
 C_PATH='@s9s_mb_2u_lib.s9s_mb_2u(sch_1):page275_i44@pure_quanta.q_inductor(chip~
s)',
 P_PATH='@s9s_mb_2u_lib.s9s_mb_2u(sch_1):page289_i44@pure_quanta.q_inductor(chip~
s)',
 PATH='I44',
 DRAWING='@S9S_MB_2U_LIB.S9S_MB_2U(SCH_1):PAGE275',
 PHYS_PAGE='289',
 XY='(-6025,1900)',
 ROT='0',
 VER='1',
 PACK_TYPE='SMLF',
 LOCATION='PL19',
 CDS_LIB='pure_quanta',
 CDS_PART_NAME='Q_INDUCTOR_SMLF-130NH/106A,INDA',
 MATERIAL='IND',
 VALUE='130NH/106A',
 PRIM_FILE='./archive_libs/logical/q_inductor/chips/chips.prt';

PART_NAME
 PL20 'Q_INDUCTOR_SMLF-300NH/33A,IND,A':;

SECTION_NUMBER 1
 '@S9S_MB_2U_LIB.S9S_MB_2U(SCH_1):PAGE280_I23@PURE_QUANTA.Q_INDUCTOR(CHIPS)':
 C_PATH='@s9s_mb_2u_lib.s9s_mb_2u(sch_1):page280_i23@pure_quanta.q_inductor(chip~
s)',
 P_PATH='@s9s_mb_2u_lib.s9s_mb_2u(sch_1):page294_i23@pure_quanta.q_inductor(chip~
s)',
 PATH='I23',
 DRAWING='@S9S_MB_2U_LIB.S9S_MB_2U(SCH_1):PAGE280',
 PHYS_PAGE='294',
 XY='(-2225,9225)',
 ROT='0',
 VER='1',
 PACK_TYPE='SMLF',
 LOCATION='PL20',
 CDS_LIB='pure_quanta',
 CDS_PART_NAME='Q_INDUCTOR_SMLF-300NH/33A,IND,A',
 MATERIAL='IND',
 VALUE='300NH/33A',
 PRIM_FILE='./archive_libs/logical/q_inductor/chips/chips.prt';

PART_NAME
 PL21 'Q_INDUCTOR_SMLF-120NH/69A,IND,A':;

SECTION_NUMBER 1
 '@S9S_MB_2U_LIB.S9S_MB_2U(SCH_1):PAGE279_I54@PURE_QUANTA.Q_INDUCTOR(CHIPS)':
 C_PATH='@s9s_mb_2u_lib.s9s_mb_2u(sch_1):page279_i54@pure_quanta.q_inductor(chip~
s)',
 P_PATH='@s9s_mb_2u_lib.s9s_mb_2u(sch_1):page293_i54@pure_quanta.q_inductor(chip~
s)',
 PATH='I54',
 DRAWING='@S9S_MB_2U_LIB.S9S_MB_2U(SCH_1):PAGE279',
 PHYS_PAGE='293',
 XY='(-4575,11250)',
 ROT='0',
 VER='1',
 PACK_TYPE='SMLF',
 LOCATION='PL21',
 CDS_LIB='pure_quanta',
 CDS_PART_NAME='Q_INDUCTOR_SMLF-120NH/69A,IND,A',
 MATERIAL='IND',
 VALUE='120NH/69A',
 PRIM_FILE='./archive_libs/logical/q_inductor/chips/chips.prt';

PART_NAME
 PL22 'Q_INDUCTOR_SMLF-120NH/69A,IND,A':;

SECTION_NUMBER 1
 '@S9S_MB_2U_LIB.S9S_MB_2U(SCH_1):PAGE279_I46@PURE_QUANTA.Q_INDUCTOR(CHIPS)':
 C_PATH='@s9s_mb_2u_lib.s9s_mb_2u(sch_1):page279_i46@pure_quanta.q_inductor(chip~
s)',
 P_PATH='@s9s_mb_2u_lib.s9s_mb_2u(sch_1):page293_i46@pure_quanta.q_inductor(chip~
s)',
 PATH='I46',
 DRAWING='@S9S_MB_2U_LIB.S9S_MB_2U(SCH_1):PAGE279',
 PHYS_PAGE='293',
 XY='(-4575,8450)',
 ROT='0',
 VER='1',
 PACK_TYPE='SMLF',
 LOCATION='PL22',
 CDS_LIB='pure_quanta',
 CDS_PART_NAME='Q_INDUCTOR_SMLF-120NH/69A,IND,A',
 MATERIAL='IND',
 VALUE='120NH/69A',
 PRIM_FILE='./archive_libs/logical/q_inductor/chips/chips.prt';

PART_NAME
 PL23 'Q_INDUCTOR_SMLF-100NH/16A,IND,A':;

SECTION_NUMBER 1
 '@S9S_MB_2U_LIB.S9S_MB_2U(SCH_1):PAGE279_I78@PURE_QUANTA.Q_INDUCTOR(CHIPS)':
 C_PATH='@s9s_mb_2u_lib.s9s_mb_2u(sch_1):page279_i78@pure_quanta.q_inductor(chip~
s)',
 P_PATH='@s9s_mb_2u_lib.s9s_mb_2u(sch_1):page293_i78@pure_quanta.q_inductor(chip~
s)',
 PATH='I78',
 DRAWING='@S9S_MB_2U_LIB.S9S_MB_2U(SCH_1):PAGE279',
 PHYS_PAGE='293',
 XY='(-2700,12575)',
 ROT='0',
 VER='1',
 PACK_TYPE='SMLF',
 LOCATION='PL23',
 CDS_LIB='pure_quanta',
 CDS_PART_NAME='Q_INDUCTOR_SMLF-100NH/16A,IND,A',
 MATERIAL='IND',
 VALUE='100NH/16A',
 PRIM_FILE='./archive_libs/logical/q_inductor/chips/chips.prt';

PART_NAME
 PL24 'Q_INDUCTOR4P_14-150NH,SMLF,INDA':;

SECTION_NUMBER 1
 '@S9S_MB_2U_LIB.S9S_MB_2U(SCH_1):PAGE274_I43@PURE_QUANTA.Q_INDUCTOR4P_14(CHIPS)':
 C_PATH='@s9s_mb_2u_lib.s9s_mb_2u(sch_1):page274_i43@pure_quanta.q_inductor4p_14~
(chips)',
 P_PATH='@s9s_mb_2u_lib.s9s_mb_2u(sch_1):page288_i43@pure_quanta.q_inductor4p_14~
(chips)',
 PATH='I43',
 DRAWING='@S9S_MB_2U_LIB.S9S_MB_2U(SCH_1):PAGE274',
 PHYS_PAGE='288',
 XY='(-3500,1575)',
 ROT='0',
 VER='1',
 LOCATION='PL24',
 SEC='1',
 CDS_LIB='pure_quanta',
 CDS_PART_NAME='Q_INDUCTOR4P_14-150NH,SMLF,INDA',
 SEC_TYPE='',
 PART_TYPE='SMLF',
 MATERIAL='IND',
 VALUE='150NH',
 PRIM_FILE='./archive_libs/logical/q_inductor4p_14/chips/chips.prt';

PART_NAME
 PL25 'Q_INDUCTOR4P_14-150NH,SMLF,INDA':;

SECTION_NUMBER 1
 '@S9S_MB_2U_LIB.S9S_MB_2U(SCH_1):PAGE274_I58@PURE_QUANTA.Q_INDUCTOR4P_14(CHIPS)':
 C_PATH='@s9s_mb_2u_lib.s9s_mb_2u(sch_1):page274_i58@pure_quanta.q_inductor4p_14~
(chips)',
 P_PATH='@s9s_mb_2u_lib.s9s_mb_2u(sch_1):page288_i58@pure_quanta.q_inductor4p_14~
(chips)',
 PATH='I58',
 DRAWING='@S9S_MB_2U_LIB.S9S_MB_2U(SCH_1):PAGE274',
 PHYS_PAGE='288',
 XY='(-3550,4400)',
 ROT='0',
 VER='1',
 LOCATION='PL25',
 SEC='1',
 CDS_LIB='pure_quanta',
 CDS_PART_NAME='Q_INDUCTOR4P_14-150NH,SMLF,INDA',
 SEC_TYPE='',
 PART_TYPE='SMLF',
 MATERIAL='IND',
 VALUE='150NH',
 PRIM_FILE='./archive_libs/logical/q_inductor4p_14/chips/chips.prt';

PART_NAME
 PL26 'Q_INDUCTOR4P_14-150NH,SMLF,INDA':;

SECTION_NUMBER 1
 '@S9S_MB_2U_LIB.S9S_MB_2U(SCH_1):PAGE273_I28@PURE_QUANTA.Q_INDUCTOR4P_14(CHIPS)':
 C_PATH='@s9s_mb_2u_lib.s9s_mb_2u(sch_1):page273_i28@pure_quanta.q_inductor4p_14~
(chips)',
 P_PATH='@s9s_mb_2u_lib.s9s_mb_2u(sch_1):page287_i28@pure_quanta.q_inductor4p_14~
(chips)',
 PATH='I28',
 DRAWING='@S9S_MB_2U_LIB.S9S_MB_2U(SCH_1):PAGE273',
 PHYS_PAGE='287',
 XY='(7800,-450)',
 ROT='0',
 VER='1',
 LOCATION='PL26',
 SEC='1',
 CDS_LIB='pure_quanta',
 CDS_PART_NAME='Q_INDUCTOR4P_14-150NH,SMLF,INDA',
 SEC_TYPE='',
 PART_TYPE='SMLF',
 MATERIAL='IND',
 VALUE='150NH',
 PRIM_FILE='./archive_libs/logical/q_inductor4p_14/chips/chips.prt';

PART_NAME
 PL27 'Q_INDUCTOR4P_14-150NH,SMLF,INDA':;

SECTION_NUMBER 1
 '@S9S_MB_2U_LIB.S9S_MB_2U(SCH_1):PAGE273_I48@PURE_QUANTA.Q_INDUCTOR4P_14(CHIPS)':
 C_PATH='@s9s_mb_2u_lib.s9s_mb_2u(sch_1):page273_i48@pure_quanta.q_inductor4p_14~
(chips)',
 P_PATH='@s9s_mb_2u_lib.s9s_mb_2u(sch_1):page287_i48@pure_quanta.q_inductor4p_14~
(chips)',
 PATH='I48',
 DRAWING='@S9S_MB_2U_LIB.S9S_MB_2U(SCH_1):PAGE273',
 PHYS_PAGE='287',
 XY='(7775,2375)',
 ROT='0',
 VER='1',
 LOCATION='PL27',
 SEC='1',
 CDS_LIB='pure_quanta',
 CDS_PART_NAME='Q_INDUCTOR4P_14-150NH,SMLF,INDA',
 SEC_TYPE='',
 PART_TYPE='SMLF',
 MATERIAL='IND',
 VALUE='150NH',
 PRIM_FILE='./archive_libs/logical/q_inductor4p_14/chips/chips.prt';

PART_NAME
 PL28 'Q_INDUCTOR4P_14-150NH,SMLF,INDA':;

SECTION_NUMBER 1
 '@S9S_MB_2U_LIB.S9S_MB_2U(SCH_1):PAGE272_I37@PURE_QUANTA.Q_INDUCTOR4P_14(CHIPS)':
 C_PATH='@s9s_mb_2u_lib.s9s_mb_2u(sch_1):page272_i37@pure_quanta.q_inductor4p_14~
(chips)',
 P_PATH='@s9s_mb_2u_lib.s9s_mb_2u(sch_1):page286_i37@pure_quanta.q_inductor4p_14~
(chips)',
 PATH='I37',
 DRAWING='@S9S_MB_2U_LIB.S9S_MB_2U(SCH_1):PAGE272',
 PHYS_PAGE='286',
 XY='(1600,-1675)',
 ROT='0',
 VER='1',
 LOCATION='PL28',
 SEC='1',
 CDS_LIB='pure_quanta',
 CDS_PART_NAME='Q_INDUCTOR4P_14-150NH,SMLF,INDA',
 SEC_TYPE='',
 PART_TYPE='SMLF',
 MATERIAL='IND',
 VALUE='150NH',
 PRIM_FILE='./archive_libs/logical/q_inductor4p_14/chips/chips.prt';

PART_NAME
 PL29 'Q_INDUCTOR4P_14-150NH,SMLF,INDA':;

SECTION_NUMBER 1
 '@S9S_MB_2U_LIB.S9S_MB_2U(SCH_1):PAGE272_I51@PURE_QUANTA.Q_INDUCTOR4P_14(CHIPS)':
 C_PATH='@s9s_mb_2u_lib.s9s_mb_2u(sch_1):page272_i51@pure_quanta.q_inductor4p_14~
(chips)',
 P_PATH='@s9s_mb_2u_lib.s9s_mb_2u(sch_1):page286_i51@pure_quanta.q_inductor4p_14~
(chips)',
 PATH='I51',
 DRAWING='@S9S_MB_2U_LIB.S9S_MB_2U(SCH_1):PAGE272',
 PHYS_PAGE='286',
 XY='(1625,1150)',
 ROT='0',
 VER='1',
 LOCATION='PL29',
 SEC='1',
 CDS_LIB='pure_quanta',
 CDS_PART_NAME='Q_INDUCTOR4P_14-150NH,SMLF,INDA',
 SEC_TYPE='',
 PART_TYPE='SMLF',
 MATERIAL='IND',
 VALUE='150NH',
 PRIM_FILE='./archive_libs/logical/q_inductor4p_14/chips/chips.prt';

PART_NAME
 PL30 'Q_INDUCTOR4P_14-150NH,SMLF,INDA':;

SECTION_NUMBER 1
 '@S9S_MB_2U_LIB.S9S_MB_2U(SCH_1):PAGE271_I18@PURE_QUANTA.Q_INDUCTOR4P_14(CHIPS)':
 C_PATH='@s9s_mb_2u_lib.s9s_mb_2u(sch_1):page271_i18@pure_quanta.q_inductor4p_14~
(chips)',
 P_PATH='@s9s_mb_2u_lib.s9s_mb_2u(sch_1):page285_i18@pure_quanta.q_inductor4p_14~
(chips)',
 PATH='I18',
 DRAWING='@S9S_MB_2U_LIB.S9S_MB_2U(SCH_1):PAGE271',
 PHYS_PAGE='285',
 XY='(300,-1825)',
 ROT='0',
 VER='1',
 LOCATION='PL30',
 SEC='1',
 CDS_LIB='pure_quanta',
 CDS_PART_NAME='Q_INDUCTOR4P_14-150NH,SMLF,INDA',
 SEC_TYPE='',
 PART_TYPE='SMLF',
 MATERIAL='IND',
 VALUE='150NH',
 PRIM_FILE='./archive_libs/logical/q_inductor4p_14/chips/chips.prt';

PART_NAME
 PL31 'Q_INDUCTOR4P_14-150NH,SMLF,INDA':;

SECTION_NUMBER 1
 '@S9S_MB_2U_LIB.S9S_MB_2U(SCH_1):PAGE271_I74@PURE_QUANTA.Q_INDUCTOR4P_14(CHIPS)':
 C_PATH='@s9s_mb_2u_lib.s9s_mb_2u(sch_1):page271_i74@pure_quanta.q_inductor4p_14~
(chips)',
 P_PATH='@s9s_mb_2u_lib.s9s_mb_2u(sch_1):page285_i74@pure_quanta.q_inductor4p_14~
(chips)',
 PATH='I74',
 DRAWING='@S9S_MB_2U_LIB.S9S_MB_2U(SCH_1):PAGE271',
 PHYS_PAGE='285',
 XY='(775,1025)',
 ROT='0',
 VER='1',
 LOCATION='PL31',
 SEC='1',
 CDS_LIB='pure_quanta',
 CDS_PART_NAME='Q_INDUCTOR4P_14-150NH,SMLF,INDA',
 SEC_TYPE='',
 PART_TYPE='SMLF',
 MATERIAL='IND',
 VALUE='150NH',
 PRIM_FILE='./archive_libs/logical/q_inductor4p_14/chips/chips.prt';

PART_NAME
 PL32 'Q_INDUCTOR_SMLF-50NH/148A,IND,A':;

SECTION_NUMBER 1
 '@S9S_MB_2U_LIB.S9S_MB_2U(SCH_1):PAGE271_I83@PURE_QUANTA.Q_INDUCTOR(CHIPS)':
 C_PATH='@s9s_mb_2u_lib.s9s_mb_2u(sch_1):page271_i83@pure_quanta.q_inductor(chip~
s)',
 P_PATH='@s9s_mb_2u_lib.s9s_mb_2u(sch_1):page285_i83@pure_quanta.q_inductor(chip~
s)',
 PATH='I83',
 DRAWING='@S9S_MB_2U_LIB.S9S_MB_2U(SCH_1):PAGE271',
 PHYS_PAGE='285',
 XY='(1925,2475)',
 ROT='0',
 VER='1',
 PACK_TYPE='SMLF',
 LOCATION='PL32',
 CDS_LIB='pure_quanta',
 CDS_PART_NAME='Q_INDUCTOR_SMLF-50NH/148A,IND,A',
 MATERIAL='IND',
 VALUE='50NH/148A',
 PRIM_FILE='./archive_libs/logical/q_inductor/chips/chips.prt';

PART_NAME
 PL33 'Q_INDUCTOR_SMLF-130NH/106A,INDA':;

SECTION_NUMBER 1
 '@S9S_MB_2U_LIB.S9S_MB_2U(SCH_1):PAGE257_I70@PURE_QUANTA.Q_INDUCTOR(CHIPS)':
 C_PATH='@s9s_mb_2u_lib.s9s_mb_2u(sch_1):page257_i70@pure_quanta.q_inductor(chip~
s)',
 P_PATH='@s9s_mb_2u_lib.s9s_mb_2u(sch_1):page271_i70@pure_quanta.q_inductor(chip~
s)',
 PATH='I70',
 DRAWING='@S9S_MB_2U_LIB.S9S_MB_2U(SCH_1):PAGE257',
 PHYS_PAGE='271',
 XY='(-25,5225)',
 ROT='0',
 VER='1',
 PACK_TYPE='SMLF',
 LOCATION='PL33',
 CDS_LIB='pure_quanta',
 CDS_PART_NAME='Q_INDUCTOR_SMLF-130NH/106A,INDA',
 MATERIAL='IND',
 VALUE='130NH/106A',
 PRIM_FILE='./archive_libs/logical/q_inductor/chips/chips.prt';

PART_NAME
 PL34 'Q_INDUCTOR_SMLF-130NH/106A,INDA':;

SECTION_NUMBER 1
 '@S9S_MB_2U_LIB.S9S_MB_2U(SCH_1):PAGE257_I49@PURE_QUANTA.Q_INDUCTOR(CHIPS)':
 C_PATH='@s9s_mb_2u_lib.s9s_mb_2u(sch_1):page257_i49@pure_quanta.q_inductor(chip~
s)',
 P_PATH='@s9s_mb_2u_lib.s9s_mb_2u(sch_1):page271_i49@pure_quanta.q_inductor(chip~
s)',
 PATH='I49',
 DRAWING='@S9S_MB_2U_LIB.S9S_MB_2U(SCH_1):PAGE257',
 PHYS_PAGE='271',
 XY='(-25,2425)',
 ROT='0',
 VER='1',
 PACK_TYPE='SMLF',
 LOCATION='PL34',
 CDS_LIB='pure_quanta',
 CDS_PART_NAME='Q_INDUCTOR_SMLF-130NH/106A,INDA',
 MATERIAL='IND',
 VALUE='130NH/106A',
 PRIM_FILE='./archive_libs/logical/q_inductor/chips/chips.prt';

PART_NAME
 PL35 'Q_INDUCTOR_SMLF-120NH/69A,IND,A':;

SECTION_NUMBER 1
 '@S9S_MB_2U_LIB.S9S_MB_2U(SCH_1):PAGE265_I30@PURE_QUANTA.Q_INDUCTOR(CHIPS)':
 C_PATH='@s9s_mb_2u_lib.s9s_mb_2u(sch_1):page265_i30@pure_quanta.q_inductor(chip~
s)',
 P_PATH='@s9s_mb_2u_lib.s9s_mb_2u(sch_1):page279_i30@pure_quanta.q_inductor(chip~
s)',
 PATH='I30',
 DRAWING='@S9S_MB_2U_LIB.S9S_MB_2U(SCH_1):PAGE265',
 PHYS_PAGE='279',
 XY='(-4200,1950)',
 ROT='0',
 VER='1',
 PACK_TYPE='SMLF',
 LOCATION='PL35',
 CDS_LIB='pure_quanta',
 CDS_PART_NAME='Q_INDUCTOR_SMLF-120NH/69A,IND,A',
 MATERIAL='IND',
 VALUE='120NH/69A',
 PRIM_FILE='./archive_libs/logical/q_inductor/chips/chips.prt';

PART_NAME
 PL43 'Q_INDUCTOR_SMLF-100NH/16A,IND,A':;

SECTION_NUMBER 1
 '@S9S_MB_2U_LIB.S9S_MB_2U(SCH_1):PAGE275_I79@PURE_QUANTA.Q_INDUCTOR(CHIPS)':
 C_PATH='@s9s_mb_2u_lib.s9s_mb_2u(sch_1):page275_i79@pure_quanta.q_inductor(chip~
s)',
 P_PATH='@s9s_mb_2u_lib.s9s_mb_2u(sch_1):page289_i79@pure_quanta.q_inductor(chip~
s)',
 PATH='I79',
 DRAWING='@S9S_MB_2U_LIB.S9S_MB_2U(SCH_1):PAGE275',
 PHYS_PAGE='289',
 XY='(-4575,5575)',
 ROT='0',
 VER='1',
 PACK_TYPE='SMLF',
 LOCATION='PL43',
 CDS_LIB='pure_quanta',
 CDS_PART_NAME='Q_INDUCTOR_SMLF-100NH/16A,IND,A',
 MATERIAL='IND',
 VALUE='100NH/16A',
 PRIM_FILE='./archive_libs/logical/q_inductor/chips/chips.prt';

PART_NAME
 PL44 'Q_INDUCTOR_SMLF-100NH/16A,IND,A':;

SECTION_NUMBER 1
 '@S9S_MB_2U_LIB.S9S_MB_2U(SCH_1):PAGE257_I80@PURE_QUANTA.Q_INDUCTOR(CHIPS)':
 C_PATH='@s9s_mb_2u_lib.s9s_mb_2u(sch_1):page257_i80@pure_quanta.q_inductor(chip~
s)',
 P_PATH='@s9s_mb_2u_lib.s9s_mb_2u(sch_1):page271_i80@pure_quanta.q_inductor(chip~
s)',
 PATH='I80',
 DRAWING='@S9S_MB_2U_LIB.S9S_MB_2U(SCH_1):PAGE257',
 PHYS_PAGE='271',
 XY='(1425,6100)',
 ROT='0',
 VER='1',
 PACK_TYPE='SMLF',
 LOCATION='PL44',
 CDS_LIB='pure_quanta',
 CDS_PART_NAME='Q_INDUCTOR_SMLF-100NH/16A,IND,A',
 MATERIAL='IND',
 VALUE='100NH/16A',
 PRIM_FILE='./archive_libs/logical/q_inductor/chips/chips.prt';

PART_NAME
 PL45 'Q_INDUCTOR_SMLF-100NH/16A,IND,A':;

SECTION_NUMBER 1
 '@S9S_MB_2U_LIB.S9S_MB_2U(SCH_1):PAGE245_I98@PURE_QUANTA.Q_INDUCTOR(CHIPS)':
 C_PATH='@s9s_mb_2u_lib.s9s_mb_2u(sch_1):page245_i98@pure_quanta.q_inductor(chip~
s)',
 P_PATH='@s9s_mb_2u_lib.s9s_mb_2u(sch_1):page259_i98@pure_quanta.q_inductor(chip~
s)',
 PATH='I98',
 DRAWING='@S9S_MB_2U_LIB.S9S_MB_2U(SCH_1):PAGE245',
 PHYS_PAGE='259',
 XY='(-4300,1075)',
 ROT='0',
 VER='1',
 PACK_TYPE='SMLF',
 LOCATION='PL45',
 CDS_LIB='pure_quanta',
 CDS_PART_NAME='Q_INDUCTOR_SMLF-100NH/16A,IND,A',
 MATERIAL='IND',
 VALUE='100NH/16A',
 PRIM_FILE='./archive_libs/logical/q_inductor/chips/chips.prt';

PART_NAME
 PL64 'Q_INDUCTOR_SMLF-BLM18SN220TN1DA':;

SECTION_NUMBER 1
 '@S9S_MB_2U_LIB.S9S_MB_2U(SCH_1):PAGE244_I5@PURE_QUANTA.Q_INDUCTOR(CHIPS)':
 C_PATH='@s9s_mb_2u_lib.s9s_mb_2u(sch_1):page244_i5@pure_quanta.q_inductor(chips~
)',
 P_PATH='@s9s_mb_2u_lib.s9s_mb_2u(sch_1):page258_i5@pure_quanta.q_inductor(chips~
)',
 PATH='I5',
 DRAWING='@S9S_MB_2U_LIB.S9S_MB_2U(SCH_1):PAGE244',
 PHYS_PAGE='258',
 XY='(-7475,7000)',
 ROT='0',
 VER='1',
 PACK_TYPE='SMLF',
 LOCATION='PL64',
 CDS_LIB='pure_quanta',
 CDS_PART_NAME='Q_INDUCTOR_SMLF-BLM18SN220TN1DA',
 MATERIAL='IND',
 VALUE='BLM18SN220TN1D/8000MA',
 PRIM_FILE='./archive_libs/logical/q_inductor/chips/chips.prt';

PART_NAME
 PL65 'Q_INDUCTOR_SMLF-4.7UH,IND,CV-4A':;

SECTION_NUMBER 1
 '@S9S_MB_2U_LIB.S9S_MB_2U(SCH_1):PAGE244_I30@PURE_QUANTA.Q_INDUCTOR(CHIPS)':
 C_PATH='@s9s_mb_2u_lib.s9s_mb_2u(sch_1):page244_i30@pure_quanta.q_inductor(chip~
s)',
 P_PATH='@s9s_mb_2u_lib.s9s_mb_2u(sch_1):page258_i30@pure_quanta.q_inductor(chip~
s)',
 PATH='I30',
 DRAWING='@S9S_MB_2U_LIB.S9S_MB_2U(SCH_1):PAGE244',
 PHYS_PAGE='258',
 XY='(-2400,6225)',
 ROT='0',
 VER='1',
 PACK_TYPE='SMLF',
 LOCATION='PL65',
 CDS_LIB='pure_quanta',
 CDS_PART_NAME='Q_INDUCTOR_SMLF-4.7UH,IND,CV-4A',
 MATERIAL='IND',
 VALUE='4.7UH',
 PRIM_FILE='./archive_libs/logical/q_inductor/chips/chips.prt';

PART_NAME
 PL66 'Q_INDUCTOR_SMLF-1.5UH/53A,IND,A':;

SECTION_NUMBER 1
 '@S9S_MB_2U_LIB.S9S_MB_2U(SCH_1):PAGE245_I129@PURE_QUANTA.Q_INDUCTOR(CHIPS)':
 C_PATH='@s9s_mb_2u_lib.s9s_mb_2u(sch_1):page245_i129@pure_quanta.q_inductor(chi~
ps)',
 P_PATH='@s9s_mb_2u_lib.s9s_mb_2u(sch_1):page259_i129@pure_quanta.q_inductor(chi~
ps)',
 PATH='I129',
 DRAWING='@S9S_MB_2U_LIB.S9S_MB_2U(SCH_1):PAGE245',
 PHYS_PAGE='259',
 XY='(1425,-725)',
 ROT='0',
 VER='1',
 PACK_TYPE='SMLF',
 LOCATION='PL66',
 CDS_LIB='pure_quanta',
 CDS_PART_NAME='Q_INDUCTOR_SMLF-1.5UH/53A,IND,A',
 MATERIAL='IND',
 VALUE='1.5UH/53A',
 PRIM_FILE='./archive_libs/logical/q_inductor/chips/chips.prt';

PART_NAME
 PL101 'Q_INDUCTOR_SMLF-100NH/16A,IND,A':;

SECTION_NUMBER 1
 '@S9S_MB_2U_LIB.S9S_MB_2U(SCH_1):PAGE258_I59@PURE_QUANTA.Q_INDUCTOR(CHIPS)':
 C_PATH='@s9s_mb_2u_lib.s9s_mb_2u(sch_1):page258_i59@pure_quanta.q_inductor(chip~
s)',
 P_PATH='@s9s_mb_2u_lib.s9s_mb_2u(sch_1):page272_i59@pure_quanta.q_inductor(chip~
s)',
 PATH='I59',
 DRAWING='@S9S_MB_2U_LIB.S9S_MB_2U(SCH_1):PAGE258',
 PHYS_PAGE='272',
 XY='(-5025,5800)',
 ROT='0',
 VER='1',
 PACK_TYPE='SMLF',
 LOCATION='PL101',
 CDS_LIB='pure_quanta',
 CDS_PART_NAME='Q_INDUCTOR_SMLF-100NH/16A,IND,A',
 MATERIAL='IND',
 VALUE='100NH/16A',
 PRIM_FILE='./archive_libs/logical/q_inductor/chips/chips.prt';

PART_NAME
 PL105 'Q_INDUCTOR_SMLF-120NH/69A,IND,A':;

SECTION_NUMBER 1
 '@S9S_MB_2U_LIB.S9S_MB_2U(SCH_1):PAGE256_I39@PURE_QUANTA.Q_INDUCTOR(CHIPS)':
 C_PATH='@s9s_mb_2u_lib.s9s_mb_2u(sch_1):page256_i39@pure_quanta.q_inductor(chip~
s)',
 P_PATH='@s9s_mb_2u_lib.s9s_mb_2u(sch_1):page270_i39@pure_quanta.q_inductor(chip~
s)',
 PATH='I39',
 DRAWING='@S9S_MB_2U_LIB.S9S_MB_2U(SCH_1):PAGE256',
 PHYS_PAGE='270',
 XY='(-4325,-2800)',
 ROT='2',
 VER='1',
 PACK_TYPE='SMLF',
 LOCATION='PL105',
 CDS_LIB='pure_quanta',
 CDS_PART_NAME='Q_INDUCTOR_SMLF-120NH/69A,IND,A',
 MATERIAL='IND',
 VALUE='120NH/69A',
 PRIM_FILE='./archive_libs/logical/q_inductor/chips/chips.prt';

PART_NAME
 PL106 'Q_INDUCTOR_SMLF-120NH/69A,IND,A':;

SECTION_NUMBER 1
 '@S9S_MB_2U_LIB.S9S_MB_2U(SCH_1):PAGE274_I23@PURE_QUANTA.Q_INDUCTOR(CHIPS)':
 C_PATH='@s9s_mb_2u_lib.s9s_mb_2u(sch_1):page274_i23@pure_quanta.q_inductor(chip~
s)',
 P_PATH='@s9s_mb_2u_lib.s9s_mb_2u(sch_1):page288_i23@pure_quanta.q_inductor(chip~
s)',
 PATH='I23',
 DRAWING='@S9S_MB_2U_LIB.S9S_MB_2U(SCH_1):PAGE274',
 PHYS_PAGE='288',
 XY='(-4550,1475)',
 ROT='2',
 VER='1',
 PACK_TYPE='SMLF',
 LOCATION='PL106',
 CDS_LIB='pure_quanta',
 CDS_PART_NAME='Q_INDUCTOR_SMLF-120NH/69A,IND,A',
 MATERIAL='IND',
 VALUE='120NH/69A',
 PRIM_FILE='./archive_libs/logical/q_inductor/chips/chips.prt';

PART_NAME
 PL110 'Q_INDUCTOR_SMLF-100NH/16A,IND,A':;

SECTION_NUMBER 1
 '@S9S_MB_2U_LIB.S9S_MB_2U(SCH_1):PAGE248_I19@PURE_QUANTA.Q_INDUCTOR(CHIPS)':
 C_PATH='@s9s_mb_2u_lib.s9s_mb_2u(sch_1):page248_i19@pure_quanta.q_inductor(chip~
s)',
 P_PATH='@s9s_mb_2u_lib.s9s_mb_2u(sch_1):page262_i19@pure_quanta.q_inductor(chip~
s)',
 PATH='I19',
 DRAWING='@S9S_MB_2U_LIB.S9S_MB_2U(SCH_1):PAGE248',
 PHYS_PAGE='262',
 XY='(-4575,650)',
 ROT='0',
 VER='1',
 PACK_TYPE='SMLF',
 LOCATION='PL110',
 CDS_LIB='pure_quanta',
 CDS_PART_NAME='Q_INDUCTOR_SMLF-100NH/16A,IND,A',
 MATERIAL='IND',
 VALUE='100NH/16A',
 PRIM_FILE='./archive_libs/logical/q_inductor/chips/chips.prt';

PART_NAME
 PL112 'Q_INDUCTOR4P_14-150NH,SMLF,INDA':;

SECTION_NUMBER 1
 '@S9S_MB_2U_LIB.S9S_MB_2U(SCH_1):PAGE254_I50@PURE_QUANTA.Q_INDUCTOR4P_14(CHIPS)':
 C_PATH='@s9s_mb_2u_lib.s9s_mb_2u(sch_1):page254_i50@pure_quanta.q_inductor4p_14~
(chips)',
 P_PATH='@s9s_mb_2u_lib.s9s_mb_2u(sch_1):page268_i50@pure_quanta.q_inductor4p_14~
(chips)',
 PATH='I50',
 DRAWING='@S9S_MB_2U_LIB.S9S_MB_2U(SCH_1):PAGE254',
 PHYS_PAGE='268',
 XY='(7000,4200)',
 ROT='0',
 VER='1',
 LOCATION='PL112',
 SEC='1',
 CDS_LIB='pure_quanta',
 CDS_PART_NAME='Q_INDUCTOR4P_14-150NH,SMLF,INDA',
 SEC_TYPE='',
 PART_TYPE='SMLF',
 MATERIAL='IND',
 VALUE='150NH',
 PRIM_FILE='./archive_libs/logical/q_inductor4p_14/chips/chips.prt';

PART_NAME
 PL113 'Q_INDUCTOR_SMLF-130NH/106A,INDA':;

SECTION_NUMBER 1
 '@S9S_MB_2U_LIB.S9S_MB_2U(SCH_1):PAGE276_I44@PURE_QUANTA.Q_INDUCTOR(CHIPS)':
 C_PATH='@s9s_mb_2u_lib.s9s_mb_2u(sch_1):page276_i44@pure_quanta.q_inductor(chip~
s)',
 P_PATH='@s9s_mb_2u_lib.s9s_mb_2u(sch_1):page290_i44@pure_quanta.q_inductor(chip~
s)',
 PATH='I44',
 DRAWING='@S9S_MB_2U_LIB.S9S_MB_2U(SCH_1):PAGE276',
 PHYS_PAGE='290',
 XY='(-3100,3850)',
 ROT='0',
 VER='1',
 PACK_TYPE='SMLF',
 LOCATION='PL113',
 CDS_LIB='pure_quanta',
 CDS_PART_NAME='Q_INDUCTOR_SMLF-130NH/106A,INDA',
 MATERIAL='IND',
 VALUE='130NH/106A',
 PRIM_FILE='./archive_libs/logical/q_inductor/chips/chips.prt';

PART_NAME
 PL114 'Q_INDUCTOR4P_14-150NH,SMLF,INDA':;

SECTION_NUMBER 1
 '@S9S_MB_2U_LIB.S9S_MB_2U(SCH_1):PAGE253_I46@PURE_QUANTA.Q_INDUCTOR4P_14(CHIPS)':
 C_PATH='@s9s_mb_2u_lib.s9s_mb_2u(sch_1):page253_i46@pure_quanta.q_inductor4p_14~
(chips)',
 P_PATH='@s9s_mb_2u_lib.s9s_mb_2u(sch_1):page267_i46@pure_quanta.q_inductor4p_14~
(chips)',
 PATH='I46',
 DRAWING='@S9S_MB_2U_LIB.S9S_MB_2U(SCH_1):PAGE253',
 PHYS_PAGE='267',
 XY='(175,575)',
 ROT='0',
 VER='1',
 LOCATION='PL114',
 SEC='1',
 CDS_LIB='pure_quanta',
 CDS_PART_NAME='Q_INDUCTOR4P_14-150NH,SMLF,INDA',
 SEC_TYPE='',
 PART_TYPE='SMLF',
 MATERIAL='IND',
 VALUE='150NH',
 PRIM_FILE='./archive_libs/logical/q_inductor4p_14/chips/chips.prt';

PART_NAME
 PL118 'Q_INDUCTOR_SMLF-0.68UH,IND,CV+A':;

SECTION_NUMBER 1
 '@S9S_MB_2U_LIB.S9S_MB_2U(SCH_1):PAGE267_I28@PURE_QUANTA.Q_INDUCTOR(CHIPS)':
 C_PATH='@s9s_mb_2u_lib.s9s_mb_2u(sch_1):page267_i28@pure_quanta.q_inductor(chip~
s)',
 P_PATH='@s9s_mb_2u_lib.s9s_mb_2u(sch_1):page281_i28@pure_quanta.q_inductor(chip~
s)',
 PATH='I28',
 DRAWING='@S9S_MB_2U_LIB.S9S_MB_2U(SCH_1):PAGE267',
 BOM_COST='VR_PCH',
 PHYS_PAGE='281',
 XY='(-6525,3650)',
 ROT='0',
 VER='1',
 PACK_TYPE='SMLF',
 LOCATION='PL118',
 CDS_LIB='pure_quanta',
 CDS_PART_NAME='Q_INDUCTOR_SMLF-0.68UH,IND,CV+A',
 MATERIAL='IND',
 VALUE='0.68UH',
 PRIM_FILE='./archive_libs/logical/q_inductor/chips/chips.prt';

PART_NAME
 PL119 'Q_INDUCTOR_SMLF-0.68UH,IND,CV+A':;

SECTION_NUMBER 1
 '@S9S_MB_2U_LIB.S9S_MB_2U(SCH_1):PAGE285_I33@PURE_QUANTA.Q_INDUCTOR(CHIPS)':
 C_PATH='@s9s_mb_2u_lib.s9s_mb_2u(sch_1):page285_i33@pure_quanta.q_inductor(chip~
s)',
 P_PATH='@s9s_mb_2u_lib.s9s_mb_2u(sch_1):page299_i33@pure_quanta.q_inductor(chip~
s)',
 PATH='I33',
 DRAWING='@S9S_MB_2U_LIB.S9S_MB_2U(SCH_1):PAGE285',
 BOM_COST='VR_PCH',
 PHYS_PAGE='299',
 XY='(-5900,3200)',
 ROT='0',
 VER='1',
 PACK_TYPE='SMLF',
 LOCATION='PL119',
 CDS_LIB='pure_quanta',
 CDS_PART_NAME='Q_INDUCTOR_SMLF-0.68UH,IND,CV+A',
 MATERIAL='IND',
 VALUE='0.68UH',
 PRIM_FILE='./archive_libs/logical/q_inductor/chips/chips.prt';

PART_NAME
 PL120 'Q_INDUCTOR_SMLF-4.7UH,IND,CV-4B':;

SECTION_NUMBER 1
 '@S9S_MB_2U_LIB.S9S_MB_2U(SCH_1):PAGE268_I29@PURE_QUANTA.Q_INDUCTOR(CHIPS)':
 C_PATH='@s9s_mb_2u_lib.s9s_mb_2u(sch_1):page268_i29@pure_quanta.q_inductor(chip~
s)',
 P_PATH='@s9s_mb_2u_lib.s9s_mb_2u(sch_1):page282_i29@pure_quanta.q_inductor(chip~
s)',
 PATH='I29',
 DRAWING='@S9S_MB_2U_LIB.S9S_MB_2U(SCH_1):PAGE268',
 BOM_COST='VR_PCH',
 PHYS_PAGE='282',
 XY='(-4475,9875)',
 ROT='0',
 VER='1',
 PACK_TYPE='SMLF',
 LOCATION='PL120',
 CDS_LIB='pure_quanta',
 CDS_PART_NAME='Q_INDUCTOR_SMLF-4.7UH,IND,CV-4B',
 MATERIAL='IND',
 VALUE='4.7UH',
 PRIM_FILE='./archive_libs/logical/q_inductor/chips/chips.prt';

PART_NAME
 PL121 'Q_INDUCTOR_SMLF-4.7UH,IND,CV-4B':;

SECTION_NUMBER 1
 '@S9S_MB_2U_LIB.S9S_MB_2U(SCH_1):PAGE286_I27@PURE_QUANTA.Q_INDUCTOR(CHIPS)':
 C_PATH='@s9s_mb_2u_lib.s9s_mb_2u(sch_1):page286_i27@pure_quanta.q_inductor(chip~
s)',
 P_PATH='@s9s_mb_2u_lib.s9s_mb_2u(sch_1):page300_i27@pure_quanta.q_inductor(chip~
s)',
 PATH='I27',
 DRAWING='@S9S_MB_2U_LIB.S9S_MB_2U(SCH_1):PAGE286',
 BOM_COST='VR_PCH',
 PHYS_PAGE='300',
 XY='(7300,7250)',
 ROT='0',
 VER='1',
 PACK_TYPE='SMLF',
 LOCATION='PL121',
 CDS_LIB='pure_quanta',
 CDS_PART_NAME='Q_INDUCTOR_SMLF-4.7UH,IND,CV-4B',
 MATERIAL='IND',
 VALUE='4.7UH',
 PRIM_FILE='./archive_libs/logical/q_inductor/chips/chips.prt';

PART_NAME
 PL150 'Q_INDUCTOR_SMLF-300NH/33A,IND,A':;

SECTION_NUMBER 1
 '@S9S_MB_2U_LIB.S9S_MB_2U(SCH_1):PAGE248_I53@PURE_QUANTA.Q_INDUCTOR(CHIPS)':
 C_PATH='@s9s_mb_2u_lib.s9s_mb_2u(sch_1):page248_i53@pure_quanta.q_inductor(chip~
s)',
 P_PATH='@s9s_mb_2u_lib.s9s_mb_2u(sch_1):page262_i53@pure_quanta.q_inductor(chip~
s)',
 PATH='I53',
 DRAWING='@S9S_MB_2U_LIB.S9S_MB_2U(SCH_1):PAGE248',
 BOM_COST='VR_PCH',
 PHYS_PAGE='262',
 XY='(1375,-325)',
 ROT='0',
 VER='1',
 PACK_TYPE='SMLF',
 LOCATION='PL150',
 CDS_LIB='pure_quanta',
 CDS_PART_NAME='Q_INDUCTOR_SMLF-300NH/33A,IND,A',
 MATERIAL='IND',
 VALUE='300NH/33A',
 PRIM_FILE='./archive_libs/logical/q_inductor/chips/chips.prt';

PART_NAME
 PL170 'Q_INDUCTOR_SMLF-2.2UH,IND,CV-2A':;

SECTION_NUMBER 1
 '@S9S_MB_2U_LIB.S9S_MB_2U(SCH_1):PAGE249_I45@PURE_QUANTA.Q_INDUCTOR(CHIPS)':
 C_PATH='@s9s_mb_2u_lib.s9s_mb_2u(sch_1):page249_i45@pure_quanta.q_inductor(chip~
s)',
 P_PATH='@s9s_mb_2u_lib.s9s_mb_2u(sch_1):page263_i45@pure_quanta.q_inductor(chip~
s)',
 PATH='I45',
 DRAWING='@S9S_MB_2U_LIB.S9S_MB_2U(SCH_1):PAGE249',
 BOM_COST='VR_PCH',
 PHYS_PAGE='263',
 XY='(-1175,6275)',
 ROT='0',
 VER='1',
 PACK_TYPE='SMLF',
 LOCATION='PL170',
 CDS_LIB='pure_quanta',
 CDS_PART_NAME='Q_INDUCTOR_SMLF-2.2UH,IND,CV-2A',
 MATERIAL='IND',
 VALUE='2.2UH',
 PRIM_FILE='./archive_libs/logical/q_inductor/chips/chips.prt';

PART_NAME
 PL210 'Q_INDUCTOR_SMLF-130NH/106A,INDA':;

SECTION_NUMBER 1
 '@S9S_MB_2U_LIB.S9S_MB_2U(SCH_1):PAGE258_I39@PURE_QUANTA.Q_INDUCTOR(CHIPS)':
 C_PATH='@s9s_mb_2u_lib.s9s_mb_2u(sch_1):page258_i39@pure_quanta.q_inductor(chip~
s)',
 P_PATH='@s9s_mb_2u_lib.s9s_mb_2u(sch_1):page272_i39@pure_quanta.q_inductor(chip~
s)',
 PATH='I39',
 DRAWING='@S9S_MB_2U_LIB.S9S_MB_2U(SCH_1):PAGE258',
 PHYS_PAGE='272',
 XY='(-6475,2125)',
 ROT='0',
 VER='1',
 PACK_TYPE='SMLF',
 LOCATION='PL210',
 CDS_LIB='pure_quanta',
 CDS_PART_NAME='Q_INDUCTOR_SMLF-130NH/106A,INDA',
 MATERIAL='IND',
 VALUE='130NH/106A',
 PRIM_FILE='./archive_libs/logical/q_inductor/chips/chips.prt';

PART_NAME
 PPQ1 'MOSFET_NCH_1D3S-PSMNR58-30YLH,B':
 ROOM='HSC1_BOM2';

SECTION_NUMBER 1
 '@S9S_MB_2U_LIB.S9S_MB_2U(SCH_1):PAGE328_I65@PURE_QUANTA.MOSFET_NCH_1D3S(CHIPS)':
 C_PATH='@s9s_mb_2u_lib.s9s_mb_2u(sch_1):page328_i65@pure_quanta.mosfet_nch_1d3s~
(chips)',
 P_PATH='@s9s_mb_2u_lib.s9s_mb_2u(sch_1):page304_i65@pure_quanta.mosfet_nch_1d3s~
(chips)',
 PATH='I65',
 DRAWING='@S9S_MB_2U_LIB.S9S_MB_2U(SCH_1):PAGE328',
 PHYS_PAGE='304',
 XY='(2975,1450)',
 ROT='6',
 VER='1',
 LOCATION='PPQ1',
 SEC='1',
 CDS_LIB='pure_quanta',
 CDS_PART_NAME='MOSFET_NCH_1D3S-PSMNR58-30YLH,B',
 SEC_TYPE='',
 PART_TYPE='SMLF',
 MATERIAL='EMPTY',
 ROOM='HSC1_BOM2',
 VALUE='PSMNR58-30YLH',
 PRIM_FILE='./archive_libs/logical/mosfet_nch_1d3s/chips/chips.prt';

PART_NAME
 PPQ2 'MOSFET_NCH_1D3S-PSMNR58-30YLH,B':
 ROOM='HSC1_BOM2';

SECTION_NUMBER 1
 '@S9S_MB_2U_LIB.S9S_MB_2U(SCH_1):PAGE328_I73@PURE_QUANTA.MOSFET_NCH_1D3S(CHIPS)':
 C_PATH='@s9s_mb_2u_lib.s9s_mb_2u(sch_1):page328_i73@pure_quanta.mosfet_nch_1d3s~
(chips)',
 P_PATH='@s9s_mb_2u_lib.s9s_mb_2u(sch_1):page304_i73@pure_quanta.mosfet_nch_1d3s~
(chips)',
 PATH='I73',
 DRAWING='@S9S_MB_2U_LIB.S9S_MB_2U(SCH_1):PAGE328',
 PHYS_PAGE='304',
 XY='(3850,1475)',
 ROT='6',
 VER='1',
 LOCATION='PPQ2',
 SEC='1',
 CDS_LIB='pure_quanta',
 CDS_PART_NAME='MOSFET_NCH_1D3S-PSMNR58-30YLH,B',
 SEC_TYPE='',
 PART_TYPE='SMLF',
 MATERIAL='EMPTY',
 ROOM='HSC1_BOM2',
 VALUE='PSMNR58-30YLH',
 PRIM_FILE='./archive_libs/logical/mosfet_nch_1d3s/chips/chips.prt';

PART_NAME
 PPQ5 'MOSFET_NCH_1D3S-PSMNR58-30YLH,B':
 ROOM='HSC1_BOM2';

SECTION_NUMBER 1
 '@S9S_MB_2U_LIB.S9S_MB_2U(SCH_1):PAGE328_I35@PURE_QUANTA.MOSFET_NCH_1D3S(CHIPS)':
 C_PATH='@s9s_mb_2u_lib.s9s_mb_2u(sch_1):page328_i35@pure_quanta.mosfet_nch_1d3s~
(chips)',
 P_PATH='@s9s_mb_2u_lib.s9s_mb_2u(sch_1):page304_i35@pure_quanta.mosfet_nch_1d3s~
(chips)',
 PATH='I35',
 DRAWING='@S9S_MB_2U_LIB.S9S_MB_2U(SCH_1):PAGE328',
 PHYS_PAGE='304',
 XY='(-525,1375)',
 ROT='6',
 VER='1',
 LOCATION='PPQ5',
 CDS_LIB='pure_quanta',
 CDS_PART_NAME='MOSFET_NCH_1D3S-PSMNR58-30YLH,B',
 PART_TYPE='SMLF',
 MATERIAL='EMPTY',
 ROOM='HSC1_BOM2',
 VALUE='PSMNR58-30YLH',
 PRIM_FILE='./archive_libs/logical/mosfet_nch_1d3s/chips/chips.prt';

PART_NAME
 PPQ6 'MOSFET_NCH_1D3S-PSMNR58-30YLH,B':
 ROOM='HSC1_BOM2';

SECTION_NUMBER 1
 '@S9S_MB_2U_LIB.S9S_MB_2U(SCH_1):PAGE328_I40@PURE_QUANTA.MOSFET_NCH_1D3S(CHIPS)':
 C_PATH='@s9s_mb_2u_lib.s9s_mb_2u(sch_1):page328_i40@pure_quanta.mosfet_nch_1d3s~
(chips)',
 P_PATH='@s9s_mb_2u_lib.s9s_mb_2u(sch_1):page304_i40@pure_quanta.mosfet_nch_1d3s~
(chips)',
 PATH='I40',
 DRAWING='@S9S_MB_2U_LIB.S9S_MB_2U(SCH_1):PAGE328',
 PHYS_PAGE='304',
 XY='(350,1400)',
 ROT='6',
 VER='1',
 LOCATION='PPQ6',
 CDS_LIB='pure_quanta',
 CDS_PART_NAME='MOSFET_NCH_1D3S-PSMNR58-30YLH,B',
 PART_TYPE='SMLF',
 MATERIAL='EMPTY',
 ROOM='HSC1_BOM2',
 VALUE='PSMNR58-30YLH',
 PRIM_FILE='./archive_libs/logical/mosfet_nch_1d3s/chips/chips.prt';

PART_NAME
 PPQ7 'MOSFET_NCH_1D3S-PSMNR58-30YLH,B':
 ROOM='HSC1_BOM2';

SECTION_NUMBER 1
 '@S9S_MB_2U_LIB.S9S_MB_2U(SCH_1):PAGE328_I41@PURE_QUANTA.MOSFET_NCH_1D3S(CHIPS)':
 C_PATH='@s9s_mb_2u_lib.s9s_mb_2u(sch_1):page328_i41@pure_quanta.mosfet_nch_1d3s~
(chips)',
 P_PATH='@s9s_mb_2u_lib.s9s_mb_2u(sch_1):page304_i41@pure_quanta.mosfet_nch_1d3s~
(chips)',
 PATH='I41',
 DRAWING='@S9S_MB_2U_LIB.S9S_MB_2U(SCH_1):PAGE328',
 PHYS_PAGE='304',
 XY='(1225,1425)',
 ROT='6',
 VER='1',
 LOCATION='PPQ7',
 CDS_LIB='pure_quanta',
 CDS_PART_NAME='MOSFET_NCH_1D3S-PSMNR58-30YLH,B',
 PART_TYPE='SMLF',
 MATERIAL='EMPTY',
 ROOM='HSC1_BOM2',
 VALUE='PSMNR58-30YLH',
 PRIM_FILE='./archive_libs/logical/mosfet_nch_1d3s/chips/chips.prt';

PART_NAME
 PPQ8 'MOSFET_NCH_1D3S-PSMNR58-30YLH,B':
 ROOM='HSC1_BOM2';

SECTION_NUMBER 1
 '@S9S_MB_2U_LIB.S9S_MB_2U(SCH_1):PAGE328_I62@PURE_QUANTA.MOSFET_NCH_1D3S(CHIPS)':
 C_PATH='@s9s_mb_2u_lib.s9s_mb_2u(sch_1):page328_i62@pure_quanta.mosfet_nch_1d3s~
(chips)',
 P_PATH='@s9s_mb_2u_lib.s9s_mb_2u(sch_1):page304_i62@pure_quanta.mosfet_nch_1d3s~
(chips)',
 PATH='I62',
 DRAWING='@S9S_MB_2U_LIB.S9S_MB_2U(SCH_1):PAGE328',
 PHYS_PAGE='304',
 XY='(2100,1425)',
 ROT='6',
 VER='1',
 LOCATION='PPQ8',
 CDS_LIB='pure_quanta',
 CDS_PART_NAME='MOSFET_NCH_1D3S-PSMNR58-30YLH,B',
 PART_TYPE='SMLF',
 MATERIAL='EMPTY',
 ROOM='HSC1_BOM2',
 VALUE='PSMNR58-30YLH',
 PRIM_FILE='./archive_libs/logical/mosfet_nch_1d3s/chips/chips.prt';

PART_NAME
 PPQ9 'MOSFET_NCH_1D3S-PSMNR58-30YLH,B':
 ROOM='HSC1_BOM2';

SECTION_NUMBER 1
 '@S9S_MB_2U_LIB.S9S_MB_2U(SCH_1):PAGE328_I77@PURE_QUANTA.MOSFET_NCH_1D3S(CHIPS)':
 C_PATH='@s9s_mb_2u_lib.s9s_mb_2u(sch_1):page328_i77@pure_quanta.mosfet_nch_1d3s~
(chips)',
 P_PATH='@s9s_mb_2u_lib.s9s_mb_2u(sch_1):page304_i77@pure_quanta.mosfet_nch_1d3s~
(chips)',
 PATH='I77',
 DRAWING='@S9S_MB_2U_LIB.S9S_MB_2U(SCH_1):PAGE328',
 PHYS_PAGE='304',
 XY='(5300,2625)',
 ROT='6',
 VER='1',
 LOCATION='PPQ9',
 CDS_LIB='pure_quanta',
 CDS_PART_NAME='MOSFET_NCH_1D3S-PSMNR58-30YLH,B',
 PART_TYPE='SMLF',
 MATERIAL='EMPTY',
 ROOM='HSC1_BOM2',
 VALUE='PSMNR58-30YLH',
 PRIM_FILE='./archive_libs/logical/mosfet_nch_1d3s/chips/chips.prt';

PART_NAME
 PR1 'Q_RES_0402LF-0,5%,1/16W,CHIP,CA':;

SECTION_NUMBER 1
 '@S9S_MB_2U_LIB.S9S_MB_2U(SCH_1):PAGE268_I19@PURE_QUANTA.Q_RES(CHIPS)':
 C_PATH='@s9s_mb_2u_lib.s9s_mb_2u(sch_1):page268_i19@pure_quanta.q_res(chips)',
 P_PATH='@s9s_mb_2u_lib.s9s_mb_2u(sch_1):page282_i19@pure_quanta.q_res(chips)',
 PATH='I19',
 DRAWING='@S9S_MB_2U_LIB.S9S_MB_2U(SCH_1):PAGE268',
 PHYS_PAGE='282',
 XY='(-5275,8375)',
 ROT='0',
 VER='1',
 PACK_TYPE='0402LF',
 LOCATION='PR1',
 CDS_LIB='pure_quanta',
 CDS_PART_NAME='Q_RES_0402LF-0,5%,1/16W,CHIP,CA',
 WATTAGE='1/16W',
 TOLERANCE='5%',
 MATERIAL='CHIP',
 VALUE='0',
 PRIM_FILE='./archive_libs/logical/q_res/chips/chips.prt';

PART_NAME
 PR2 'Q_RES_0402LF-0,5%,1/16W,CHIP,CA':;

SECTION_NUMBER 1
 '@S9S_MB_2U_LIB.S9S_MB_2U(SCH_1):PAGE286_I22@PURE_QUANTA.Q_RES(CHIPS)':
 C_PATH='@s9s_mb_2u_lib.s9s_mb_2u(sch_1):page286_i22@pure_quanta.q_res(chips)',
 P_PATH='@s9s_mb_2u_lib.s9s_mb_2u(sch_1):page300_i22@pure_quanta.q_res(chips)',
 PATH='I22',
 DRAWING='@S9S_MB_2U_LIB.S9S_MB_2U(SCH_1):PAGE286',
 PHYS_PAGE='300',
 XY='(6475,5750)',
 ROT='0',
 VER='1',
 PACK_TYPE='0402LF',
 LOCATION='PR2',
 CDS_LIB='pure_quanta',
 CDS_PART_NAME='Q_RES_0402LF-0,5%,1/16W,CHIP,CA',
 WATTAGE='1/16W',
 TOLERANCE='5%',
 MATERIAL='CHIP',
 VALUE='0',
 PRIM_FILE='./archive_libs/logical/q_res/chips/chips.prt';

PART_NAME
 PR3 'Q_RES_4P_12-0.003,1%,3W,SMLF,EA':
 ROOM='HSC1_BOM2';

SECTION_NUMBER 1
 '@S9S_MB_2U_LIB.S9S_MB_2U(SCH_1):PAGE328_I126@PURE_QUANTA.Q_RES_4P_12(CHIPS)':
 C_PATH='@s9s_mb_2u_lib.s9s_mb_2u(sch_1):page328_i126@pure_quanta.q_res_4p_12(ch~
ips)',
 P_PATH='@s9s_mb_2u_lib.s9s_mb_2u(sch_1):page304_i126@pure_quanta.q_res_4p_12(ch~
ips)',
 PATH='I126',
 DRAWING='@S9S_MB_2U_LIB.S9S_MB_2U(SCH_1):PAGE328',
 PHYS_PAGE='304',
 XY='(2175,4325)',
 ROT='3',
 VER='1',
 LOCATION='PR3',
 CDS_LIB='pure_quanta',
 CDS_PART_NAME='Q_RES_4P_12-0.003,1%,3W,SMLF,EA',
 PART_TYPE='SMLF',
 WATTAGE='3W',
 TOLERANCE='1%',
 MATERIAL='EMPTY',
 ROOM='HSC1_BOM2',
 VALUE='0.003',
 PRIM_FILE='./archive_libs/logical/q_res_4p_12/chips/chips.prt';

PART_NAME
 PR4 'Q_SP_RES4P-0.0003,1%,4W,SMLF,EA':
 ROOM='HSC1_BOM2';

SECTION_NUMBER 1
 '@S9S_MB_2U_LIB.S9S_MB_2U(SCH_1):PAGE328_I79@PURE_QUANTA.Q_SP_RES4P(CHIPS)':
 C_PATH='@s9s_mb_2u_lib.s9s_mb_2u(sch_1):page328_i79@pure_quanta.q_sp_res4p(chip~
s)',
 P_PATH='@s9s_mb_2u_lib.s9s_mb_2u(sch_1):page304_i79@pure_quanta.q_sp_res4p(chip~
s)',
 PATH='I79',
 DRAWING='@S9S_MB_2U_LIB.S9S_MB_2U(SCH_1):PAGE328',
 PHYS_PAGE='304',
 XY='(2175,4050)',
 ROT='0',
 VER='1',
 LOCATION='PR4',
 SEC='1',
 CDS_LIB='pure_quanta',
 CDS_PART_NAME='Q_SP_RES4P-0.0003,1%,4W,SMLF,EA',
 SEC_TYPE='',
 PART_TYPE='SMLF',
 WATTAGE='4W',
 TOLERANCE='1%',
 MATERIAL='EMPTY',
 ROOM='HSC1_BOM2',
 VALUE='0.0003',
 PRIM_FILE='./archive_libs/logical/q_sp_res4p/chips/chips.prt';

PART_NAME
 PR50 'Q_RES_0402LF-12.4K,0.1%,1/16W,A':;

SECTION_NUMBER 1
 '@S9S_MB_2U_LIB.S9S_MB_2U(SCH_1):PAGE268_I28@PURE_QUANTA.Q_RES(CHIPS)':
 C_PATH='@s9s_mb_2u_lib.s9s_mb_2u(sch_1):page268_i28@pure_quanta.q_res(chips)',
 P_PATH='@s9s_mb_2u_lib.s9s_mb_2u(sch_1):page282_i28@pure_quanta.q_res(chips)',
 PATH='I28',
 DRAWING='@S9S_MB_2U_LIB.S9S_MB_2U(SCH_1):PAGE268',
 PHYS_PAGE='282',
 XY='(-4600,8675)',
 ROT='0',
 VER='2',
 PACK_TYPE='0402LF',
 LOCATION='PR50',
 SEC='1',
 CDS_LIB='pure_quanta',
 CDS_PART_NAME='Q_RES_0402LF-12.4K,0.1%,1/16W,A',
 SEC_TYPE='0402LF',
 WATTAGE='1/16W',
 TOLERANCE='0.1%',
 MATERIAL='CHIP',
 VALUE='12.4K',
 PRIM_FILE='./archive_libs/logical/q_res/chips/chips.prt';

PART_NAME
 PR51 'Q_RES_0402LF-12.4K,0.1%,1/16W,A':;

SECTION_NUMBER 1
 '@S9S_MB_2U_LIB.S9S_MB_2U(SCH_1):PAGE286_I26@PURE_QUANTA.Q_RES(CHIPS)':
 C_PATH='@s9s_mb_2u_lib.s9s_mb_2u(sch_1):page286_i26@pure_quanta.q_res(chips)',
 P_PATH='@s9s_mb_2u_lib.s9s_mb_2u(sch_1):page300_i26@pure_quanta.q_res(chips)',
 PATH='I26',
 DRAWING='@S9S_MB_2U_LIB.S9S_MB_2U(SCH_1):PAGE286',
 PHYS_PAGE='300',
 XY='(7075,6050)',
 ROT='0',
 VER='2',
 PACK_TYPE='0402LF',
 LOCATION='PR51',
 SEC='1',
 CDS_LIB='pure_quanta',
 CDS_PART_NAME='Q_RES_0402LF-12.4K,0.1%,1/16W,A',
 SEC_TYPE='0402LF',
 WATTAGE='1/16W',
 TOLERANCE='0.1%',
 MATERIAL='CHIP',
 VALUE='12.4K',
 PRIM_FILE='./archive_libs/logical/q_res/chips/chips.prt';

PART_NAME
 PR73 'Q_RES_0402LF-10K,1%,1/16W,CHIPA':;

SECTION_NUMBER 1
 '@S9S_MB_2U_LIB.S9S_MB_2U(SCH_1):PAGE245_I139@PURE_QUANTA.Q_RES(CHIPS)':
 C_PATH='@s9s_mb_2u_lib.s9s_mb_2u(sch_1):page245_i139@pure_quanta.q_res(chips)',
 P_PATH='@s9s_mb_2u_lib.s9s_mb_2u(sch_1):page259_i139@pure_quanta.q_res(chips)',
 PATH='I139',
 DRAWING='@S9S_MB_2U_LIB.S9S_MB_2U(SCH_1):PAGE245',
 PHYS_PAGE='259',
 XY='(900,200)',
 ROT='0',
 VER='2',
 PACK_TYPE='0402LF',
 LOCATION='PR73',
 CDS_LIB='pure_quanta',
 CDS_PART_NAME='Q_RES_0402LF-10K,1%,1/16W,CHIPA',
 WATTAGE='1/16W',
 TOLERANCE='1%',
 MATERIAL='CHIP',
 VALUE='10K',
 PRIM_FILE='./archive_libs/logical/q_res/chips/chips.prt';

PART_NAME
 PR89 'Q_RES_0402LF-16.9K,1%,1/16W,CHA':;

SECTION_NUMBER 1
 '@S9S_MB_2U_LIB.S9S_MB_2U(SCH_1):PAGE244_I16@PURE_QUANTA.Q_RES(CHIPS)':
 C_PATH='@s9s_mb_2u_lib.s9s_mb_2u(sch_1):page244_i16@pure_quanta.q_res(chips)',
 P_PATH='@s9s_mb_2u_lib.s9s_mb_2u(sch_1):page258_i16@pure_quanta.q_res(chips)',
 PATH='I16',
 DRAWING='@S9S_MB_2U_LIB.S9S_MB_2U(SCH_1):PAGE244',
 PHYS_PAGE='258',
 XY='(-5462,5182)',
 ROT='0',
 VER='2',
 PACK_TYPE='0402LF',
 LOCATION='PR89',
 SEC='1',
 CDS_LIB='pure_quanta',
 CDS_PART_NAME='Q_RES_0402LF-16.9K,1%,1/16W,CHA',
 SEC_TYPE='0402LF',
 WATTAGE='1/16W',
 TOLERANCE='1%',
 MATERIAL='CHIP',
 VALUE='16.9K',
 PRIM_FILE='./archive_libs/logical/q_res/chips/chips.prt';

PART_NAME
 PR91 'Q_RES_0402LF-11.8K,0.1%,1/16W,A':;

SECTION_NUMBER 1
 '@S9S_MB_2U_LIB.S9S_MB_2U(SCH_1):PAGE244_I25@PURE_QUANTA.Q_RES(CHIPS)':
 C_PATH='@s9s_mb_2u_lib.s9s_mb_2u(sch_1):page244_i25@pure_quanta.q_res(chips)',
 P_PATH='@s9s_mb_2u_lib.s9s_mb_2u(sch_1):page258_i25@pure_quanta.q_res(chips)',
 PATH='I25',
 DRAWING='@S9S_MB_2U_LIB.S9S_MB_2U(SCH_1):PAGE244',
 PHYS_PAGE='258',
 XY='(-3250,5475)',
 ROT='0',
 VER='2',
 PACK_TYPE='0402LF',
 LOCATION='PR91',
 CDS_LIB='pure_quanta',
 CDS_PART_NAME='Q_RES_0402LF-11.8K,0.1%,1/16W,A',
 WATTAGE='1/16W',
 TOLERANCE='0.1%',
 MATERIAL='CHIP',
 VALUE='11.8K',
 PRIM_FILE='./archive_libs/logical/q_res/chips/chips.prt';

PART_NAME
 PR92 'Q_RES_0402LF-88.7K,1%,1/16W,CHA':;

SECTION_NUMBER 1
 '@S9S_MB_2U_LIB.S9S_MB_2U(SCH_1):PAGE244_I39@PURE_QUANTA.Q_RES(CHIPS)':
 C_PATH='@s9s_mb_2u_lib.s9s_mb_2u(sch_1):page244_i39@pure_quanta.q_res(chips)',
 P_PATH='@s9s_mb_2u_lib.s9s_mb_2u(sch_1):page258_i39@pure_quanta.q_res(chips)',
 PATH='I39',
 DRAWING='@S9S_MB_2U_LIB.S9S_MB_2U(SCH_1):PAGE244',
 PHYS_PAGE='258',
 XY='(-1875,5400)',
 ROT='0',
 VER='1',
 PACK_TYPE='0402LF',
 LOCATION='PR92',
 CDS_LIB='pure_quanta',
 CDS_PART_NAME='Q_RES_0402LF-88.7K,1%,1/16W,CHA',
 WATTAGE='1/16W',
 TOLERANCE='1%',
 MATERIAL='CHIP',
 VALUE='88.7K',
 PRIM_FILE='./archive_libs/logical/q_res/chips/chips.prt';

PART_NAME
 PR97 'Q_RES_0402LF-2.2,1%,1/16W,CHIPA':;

SECTION_NUMBER 1
 '@S9S_MB_2U_LIB.S9S_MB_2U(SCH_1):PAGE262_I21@PURE_QUANTA.Q_RES(CHIPS)':
 C_PATH='@s9s_mb_2u_lib.s9s_mb_2u(sch_1):page262_i21@pure_quanta.q_res(chips)',
 P_PATH='@s9s_mb_2u_lib.s9s_mb_2u(sch_1):page276_i21@pure_quanta.q_res(chips)',
 PATH='I21',
 DRAWING='@S9S_MB_2U_LIB.S9S_MB_2U(SCH_1):PAGE262',
 PHYS_PAGE='276',
 XY='(-9600,4400)',
 ROT='0',
 VER='2',
 PACK_TYPE='0402LF',
 LOCATION='PR97',
 CDS_LIB='pure_quanta',
 CDS_PART_NAME='Q_RES_0402LF-2.2,1%,1/16W,CHIPA',
 WATTAGE='1/16W',
 TOLERANCE='1%',
 MATERIAL='CHIP',
 VALUE='2.2',
 PRIM_FILE='./archive_libs/logical/q_res/chips/chips.prt';

PART_NAME
 PR101 'Q_RES_0402LF-2.2,1%,1/16W,CHIPA':;

SECTION_NUMBER 1
 '@S9S_MB_2U_LIB.S9S_MB_2U(SCH_1):PAGE261_I26@PURE_QUANTA.Q_RES(CHIPS)':
 C_PATH='@s9s_mb_2u_lib.s9s_mb_2u(sch_1):page261_i26@pure_quanta.q_res(chips)',
 P_PATH='@s9s_mb_2u_lib.s9s_mb_2u(sch_1):page275_i26@pure_quanta.q_res(chips)',
 PATH='I26',
 DRAWING='@S9S_MB_2U_LIB.S9S_MB_2U(SCH_1):PAGE261',
 PHYS_PAGE='275',
 XY='(-10400,5625)',
 ROT='0',
 VER='2',
 PACK_TYPE='0402LF',
 LOCATION='PR101',
 CDS_LIB='pure_quanta',
 CDS_PART_NAME='Q_RES_0402LF-2.2,1%,1/16W,CHIPA',
 WATTAGE='1/16W',
 TOLERANCE='1%',
 MATERIAL='CHIP',
 VALUE='2.2',
 PRIM_FILE='./archive_libs/logical/q_res/chips/chips.prt';

PART_NAME
 PR102 'Q_RES_0402LF-2.2,1%,1/16W,CHIPA':;

SECTION_NUMBER 1
 '@S9S_MB_2U_LIB.S9S_MB_2U(SCH_1):PAGE261_I14@PURE_QUANTA.Q_RES(CHIPS)':
 C_PATH='@s9s_mb_2u_lib.s9s_mb_2u(sch_1):page261_i14@pure_quanta.q_res(chips)',
 P_PATH='@s9s_mb_2u_lib.s9s_mb_2u(sch_1):page275_i14@pure_quanta.q_res(chips)',
 PATH='I14',
 DRAWING='@S9S_MB_2U_LIB.S9S_MB_2U(SCH_1):PAGE261',
 PHYS_PAGE='275',
 XY='(-10400,2825)',
 ROT='0',
 VER='2',
 PACK_TYPE='0402LF',
 LOCATION='PR102',
 CDS_LIB='pure_quanta',
 CDS_PART_NAME='Q_RES_0402LF-2.2,1%,1/16W,CHIPA',
 WATTAGE='1/16W',
 TOLERANCE='1%',
 MATERIAL='CHIP',
 VALUE='2.2',
 PRIM_FILE='./archive_libs/logical/q_res/chips/chips.prt';

PART_NAME
 PR105 'Q_RES_0402LF-28K,1%,1/16W,EMPTA':;

SECTION_NUMBER 1
 '@S9S_MB_2U_LIB.S9S_MB_2U(SCH_1):PAGE260_I7@PURE_QUANTA.Q_RES(CHIPS)':
 C_PATH='@s9s_mb_2u_lib.s9s_mb_2u(sch_1):page260_i7@pure_quanta.q_res(chips)',
 P_PATH='@s9s_mb_2u_lib.s9s_mb_2u(sch_1):page274_i7@pure_quanta.q_res(chips)',
 PATH='I7',
 DRAWING='@S9S_MB_2U_LIB.S9S_MB_2U(SCH_1):PAGE260',
 PHYS_PAGE='274',
 XY='(-9875,2475)',
 ROT='0',
 VER='1',
 PACK_TYPE='0402LF',
 LOCATION='PR105',
 CDS_LIB='pure_quanta',
 CDS_PART_NAME='Q_RES_0402LF-28K,1%,1/16W,EMPTA',
 WATTAGE='1/16W',
 TOLERANCE='1%',
 MATERIAL='EMPTY',
 VALUE='28K',
 PRIM_FILE='./archive_libs/logical/q_res/chips/chips.prt';

PART_NAME
 PR106 'Q_RES_0402LF-681,1%,1/16W,CHIPA':;

SECTION_NUMBER 1
 '@S9S_MB_2U_LIB.S9S_MB_2U(SCH_1):PAGE260_I109@PURE_QUANTA.Q_RES(CHIPS)':
 C_PATH='@s9s_mb_2u_lib.s9s_mb_2u(sch_1):page260_i109@pure_quanta.q_res(chips)',
 P_PATH='@s9s_mb_2u_lib.s9s_mb_2u(sch_1):page274_i109@pure_quanta.q_res(chips)',
 PATH='I109',
 DRAWING='@S9S_MB_2U_LIB.S9S_MB_2U(SCH_1):PAGE260',
 PHYS_PAGE='274',
 XY='(-9750,2250)',
 ROT='0',
 VER='2',
 PACK_TYPE='0402LF',
 LOCATION='PR106',
 CDS_LIB='pure_quanta',
 CDS_PART_NAME='Q_RES_0402LF-681,1%,1/16W,CHIPA',
 WATTAGE='1/16W',
 TOLERANCE='1%',
 MATERIAL='CHIP',
 VALUE='681',
 PRIM_FILE='./archive_libs/logical/q_res/chips/chips.prt';

PART_NAME
 PR107 'Q_RES_0402LF-0,5%,1/16W,EMPTY,A':;

SECTION_NUMBER 1
 '@S9S_MB_2U_LIB.S9S_MB_2U(SCH_1):PAGE260_I10@PURE_QUANTA.Q_RES(CHIPS)':
 C_PATH='@s9s_mb_2u_lib.s9s_mb_2u(sch_1):page260_i10@pure_quanta.q_res(chips)',
 P_PATH='@s9s_mb_2u_lib.s9s_mb_2u(sch_1):page274_i10@pure_quanta.q_res(chips)',
 PATH='I10',
 DRAWING='@S9S_MB_2U_LIB.S9S_MB_2U(SCH_1):PAGE260',
 PHYS_PAGE='274',
 XY='(-9275,2225)',
 ROT='0',
 VER='1',
 PACK_TYPE='0402LF',
 LOCATION='PR107',
 CDS_LIB='pure_quanta',
 CDS_PART_NAME='Q_RES_0402LF-0,5%,1/16W,EMPTY,A',
 WATTAGE='1/16W',
 TOLERANCE='5%',
 MATERIAL='EMPTY',
 VALUE='0',
 PRIM_FILE='./archive_libs/logical/q_res/chips/chips.prt';

PART_NAME
 PR108 'Q_RES_0402LF-0,5%,1/16W,CHIP,CA':;

SECTION_NUMBER 1
 '@S9S_MB_2U_LIB.S9S_MB_2U(SCH_1):PAGE260_I9@PURE_QUANTA.Q_RES(CHIPS)':
 C_PATH='@s9s_mb_2u_lib.s9s_mb_2u(sch_1):page260_i9@pure_quanta.q_res(chips)',
 P_PATH='@s9s_mb_2u_lib.s9s_mb_2u(sch_1):page274_i9@pure_quanta.q_res(chips)',
 PATH='I9',
 DRAWING='@S9S_MB_2U_LIB.S9S_MB_2U(SCH_1):PAGE260',
 PHYS_PAGE='274',
 XY='(-9275,2125)',
 ROT='0',
 VER='1',
 PACK_TYPE='0402LF',
 LOCATION='PR108',
 CDS_LIB='pure_quanta',
 CDS_PART_NAME='Q_RES_0402LF-0,5%,1/16W,CHIP,CA',
 WATTAGE='1/16W',
 TOLERANCE='5%',
 MATERIAL='CHIP',
 VALUE='0',
 PRIM_FILE='./archive_libs/logical/q_res/chips/chips.prt';

PART_NAME
 PR120 'Q_RES_0402LF-0,5%,1/16W,CHIP,CA':;

SECTION_NUMBER 1
 '@S9S_MB_2U_LIB.S9S_MB_2U(SCH_1):PAGE260_I49@PURE_QUANTA.Q_RES(CHIPS)':
 C_PATH='@s9s_mb_2u_lib.s9s_mb_2u(sch_1):page260_i49@pure_quanta.q_res(chips)',
 P_PATH='@s9s_mb_2u_lib.s9s_mb_2u(sch_1):page274_i49@pure_quanta.q_res(chips)',
 PATH='I49',
 DRAWING='@S9S_MB_2U_LIB.S9S_MB_2U(SCH_1):PAGE260',
 PHYS_PAGE='274',
 XY='(-8850,5575)',
 ROT='0',
 VER='1',
 PACK_TYPE='0402LF',
 LOCATION='PR120',
 CDS_LIB='pure_quanta',
 CDS_PART_NAME='Q_RES_0402LF-0,5%,1/16W,CHIP,CA',
 WATTAGE='1/16W',
 TOLERANCE='5%',
 MATERIAL='CHIP',
 VALUE='0',
 PRIM_FILE='./archive_libs/logical/q_res/chips/chips.prt';

PART_NAME
 PR121 'Q_RES_0402LF-0,5%,1/16W,CHIP,CA':;

SECTION_NUMBER 1
 '@S9S_MB_2U_LIB.S9S_MB_2U(SCH_1):PAGE260_I47@PURE_QUANTA.Q_RES(CHIPS)':
 C_PATH='@s9s_mb_2u_lib.s9s_mb_2u(sch_1):page260_i47@pure_quanta.q_res(chips)',
 P_PATH='@s9s_mb_2u_lib.s9s_mb_2u(sch_1):page274_i47@pure_quanta.q_res(chips)',
 PATH='I47',
 DRAWING='@S9S_MB_2U_LIB.S9S_MB_2U(SCH_1):PAGE260',
 PHYS_PAGE='274',
 XY='(-8850,4475)',
 ROT='0',
 VER='1',
 PACK_TYPE='0402LF',
 LOCATION='PR121',
 CDS_LIB='pure_quanta',
 CDS_PART_NAME='Q_RES_0402LF-0,5%,1/16W,CHIP,CA',
 WATTAGE='1/16W',
 TOLERANCE='5%',
 MATERIAL='CHIP',
 VALUE='0',
 PRIM_FILE='./archive_libs/logical/q_res/chips/chips.prt';

PART_NAME
 PR123 'Q_RES_0402LF-1K,1%,1/16W,EMPTYA':;

SECTION_NUMBER 1
 '@S9S_MB_2U_LIB.S9S_MB_2U(SCH_1):PAGE260_I21@PURE_QUANTA.Q_RES(CHIPS)':
 C_PATH='@s9s_mb_2u_lib.s9s_mb_2u(sch_1):page260_i21@pure_quanta.q_res(chips)',
 P_PATH='@s9s_mb_2u_lib.s9s_mb_2u(sch_1):page274_i21@pure_quanta.q_res(chips)',
 PATH='I21',
 DRAWING='@S9S_MB_2U_LIB.S9S_MB_2U(SCH_1):PAGE260',
 PHYS_PAGE='274',
 XY='(-8075,1925)',
 ROT='0',
 VER='2',
 PACK_TYPE='0402LF',
 LOCATION='PR123',
 CDS_LIB='pure_quanta',
 CDS_PART_NAME='Q_RES_0402LF-1K,1%,1/16W,EMPTYA',
 WATTAGE='1/16W',
 TOLERANCE='1%',
 MATERIAL='EMPTY',
 VALUE='1K',
 PRIM_FILE='./archive_libs/logical/q_res/chips/chips.prt';

PART_NAME
 PR130 'Q_RES_0402LF-1,1%,1/16W,CHIP,CA':;

SECTION_NUMBER 1
 '@S9S_MB_2U_LIB.S9S_MB_2U(SCH_1):PAGE260_I100@PURE_QUANTA.Q_RES(CHIPS)':
 C_PATH='@s9s_mb_2u_lib.s9s_mb_2u(sch_1):page260_i100@pure_quanta.q_res(chips)',
 P_PATH='@s9s_mb_2u_lib.s9s_mb_2u(sch_1):page274_i100@pure_quanta.q_res(chips)',
 PATH='I100',
 DRAWING='@S9S_MB_2U_LIB.S9S_MB_2U(SCH_1):PAGE260',
 PHYS_PAGE='274',
 XY='(-4850,7575)',
 ROT='0',
 VER='1',
 PACK_TYPE='0402LF',
 LOCATION='PR130',
 CDS_LIB='pure_quanta',
 CDS_PART_NAME='Q_RES_0402LF-1,1%,1/16W,CHIP,CA',
 WATTAGE='1/16W',
 TOLERANCE='1%',
 MATERIAL='CHIP',
 VALUE='1',
 PRIM_FILE='./archive_libs/logical/q_res/chips/chips.prt';

PART_NAME
 PR132 'Q_RES_0402LF-8.87K,1%,1/16W,EMA':;

SECTION_NUMBER 1
 '@S9S_MB_2U_LIB.S9S_MB_2U(SCH_1):PAGE256_I4@PURE_QUANTA.Q_RES(CHIPS)':
 C_PATH='@s9s_mb_2u_lib.s9s_mb_2u(sch_1):page256_i4@pure_quanta.q_res(chips)',
 P_PATH='@s9s_mb_2u_lib.s9s_mb_2u(sch_1):page270_i4@pure_quanta.q_res(chips)',
 PATH='I4',
 DRAWING='@S9S_MB_2U_LIB.S9S_MB_2U(SCH_1):PAGE256',
 PHYS_PAGE='270',
 XY='(-7550,-5900)',
 ROT='2',
 VER='2',
 PACK_TYPE='0402LF',
 LOCATION='PR132',
 CDS_LIB='pure_quanta',
 CDS_PART_NAME='Q_RES_0402LF-8.87K,1%,1/16W,EMA',
 WATTAGE='1/16W',
 TOLERANCE='1%',
 MATERIAL='EMPTY',
 VALUE='8.87K',
 PRIM_FILE='./archive_libs/logical/q_res/chips/chips.prt';

PART_NAME
 PR133 'Q_RES_0402LF-8.87K,1%,1/16W,EMA':;

SECTION_NUMBER 1
 '@S9S_MB_2U_LIB.S9S_MB_2U(SCH_1):PAGE256_I23@PURE_QUANTA.Q_RES(CHIPS)':
 C_PATH='@s9s_mb_2u_lib.s9s_mb_2u(sch_1):page256_i23@pure_quanta.q_res(chips)',
 P_PATH='@s9s_mb_2u_lib.s9s_mb_2u(sch_1):page270_i23@pure_quanta.q_res(chips)',
 PATH='I23',
 DRAWING='@S9S_MB_2U_LIB.S9S_MB_2U(SCH_1):PAGE256',
 PHYS_PAGE='270',
 XY='(-7525,-3075)',
 ROT='2',
 VER='2',
 PACK_TYPE='0402LF',
 LOCATION='PR133',
 CDS_LIB='pure_quanta',
 CDS_PART_NAME='Q_RES_0402LF-8.87K,1%,1/16W,EMA',
 WATTAGE='1/16W',
 TOLERANCE='1%',
 MATERIAL='EMPTY',
 VALUE='8.87K',
 PRIM_FILE='./archive_libs/logical/q_res/chips/chips.prt';

PART_NAME
 PR134 'Q_RES_0402LF-2.2,1%,1/16W,CHIPA':;

SECTION_NUMBER 1
 '@S9S_MB_2U_LIB.S9S_MB_2U(SCH_1):PAGE256_I12@PURE_QUANTA.Q_RES(CHIPS)':
 C_PATH='@s9s_mb_2u_lib.s9s_mb_2u(sch_1):page256_i12@pure_quanta.q_res(chips)',
 P_PATH='@s9s_mb_2u_lib.s9s_mb_2u(sch_1):page270_i12@pure_quanta.q_res(chips)',
 PATH='I12',
 DRAWING='@S9S_MB_2U_LIB.S9S_MB_2U(SCH_1):PAGE256',
 PHYS_PAGE='270',
 XY='(-7150,-4400)',
 ROT='0',
 VER='2',
 PACK_TYPE='0402LF',
 LOCATION='PR134',
 CDS_LIB='pure_quanta',
 CDS_PART_NAME='Q_RES_0402LF-2.2,1%,1/16W,CHIPA',
 WATTAGE='1/16W',
 TOLERANCE='1%',
 MATERIAL='CHIP',
 VALUE='2.2',
 PRIM_FILE='./archive_libs/logical/q_res/chips/chips.prt';

PART_NAME
 PR135 'Q_RES_0402LF-2.2,1%,1/16W,CHIPA':;

SECTION_NUMBER 1
 '@S9S_MB_2U_LIB.S9S_MB_2U(SCH_1):PAGE256_I33@PURE_QUANTA.Q_RES(CHIPS)':
 C_PATH='@s9s_mb_2u_lib.s9s_mb_2u(sch_1):page256_i33@pure_quanta.q_res(chips)',
 P_PATH='@s9s_mb_2u_lib.s9s_mb_2u(sch_1):page270_i33@pure_quanta.q_res(chips)',
 PATH='I33',
 DRAWING='@S9S_MB_2U_LIB.S9S_MB_2U(SCH_1):PAGE256',
 PHYS_PAGE='270',
 XY='(-7125,-1575)',
 ROT='0',
 VER='2',
 PACK_TYPE='0402LF',
 LOCATION='PR135',
 CDS_LIB='pure_quanta',
 CDS_PART_NAME='Q_RES_0402LF-2.2,1%,1/16W,CHIPA',
 WATTAGE='1/16W',
 TOLERANCE='1%',
 MATERIAL='CHIP',
 VALUE='2.2',
 PRIM_FILE='./archive_libs/logical/q_res/chips/chips.prt';

PART_NAME
 PR136 'Q_RES_0402LF-0,5%,1/16W,CHIP,CA':;

SECTION_NUMBER 1
 '@S9S_MB_2U_LIB.S9S_MB_2U(SCH_1):PAGE256_I46@PURE_QUANTA.Q_RES(CHIPS)':
 C_PATH='@s9s_mb_2u_lib.s9s_mb_2u(sch_1):page256_i46@pure_quanta.q_res(chips)',
 P_PATH='@s9s_mb_2u_lib.s9s_mb_2u(sch_1):page270_i46@pure_quanta.q_res(chips)',
 PATH='I46',
 DRAWING='@S9S_MB_2U_LIB.S9S_MB_2U(SCH_1):PAGE256',
 PHYS_PAGE='270',
 XY='(-3150,-5900)',
 ROT='0',
 VER='1',
 PACK_TYPE='0402LF',
 LOCATION='PR136',
 CDS_LIB='pure_quanta',
 CDS_PART_NAME='Q_RES_0402LF-0,5%,1/16W,CHIP,CA',
 WATTAGE='1/16W',
 TOLERANCE='5%',
 MATERIAL='CHIP',
 VALUE='0',
 PRIM_FILE='./archive_libs/logical/q_res/chips/chips.prt';

PART_NAME
 PR137 'Q_RES_0402LF-0,5%,1/16W,CHIP,CA':;

SECTION_NUMBER 1
 '@S9S_MB_2U_LIB.S9S_MB_2U(SCH_1):PAGE256_I57@PURE_QUANTA.Q_RES(CHIPS)':
 C_PATH='@s9s_mb_2u_lib.s9s_mb_2u(sch_1):page256_i57@pure_quanta.q_res(chips)',
 P_PATH='@s9s_mb_2u_lib.s9s_mb_2u(sch_1):page270_i57@pure_quanta.q_res(chips)',
 PATH='I57',
 DRAWING='@S9S_MB_2U_LIB.S9S_MB_2U(SCH_1):PAGE256',
 PHYS_PAGE='270',
 XY='(-3100,-3175)',
 ROT='0',
 VER='1',
 PACK_TYPE='0402LF',
 LOCATION='PR137',
 CDS_LIB='pure_quanta',
 CDS_PART_NAME='Q_RES_0402LF-0,5%,1/16W,CHIP,CA',
 WATTAGE='1/16W',
 TOLERANCE='5%',
 MATERIAL='CHIP',
 VALUE='0',
 PRIM_FILE='./archive_libs/logical/q_res/chips/chips.prt';

PART_NAME
 PR138 'Q_RES_0402LF-8.87K,1%,1/16W,EMA':;

SECTION_NUMBER 1
 '@S9S_MB_2U_LIB.S9S_MB_2U(SCH_1):PAGE255_I2@PURE_QUANTA.Q_RES(CHIPS)':
 C_PATH='@s9s_mb_2u_lib.s9s_mb_2u(sch_1):page255_i2@pure_quanta.q_res(chips)',
 P_PATH='@s9s_mb_2u_lib.s9s_mb_2u(sch_1):page269_i2@pure_quanta.q_res(chips)',
 PATH='I2',
 DRAWING='@S9S_MB_2U_LIB.S9S_MB_2U(SCH_1):PAGE255',
 PHYS_PAGE='269',
 XY='(1675,1400)',
 ROT='2',
 VER='2',
 PACK_TYPE='0402LF',
 LOCATION='PR138',
 CDS_LIB='pure_quanta',
 CDS_PART_NAME='Q_RES_0402LF-8.87K,1%,1/16W,EMA',
 WATTAGE='1/16W',
 TOLERANCE='1%',
 MATERIAL='EMPTY',
 VALUE='8.87K',
 PRIM_FILE='./archive_libs/logical/q_res/chips/chips.prt';

PART_NAME
 PR139 'Q_RES_0402LF-8.87K,1%,1/16W,EMA':;

SECTION_NUMBER 1
 '@S9S_MB_2U_LIB.S9S_MB_2U(SCH_1):PAGE255_I4@PURE_QUANTA.Q_RES(CHIPS)':
 C_PATH='@s9s_mb_2u_lib.s9s_mb_2u(sch_1):page255_i4@pure_quanta.q_res(chips)',
 P_PATH='@s9s_mb_2u_lib.s9s_mb_2u(sch_1):page269_i4@pure_quanta.q_res(chips)',
 PATH='I4',
 DRAWING='@S9S_MB_2U_LIB.S9S_MB_2U(SCH_1):PAGE255',
 PHYS_PAGE='269',
 XY='(1700,4225)',
 ROT='2',
 VER='2',
 PACK_TYPE='0402LF',
 LOCATION='PR139',
 CDS_LIB='pure_quanta',
 CDS_PART_NAME='Q_RES_0402LF-8.87K,1%,1/16W,EMA',
 WATTAGE='1/16W',
 TOLERANCE='1%',
 MATERIAL='EMPTY',
 VALUE='8.87K',
 PRIM_FILE='./archive_libs/logical/q_res/chips/chips.prt';

PART_NAME
 PR140 'Q_RES_0402LF-2.2,1%,1/16W,CHIPA':;

SECTION_NUMBER 1
 '@S9S_MB_2U_LIB.S9S_MB_2U(SCH_1):PAGE255_I14@PURE_QUANTA.Q_RES(CHIPS)':
 C_PATH='@s9s_mb_2u_lib.s9s_mb_2u(sch_1):page255_i14@pure_quanta.q_res(chips)',
 P_PATH='@s9s_mb_2u_lib.s9s_mb_2u(sch_1):page269_i14@pure_quanta.q_res(chips)',
 PATH='I14',
 DRAWING='@S9S_MB_2U_LIB.S9S_MB_2U(SCH_1):PAGE255',
 PHYS_PAGE='269',
 XY='(2075,2900)',
 ROT='0',
 VER='2',
 PACK_TYPE='0402LF',
 LOCATION='PR140',
 CDS_LIB='pure_quanta',
 CDS_PART_NAME='Q_RES_0402LF-2.2,1%,1/16W,CHIPA',
 WATTAGE='1/16W',
 TOLERANCE='1%',
 MATERIAL='CHIP',
 VALUE='2.2',
 PRIM_FILE='./archive_libs/logical/q_res/chips/chips.prt';

PART_NAME
 PR141 'Q_RES_0402LF-2.2,1%,1/16W,CHIPA':;

SECTION_NUMBER 1
 '@S9S_MB_2U_LIB.S9S_MB_2U(SCH_1):PAGE255_I26@PURE_QUANTA.Q_RES(CHIPS)':
 C_PATH='@s9s_mb_2u_lib.s9s_mb_2u(sch_1):page255_i26@pure_quanta.q_res(chips)',
 P_PATH='@s9s_mb_2u_lib.s9s_mb_2u(sch_1):page269_i26@pure_quanta.q_res(chips)',
 PATH='I26',
 DRAWING='@S9S_MB_2U_LIB.S9S_MB_2U(SCH_1):PAGE255',
 PHYS_PAGE='269',
 XY='(2100,5725)',
 ROT='0',
 VER='2',
 PACK_TYPE='0402LF',
 LOCATION='PR141',
 CDS_LIB='pure_quanta',
 CDS_PART_NAME='Q_RES_0402LF-2.2,1%,1/16W,CHIPA',
 WATTAGE='1/16W',
 TOLERANCE='1%',
 MATERIAL='CHIP',
 VALUE='2.2',
 PRIM_FILE='./archive_libs/logical/q_res/chips/chips.prt';

PART_NAME
 PR142 'Q_RES_0402LF-0,5%,1/16W,CHIP,CA':;

SECTION_NUMBER 1
 '@S9S_MB_2U_LIB.S9S_MB_2U(SCH_1):PAGE255_I40@PURE_QUANTA.Q_RES(CHIPS)':
 C_PATH='@s9s_mb_2u_lib.s9s_mb_2u(sch_1):page255_i40@pure_quanta.q_res(chips)',
 P_PATH='@s9s_mb_2u_lib.s9s_mb_2u(sch_1):page269_i40@pure_quanta.q_res(chips)',
 PATH='I40',
 DRAWING='@S9S_MB_2U_LIB.S9S_MB_2U(SCH_1):PAGE255',
 PHYS_PAGE='269',
 XY='(6125,1375)',
 ROT='0',
 VER='1',
 PACK_TYPE='0402LF',
 LOCATION='PR142',
 CDS_LIB='pure_quanta',
 CDS_PART_NAME='Q_RES_0402LF-0,5%,1/16W,CHIP,CA',
 WATTAGE='1/16W',
 TOLERANCE='5%',
 MATERIAL='CHIP',
 VALUE='0',
 PRIM_FILE='./archive_libs/logical/q_res/chips/chips.prt';

PART_NAME
 PR143 'Q_RES_0402LF-0,5%,1/16W,CHIP,CA':;

SECTION_NUMBER 1
 '@S9S_MB_2U_LIB.S9S_MB_2U(SCH_1):PAGE255_I46@PURE_QUANTA.Q_RES(CHIPS)':
 C_PATH='@s9s_mb_2u_lib.s9s_mb_2u(sch_1):page255_i46@pure_quanta.q_res(chips)',
 P_PATH='@s9s_mb_2u_lib.s9s_mb_2u(sch_1):page269_i46@pure_quanta.q_res(chips)',
 PATH='I46',
 DRAWING='@S9S_MB_2U_LIB.S9S_MB_2U(SCH_1):PAGE255',
 PHYS_PAGE='269',
 XY='(6150,4175)',
 ROT='0',
 VER='1',
 PACK_TYPE='0402LF',
 LOCATION='PR143',
 CDS_LIB='pure_quanta',
 CDS_PART_NAME='Q_RES_0402LF-0,5%,1/16W,CHIP,CA',
 WATTAGE='1/16W',
 TOLERANCE='5%',
 MATERIAL='CHIP',
 VALUE='0',
 PRIM_FILE='./archive_libs/logical/q_res/chips/chips.prt';

PART_NAME
 PR144 'Q_RES_0402LF-8.87K,1%,1/16W,EMA':;

SECTION_NUMBER 1
 '@S9S_MB_2U_LIB.S9S_MB_2U(SCH_1):PAGE254_I2@PURE_QUANTA.Q_RES(CHIPS)':
 C_PATH='@s9s_mb_2u_lib.s9s_mb_2u(sch_1):page254_i2@pure_quanta.q_res(chips)',
 P_PATH='@s9s_mb_2u_lib.s9s_mb_2u(sch_1):page268_i2@pure_quanta.q_res(chips)',
 PATH='I2',
 DRAWING='@S9S_MB_2U_LIB.S9S_MB_2U(SCH_1):PAGE254',
 PHYS_PAGE='268',
 XY='(2600,1000)',
 ROT='2',
 VER='2',
 PACK_TYPE='0402LF',
 LOCATION='PR144',
 CDS_LIB='pure_quanta',
 CDS_PART_NAME='Q_RES_0402LF-8.87K,1%,1/16W,EMA',
 WATTAGE='1/16W',
 TOLERANCE='1%',
 MATERIAL='EMPTY',
 VALUE='8.87K',
 PRIM_FILE='./archive_libs/logical/q_res/chips/chips.prt';

PART_NAME
 PR145 'Q_RES_0402LF-8.87K,1%,1/16W,EMA':;

SECTION_NUMBER 1
 '@S9S_MB_2U_LIB.S9S_MB_2U(SCH_1):PAGE254_I4@PURE_QUANTA.Q_RES(CHIPS)':
 C_PATH='@s9s_mb_2u_lib.s9s_mb_2u(sch_1):page254_i4@pure_quanta.q_res(chips)',
 P_PATH='@s9s_mb_2u_lib.s9s_mb_2u(sch_1):page268_i4@pure_quanta.q_res(chips)',
 PATH='I4',
 DRAWING='@S9S_MB_2U_LIB.S9S_MB_2U(SCH_1):PAGE254',
 PHYS_PAGE='268',
 XY='(2625,3825)',
 ROT='2',
 VER='2',
 PACK_TYPE='0402LF',
 LOCATION='PR145',
 CDS_LIB='pure_quanta',
 CDS_PART_NAME='Q_RES_0402LF-8.87K,1%,1/16W,EMA',
 WATTAGE='1/16W',
 TOLERANCE='1%',
 MATERIAL='EMPTY',
 VALUE='8.87K',
 PRIM_FILE='./archive_libs/logical/q_res/chips/chips.prt';

PART_NAME
 PR146 'Q_RES_0402LF-2.2,1%,1/16W,CHIPA':;

SECTION_NUMBER 1
 '@S9S_MB_2U_LIB.S9S_MB_2U(SCH_1):PAGE254_I14@PURE_QUANTA.Q_RES(CHIPS)':
 C_PATH='@s9s_mb_2u_lib.s9s_mb_2u(sch_1):page254_i14@pure_quanta.q_res(chips)',
 P_PATH='@s9s_mb_2u_lib.s9s_mb_2u(sch_1):page268_i14@pure_quanta.q_res(chips)',
 PATH='I14',
 DRAWING='@S9S_MB_2U_LIB.S9S_MB_2U(SCH_1):PAGE254',
 PHYS_PAGE='268',
 XY='(3000,2500)',
 ROT='0',
 VER='2',
 PACK_TYPE='0402LF',
 LOCATION='PR146',
 CDS_LIB='pure_quanta',
 CDS_PART_NAME='Q_RES_0402LF-2.2,1%,1/16W,CHIPA',
 WATTAGE='1/16W',
 TOLERANCE='1%',
 MATERIAL='CHIP',
 VALUE='2.2',
 PRIM_FILE='./archive_libs/logical/q_res/chips/chips.prt';

PART_NAME
 PR147 'Q_RES_0402LF-2.2,1%,1/16W,CHIPA':;

SECTION_NUMBER 1
 '@S9S_MB_2U_LIB.S9S_MB_2U(SCH_1):PAGE254_I27@PURE_QUANTA.Q_RES(CHIPS)':
 C_PATH='@s9s_mb_2u_lib.s9s_mb_2u(sch_1):page254_i27@pure_quanta.q_res(chips)',
 P_PATH='@s9s_mb_2u_lib.s9s_mb_2u(sch_1):page268_i27@pure_quanta.q_res(chips)',
 PATH='I27',
 DRAWING='@S9S_MB_2U_LIB.S9S_MB_2U(SCH_1):PAGE254',
 PHYS_PAGE='268',
 XY='(3025,5325)',
 ROT='0',
 VER='2',
 PACK_TYPE='0402LF',
 LOCATION='PR147',
 CDS_LIB='pure_quanta',
 CDS_PART_NAME='Q_RES_0402LF-2.2,1%,1/16W,CHIPA',
 WATTAGE='1/16W',
 TOLERANCE='1%',
 MATERIAL='CHIP',
 VALUE='2.2',
 PRIM_FILE='./archive_libs/logical/q_res/chips/chips.prt';

PART_NAME
 PR148 'Q_RES_0402LF-0,5%,1/16W,CHIP,CA':;

SECTION_NUMBER 1
 '@S9S_MB_2U_LIB.S9S_MB_2U(SCH_1):PAGE254_I41@PURE_QUANTA.Q_RES(CHIPS)':
 C_PATH='@s9s_mb_2u_lib.s9s_mb_2u(sch_1):page254_i41@pure_quanta.q_res(chips)',
 P_PATH='@s9s_mb_2u_lib.s9s_mb_2u(sch_1):page268_i41@pure_quanta.q_res(chips)',
 PATH='I41',
 DRAWING='@S9S_MB_2U_LIB.S9S_MB_2U(SCH_1):PAGE254',
 PHYS_PAGE='268',
 XY='(7075,975)',
 ROT='0',
 VER='1',
 PACK_TYPE='0402LF',
 LOCATION='PR148',
 CDS_LIB='pure_quanta',
 CDS_PART_NAME='Q_RES_0402LF-0,5%,1/16W,CHIP,CA',
 WATTAGE='1/16W',
 TOLERANCE='5%',
 MATERIAL='CHIP',
 VALUE='0',
 PRIM_FILE='./archive_libs/logical/q_res/chips/chips.prt';

PART_NAME
 PR149 'Q_RES_0402LF-0,5%,1/16W,CHIP,CA':;

SECTION_NUMBER 1
 '@S9S_MB_2U_LIB.S9S_MB_2U(SCH_1):PAGE254_I46@PURE_QUANTA.Q_RES(CHIPS)':
 C_PATH='@s9s_mb_2u_lib.s9s_mb_2u(sch_1):page254_i46@pure_quanta.q_res(chips)',
 P_PATH='@s9s_mb_2u_lib.s9s_mb_2u(sch_1):page268_i46@pure_quanta.q_res(chips)',
 PATH='I46',
 DRAWING='@S9S_MB_2U_LIB.S9S_MB_2U(SCH_1):PAGE254',
 PHYS_PAGE='268',
 XY='(7100,3775)',
 ROT='0',
 VER='1',
 PACK_TYPE='0402LF',
 LOCATION='PR149',
 CDS_LIB='pure_quanta',
 CDS_PART_NAME='Q_RES_0402LF-0,5%,1/16W,CHIP,CA',
 WATTAGE='1/16W',
 TOLERANCE='5%',
 MATERIAL='CHIP',
 VALUE='0',
 PRIM_FILE='./archive_libs/logical/q_res/chips/chips.prt';

PART_NAME
 PR150 'Q_RES_0402LF-8.87K,1%,1/16W,EMA':;

SECTION_NUMBER 1
 '@S9S_MB_2U_LIB.S9S_MB_2U(SCH_1):PAGE253_I2@PURE_QUANTA.Q_RES(CHIPS)':
 C_PATH='@s9s_mb_2u_lib.s9s_mb_2u(sch_1):page253_i2@pure_quanta.q_res(chips)',
 P_PATH='@s9s_mb_2u_lib.s9s_mb_2u(sch_1):page267_i2@pure_quanta.q_res(chips)',
 PATH='I2',
 DRAWING='@S9S_MB_2U_LIB.S9S_MB_2U(SCH_1):PAGE253',
 PHYS_PAGE='267',
 XY='(-4200,-2625)',
 ROT='2',
 VER='2',
 PACK_TYPE='0402LF',
 LOCATION='PR150',
 CDS_LIB='pure_quanta',
 CDS_PART_NAME='Q_RES_0402LF-8.87K,1%,1/16W,EMA',
 WATTAGE='1/16W',
 TOLERANCE='1%',
 MATERIAL='EMPTY',
 VALUE='8.87K',
 PRIM_FILE='./archive_libs/logical/q_res/chips/chips.prt';

PART_NAME
 PR151 'Q_RES_0402LF-8.87K,1%,1/16W,EMA':;

SECTION_NUMBER 1
 '@S9S_MB_2U_LIB.S9S_MB_2U(SCH_1):PAGE253_I29@PURE_QUANTA.Q_RES(CHIPS)':
 C_PATH='@s9s_mb_2u_lib.s9s_mb_2u(sch_1):page253_i29@pure_quanta.q_res(chips)',
 P_PATH='@s9s_mb_2u_lib.s9s_mb_2u(sch_1):page267_i29@pure_quanta.q_res(chips)',
 PATH='I29',
 DRAWING='@S9S_MB_2U_LIB.S9S_MB_2U(SCH_1):PAGE253',
 PHYS_PAGE='267',
 XY='(-4175,200)',
 ROT='2',
 VER='2',
 PACK_TYPE='0402LF',
 LOCATION='PR151',
 CDS_LIB='pure_quanta',
 CDS_PART_NAME='Q_RES_0402LF-8.87K,1%,1/16W,EMA',
 WATTAGE='1/16W',
 TOLERANCE='1%',
 MATERIAL='EMPTY',
 VALUE='8.87K',
 PRIM_FILE='./archive_libs/logical/q_res/chips/chips.prt';

PART_NAME
 PR152 'Q_RES_0402LF-2.2,1%,1/16W,CHIPA':;

SECTION_NUMBER 1
 '@S9S_MB_2U_LIB.S9S_MB_2U(SCH_1):PAGE253_I12@PURE_QUANTA.Q_RES(CHIPS)':
 C_PATH='@s9s_mb_2u_lib.s9s_mb_2u(sch_1):page253_i12@pure_quanta.q_res(chips)',
 P_PATH='@s9s_mb_2u_lib.s9s_mb_2u(sch_1):page267_i12@pure_quanta.q_res(chips)',
 PATH='I12',
 DRAWING='@S9S_MB_2U_LIB.S9S_MB_2U(SCH_1):PAGE253',
 PHYS_PAGE='267',
 XY='(-3800,-1125)',
 ROT='0',
 VER='2',
 PACK_TYPE='0402LF',
 LOCATION='PR152',
 CDS_LIB='pure_quanta',
 CDS_PART_NAME='Q_RES_0402LF-2.2,1%,1/16W,CHIPA',
 WATTAGE='1/16W',
 TOLERANCE='1%',
 MATERIAL='CHIP',
 VALUE='2.2',
 PRIM_FILE='./archive_libs/logical/q_res/chips/chips.prt';

PART_NAME
 PR153 'Q_RES_0402LF-2.2,1%,1/16W,CHIPA':;

SECTION_NUMBER 1
 '@S9S_MB_2U_LIB.S9S_MB_2U(SCH_1):PAGE253_I37@PURE_QUANTA.Q_RES(CHIPS)':
 C_PATH='@s9s_mb_2u_lib.s9s_mb_2u(sch_1):page253_i37@pure_quanta.q_res(chips)',
 P_PATH='@s9s_mb_2u_lib.s9s_mb_2u(sch_1):page267_i37@pure_quanta.q_res(chips)',
 PATH='I37',
 DRAWING='@S9S_MB_2U_LIB.S9S_MB_2U(SCH_1):PAGE253',
 PHYS_PAGE='267',
 XY='(-3775,1700)',
 ROT='0',
 VER='2',
 PACK_TYPE='0402LF',
 LOCATION='PR153',
 CDS_LIB='pure_quanta',
 CDS_PART_NAME='Q_RES_0402LF-2.2,1%,1/16W,CHIPA',
 WATTAGE='1/16W',
 TOLERANCE='1%',
 MATERIAL='CHIP',
 VALUE='2.2',
 PRIM_FILE='./archive_libs/logical/q_res/chips/chips.prt';

PART_NAME
 PR154 'Q_RES_0402LF-0,5%,1/16W,CHIP,CA':;

SECTION_NUMBER 1
 '@S9S_MB_2U_LIB.S9S_MB_2U(SCH_1):PAGE253_I51@PURE_QUANTA.Q_RES(CHIPS)':
 C_PATH='@s9s_mb_2u_lib.s9s_mb_2u(sch_1):page253_i51@pure_quanta.q_res(chips)',
 P_PATH='@s9s_mb_2u_lib.s9s_mb_2u(sch_1):page267_i51@pure_quanta.q_res(chips)',
 PATH='I51',
 DRAWING='@S9S_MB_2U_LIB.S9S_MB_2U(SCH_1):PAGE253',
 PHYS_PAGE='267',
 XY='(25,-2675)',
 ROT='0',
 VER='1',
 PACK_TYPE='0402LF',
 LOCATION='PR154',
 CDS_LIB='pure_quanta',
 CDS_PART_NAME='Q_RES_0402LF-0,5%,1/16W,CHIP,CA',
 WATTAGE='1/16W',
 TOLERANCE='5%',
 MATERIAL='CHIP',
 VALUE='0',
 PRIM_FILE='./archive_libs/logical/q_res/chips/chips.prt';

PART_NAME
 PR155 'Q_RES_0402LF-0,5%,1/16W,CHIP,CA':;

SECTION_NUMBER 1
 '@S9S_MB_2U_LIB.S9S_MB_2U(SCH_1):PAGE253_I73@PURE_QUANTA.Q_RES(CHIPS)':
 C_PATH='@s9s_mb_2u_lib.s9s_mb_2u(sch_1):page253_i73@pure_quanta.q_res(chips)',
 P_PATH='@s9s_mb_2u_lib.s9s_mb_2u(sch_1):page267_i73@pure_quanta.q_res(chips)',
 PATH='I73',
 DRAWING='@S9S_MB_2U_LIB.S9S_MB_2U(SCH_1):PAGE253',
 PHYS_PAGE='267',
 XY='(100,100)',
 ROT='0',
 VER='1',
 PACK_TYPE='0402LF',
 LOCATION='PR155',
 CDS_LIB='pure_quanta',
 CDS_PART_NAME='Q_RES_0402LF-0,5%,1/16W,CHIP,CA',
 WATTAGE='1/16W',
 TOLERANCE='5%',
 MATERIAL='CHIP',
 VALUE='0',
 PRIM_FILE='./archive_libs/logical/q_res/chips/chips.prt';

PART_NAME
 PR156 'Q_RES_0402LF-0,5%,1/16W,CHIP,CA':;

SECTION_NUMBER 1
 '@S9S_MB_2U_LIB.S9S_MB_2U(SCH_1):PAGE252_I10@PURE_QUANTA.Q_RES(CHIPS)':
 C_PATH='@s9s_mb_2u_lib.s9s_mb_2u(sch_1):page252_i10@pure_quanta.q_res(chips)',
 P_PATH='@s9s_mb_2u_lib.s9s_mb_2u(sch_1):page266_i10@pure_quanta.q_res(chips)',
 PATH='I10',
 DRAWING='@S9S_MB_2U_LIB.S9S_MB_2U(SCH_1):PAGE252',
 PHYS_PAGE='266',
 XY='(-5200,1100)',
 ROT='0',
 VER='1',
 PACK_TYPE='0402LF',
 LOCATION='PR156',
 CDS_LIB='pure_quanta',
 CDS_PART_NAME='Q_RES_0402LF-0,5%,1/16W,CHIP,CA',
 WATTAGE='1/16W',
 TOLERANCE='5%',
 MATERIAL='CHIP',
 VALUE='0',
 PRIM_FILE='./archive_libs/logical/q_res/chips/chips.prt';

PART_NAME
 PR157 'Q_RES_0402LF-0,5%,1/16W,EMPTY,A':;

SECTION_NUMBER 1
 '@S9S_MB_2U_LIB.S9S_MB_2U(SCH_1):PAGE252_I11@PURE_QUANTA.Q_RES(CHIPS)':
 C_PATH='@s9s_mb_2u_lib.s9s_mb_2u(sch_1):page252_i11@pure_quanta.q_res(chips)',
 P_PATH='@s9s_mb_2u_lib.s9s_mb_2u(sch_1):page266_i11@pure_quanta.q_res(chips)',
 PATH='I11',
 DRAWING='@S9S_MB_2U_LIB.S9S_MB_2U(SCH_1):PAGE252',
 PHYS_PAGE='266',
 XY='(-5200,1200)',
 ROT='0',
 VER='1',
 PACK_TYPE='0402LF',
 LOCATION='PR157',
 CDS_LIB='pure_quanta',
 CDS_PART_NAME='Q_RES_0402LF-0,5%,1/16W,EMPTY,A',
 WATTAGE='1/16W',
 TOLERANCE='5%',
 MATERIAL='EMPTY',
 VALUE='0',
 PRIM_FILE='./archive_libs/logical/q_res/chips/chips.prt';

PART_NAME
 PR158 'Q_RES_0402LF-0,5%,1/16W,CHIP,CA':;

SECTION_NUMBER 1
 '@S9S_MB_2U_LIB.S9S_MB_2U(SCH_1):PAGE252_I51@PURE_QUANTA.Q_RES(CHIPS)':
 C_PATH='@s9s_mb_2u_lib.s9s_mb_2u(sch_1):page252_i51@pure_quanta.q_res(chips)',
 P_PATH='@s9s_mb_2u_lib.s9s_mb_2u(sch_1):page266_i51@pure_quanta.q_res(chips)',
 PATH='I51',
 DRAWING='@S9S_MB_2U_LIB.S9S_MB_2U(SCH_1):PAGE252',
 PHYS_PAGE='266',
 XY='(-4750,900)',
 ROT='0',
 VER='2',
 PACK_TYPE='0402LF',
 LOCATION='PR158',
 CDS_LIB='pure_quanta',
 CDS_PART_NAME='Q_RES_0402LF-0,5%,1/16W,CHIP,CA',
 WATTAGE='1/16W',
 TOLERANCE='5%',
 MATERIAL='CHIP',
 VALUE='0',
 PRIM_FILE='./archive_libs/logical/q_res/chips/chips.prt';

PART_NAME
 PR159 'Q_RES_0402LF-28K,1%,1/16W,EMPTA':;

SECTION_NUMBER 1
 '@S9S_MB_2U_LIB.S9S_MB_2U(SCH_1):PAGE252_I5@PURE_QUANTA.Q_RES(CHIPS)':
 C_PATH='@s9s_mb_2u_lib.s9s_mb_2u(sch_1):page252_i5@pure_quanta.q_res(chips)',
 P_PATH='@s9s_mb_2u_lib.s9s_mb_2u(sch_1):page266_i5@pure_quanta.q_res(chips)',
 PATH='I5',
 DRAWING='@S9S_MB_2U_LIB.S9S_MB_2U(SCH_1):PAGE252',
 PHYS_PAGE='266',
 XY='(-6050,1450)',
 ROT='0',
 VER='1',
 PACK_TYPE='0402LF',
 LOCATION='PR159',
 CDS_LIB='pure_quanta',
 CDS_PART_NAME='Q_RES_0402LF-28K,1%,1/16W,EMPTA',
 WATTAGE='1/16W',
 TOLERANCE='1%',
 MATERIAL='EMPTY',
 VALUE='28K',
 PRIM_FILE='./archive_libs/logical/q_res/chips/chips.prt';

PART_NAME
 PR166 'Q_RES_0402LF-1K,1%,1/16W,EMPTYA':;

SECTION_NUMBER 1
 '@S9S_MB_2U_LIB.S9S_MB_2U(SCH_1):PAGE252_I60@PURE_QUANTA.Q_RES(CHIPS)':
 C_PATH='@s9s_mb_2u_lib.s9s_mb_2u(sch_1):page252_i60@pure_quanta.q_res(chips)',
 P_PATH='@s9s_mb_2u_lib.s9s_mb_2u(sch_1):page266_i60@pure_quanta.q_res(chips)',
 PATH='I60',
 DRAWING='@S9S_MB_2U_LIB.S9S_MB_2U(SCH_1):PAGE252',
 PHYS_PAGE='266',
 XY='(-4050,900)',
 ROT='0',
 VER='2',
 PACK_TYPE='0402LF',
 LOCATION='PR166',
 CDS_LIB='pure_quanta',
 CDS_PART_NAME='Q_RES_0402LF-1K,1%,1/16W,EMPTYA',
 WATTAGE='1/16W',
 TOLERANCE='1%',
 MATERIAL='EMPTY',
 VALUE='1K',
 PRIM_FILE='./archive_libs/logical/q_res/chips/chips.prt';

PART_NAME
 PR170 'Q_RES_0402LF-0,5%,1/16W,CHIP,CA':;

SECTION_NUMBER 1
 '@S9S_MB_2U_LIB.S9S_MB_2U(SCH_1):PAGE252_I77@PURE_QUANTA.Q_RES(CHIPS)':
 C_PATH='@s9s_mb_2u_lib.s9s_mb_2u(sch_1):page252_i77@pure_quanta.q_res(chips)',
 P_PATH='@s9s_mb_2u_lib.s9s_mb_2u(sch_1):page266_i77@pure_quanta.q_res(chips)',
 PATH='I77',
 DRAWING='@S9S_MB_2U_LIB.S9S_MB_2U(SCH_1):PAGE252',
 PHYS_PAGE='266',
 XY='(-4775,4550)',
 ROT='0',
 VER='1',
 PACK_TYPE='0402LF',
 LOCATION='PR170',
 CDS_LIB='pure_quanta',
 CDS_PART_NAME='Q_RES_0402LF-0,5%,1/16W,CHIP,CA',
 WATTAGE='1/16W',
 TOLERANCE='5%',
 MATERIAL='CHIP',
 VALUE='0',
 PRIM_FILE='./archive_libs/logical/q_res/chips/chips.prt';

PART_NAME
 PR171 'Q_RES_0402LF-0,5%,1/16W,CHIP,CA':;

SECTION_NUMBER 1
 '@S9S_MB_2U_LIB.S9S_MB_2U(SCH_1):PAGE252_I8@PURE_QUANTA.Q_RES(CHIPS)':
 C_PATH='@s9s_mb_2u_lib.s9s_mb_2u(sch_1):page252_i8@pure_quanta.q_res(chips)',
 P_PATH='@s9s_mb_2u_lib.s9s_mb_2u(sch_1):page266_i8@pure_quanta.q_res(chips)',
 PATH='I8',
 DRAWING='@S9S_MB_2U_LIB.S9S_MB_2U(SCH_1):PAGE252',
 PHYS_PAGE='266',
 XY='(-5675,1225)',
 ROT='2',
 VER='2',
 PACK_TYPE='0402LF',
 LOCATION='PR171',
 CDS_LIB='pure_quanta',
 CDS_PART_NAME='Q_RES_0402LF-0,5%,1/16W,CHIP,CA',
 WATTAGE='1/16W',
 TOLERANCE='5%',
 MATERIAL='CHIP',
 VALUE='0',
 PRIM_FILE='./archive_libs/logical/q_res/chips/chips.prt';

PART_NAME
 PR176 'Q_RES_0402LF-1,1%,1/16W,CHIP,CA':;

SECTION_NUMBER 1
 '@S9S_MB_2U_LIB.S9S_MB_2U(SCH_1):PAGE252_I133@PURE_QUANTA.Q_RES(CHIPS)':
 C_PATH='@s9s_mb_2u_lib.s9s_mb_2u(sch_1):page252_i133@pure_quanta.q_res(chips)',
 P_PATH='@s9s_mb_2u_lib.s9s_mb_2u(sch_1):page266_i133@pure_quanta.q_res(chips)',
 PATH='I133',
 DRAWING='@S9S_MB_2U_LIB.S9S_MB_2U(SCH_1):PAGE252',
 PHYS_PAGE='266',
 XY='(-775,6550)',
 ROT='0',
 VER='1',
 PACK_TYPE='0402LF',
 LOCATION='PR176',
 CDS_LIB='pure_quanta',
 CDS_PART_NAME='Q_RES_0402LF-1,1%,1/16W,CHIP,CA',
 WATTAGE='1/16W',
 TOLERANCE='1%',
 MATERIAL='CHIP',
 VALUE='1',
 PRIM_FILE='./archive_libs/logical/q_res/chips/chips.prt';

PART_NAME
 PR187 'Q_RES_0402LF-10K,0.1%,1/16W,CHA':;

SECTION_NUMBER 1
 '@S9S_MB_2U_LIB.S9S_MB_2U(SCH_1):PAGE248_I34@PURE_QUANTA.Q_RES(CHIPS)':
 C_PATH='@s9s_mb_2u_lib.s9s_mb_2u(sch_1):page248_i34@pure_quanta.q_res(chips)',
 P_PATH='@s9s_mb_2u_lib.s9s_mb_2u(sch_1):page262_i34@pure_quanta.q_res(chips)',
 PATH='I34',
 DRAWING='@S9S_MB_2U_LIB.S9S_MB_2U(SCH_1):PAGE248',
 BOM_COST='VR_PCH',
 PHYS_PAGE='262',
 XY='(700,-1300)',
 ROT='0',
 VER='2',
 PACK_TYPE='0402LF',
 LOCATION='PR187',
 CDS_LIB='pure_quanta',
 CDS_PART_NAME='Q_RES_0402LF-10K,0.1%,1/16W,CHA',
 WATTAGE='1/16W',
 TOLERANCE='0.1%',
 MATERIAL='CHIP',
 VALUE='10K',
 PRIM_FILE='./archive_libs/logical/q_res/chips/chips.prt';

PART_NAME
 PR200 'Q_RES_0402LF-2.2,1%,1/16W,CHIPA':;

SECTION_NUMBER 1
 '@S9S_MB_2U_LIB.S9S_MB_2U(SCH_1):PAGE283_I16@PURE_QUANTA.Q_RES(CHIPS)':
 C_PATH='@s9s_mb_2u_lib.s9s_mb_2u(sch_1):page283_i16@pure_quanta.q_res(chips)',
 P_PATH='@s9s_mb_2u_lib.s9s_mb_2u(sch_1):page297_i16@pure_quanta.q_res(chips)',
 PATH='I16',
 DRAWING='@S9S_MB_2U_LIB.S9S_MB_2U(SCH_1):PAGE283',
 PHYS_PAGE='297',
 XY='(-8050,4475)',
 ROT='0',
 VER='2',
 PACK_TYPE='0402LF',
 LOCATION='PR200',
 CDS_LIB='pure_quanta',
 CDS_PART_NAME='Q_RES_0402LF-2.2,1%,1/16W,CHIPA',
 WATTAGE='1/16W',
 TOLERANCE='1%',
 MATERIAL='CHIP',
 VALUE='2.2',
 PRIM_FILE='./archive_libs/logical/q_res/chips/chips.prt';

PART_NAME
 PR202 'Q_RES_0402LF-28K,1%,1/16W,EMPTA':;

SECTION_NUMBER 1
 '@S9S_MB_2U_LIB.S9S_MB_2U(SCH_1):PAGE282_I8@PURE_QUANTA.Q_RES(CHIPS)':
 C_PATH='@s9s_mb_2u_lib.s9s_mb_2u(sch_1):page282_i8@pure_quanta.q_res(chips)',
 P_PATH='@s9s_mb_2u_lib.s9s_mb_2u(sch_1):page296_i8@pure_quanta.q_res(chips)',
 PATH='I8',
 DRAWING='@S9S_MB_2U_LIB.S9S_MB_2U(SCH_1):PAGE282',
 PHYS_PAGE='296',
 XY='(-6200,350)',
 ROT='0',
 VER='1',
 PACK_TYPE='0402LF',
 LOCATION='PR202',
 CDS_LIB='pure_quanta',
 CDS_PART_NAME='Q_RES_0402LF-28K,1%,1/16W,EMPTA',
 WATTAGE='1/16W',
 TOLERANCE='1%',
 MATERIAL='EMPTY',
 VALUE='28K',
 PRIM_FILE='./archive_libs/logical/q_res/chips/chips.prt';

PART_NAME
 PR203 'Q_RES_0402LF-24.3K,1%,1/16W,CHA':;

SECTION_NUMBER 1
 '@S9S_MB_2U_LIB.S9S_MB_2U(SCH_1):PAGE282_I95@PURE_QUANTA.Q_RES(CHIPS)':
 C_PATH='@s9s_mb_2u_lib.s9s_mb_2u(sch_1):page282_i95@pure_quanta.q_res(chips)',
 P_PATH='@s9s_mb_2u_lib.s9s_mb_2u(sch_1):page296_i95@pure_quanta.q_res(chips)',
 PATH='I95',
 DRAWING='@S9S_MB_2U_LIB.S9S_MB_2U(SCH_1):PAGE282',
 PHYS_PAGE='296',
 XY='(-6200,225)',
 ROT='0',
 VER='1',
 PACK_TYPE='0402LF',
 LOCATION='PR203',
 CDS_LIB='pure_quanta',
 CDS_PART_NAME='Q_RES_0402LF-24.3K,1%,1/16W,CHA',
 WATTAGE='1/16W',
 TOLERANCE='1%',
 MATERIAL='CHIP',
 VALUE='24.3K',
 PRIM_FILE='./archive_libs/logical/q_res/chips/chips.prt';

PART_NAME
 PR214 'Q_RES_0402LF-1K,1%,1/16W,EMPTYA':;

SECTION_NUMBER 1
 '@S9S_MB_2U_LIB.S9S_MB_2U(SCH_1):PAGE282_I11@PURE_QUANTA.Q_RES(CHIPS)':
 C_PATH='@s9s_mb_2u_lib.s9s_mb_2u(sch_1):page282_i11@pure_quanta.q_res(chips)',
 P_PATH='@s9s_mb_2u_lib.s9s_mb_2u(sch_1):page296_i11@pure_quanta.q_res(chips)',
 PATH='I11',
 DRAWING='@S9S_MB_2U_LIB.S9S_MB_2U(SCH_1):PAGE282',
 PHYS_PAGE='296',
 XY='(-5000,-200)',
 ROT='2',
 VER='2',
 PACK_TYPE='0402LF',
 LOCATION='PR214',
 CDS_LIB='pure_quanta',
 CDS_PART_NAME='Q_RES_0402LF-1K,1%,1/16W,EMPTYA',
 WATTAGE='1/16W',
 TOLERANCE='1%',
 MATERIAL='EMPTY',
 VALUE='1K',
 PRIM_FILE='./archive_libs/logical/q_res/chips/chips.prt';

PART_NAME
 PR215 'Q_RES_0402LF-1K,1%,1/16W,CHIP,A':;

SECTION_NUMBER 1
 '@S9S_MB_2U_LIB.S9S_MB_2U(SCH_1):PAGE282_I18@PURE_QUANTA.Q_RES(CHIPS)':
 C_PATH='@s9s_mb_2u_lib.s9s_mb_2u(sch_1):page282_i18@pure_quanta.q_res(chips)',
 P_PATH='@s9s_mb_2u_lib.s9s_mb_2u(sch_1):page296_i18@pure_quanta.q_res(chips)',
 PATH='I18',
 DRAWING='@S9S_MB_2U_LIB.S9S_MB_2U(SCH_1):PAGE282',
 PHYS_PAGE='296',
 XY='(-5075,1750)',
 ROT='0',
 VER='2',
 PACK_TYPE='0402LF',
 LOCATION='PR215',
 CDS_LIB='pure_quanta',
 CDS_PART_NAME='Q_RES_0402LF-1K,1%,1/16W,CHIP,A',
 WATTAGE='1/16W',
 TOLERANCE='1%',
 MATERIAL='CHIP',
 VALUE='1K',
 PRIM_FILE='./archive_libs/logical/q_res/chips/chips.prt';

PART_NAME
 PR216 'Q_RES_0402LF-0,5%,1/16W,CHIP,CA':;

SECTION_NUMBER 1
 '@S9S_MB_2U_LIB.S9S_MB_2U(SCH_1):PAGE282_I21@PURE_QUANTA.Q_RES(CHIPS)':
 C_PATH='@s9s_mb_2u_lib.s9s_mb_2u(sch_1):page282_i21@pure_quanta.q_res(chips)',
 P_PATH='@s9s_mb_2u_lib.s9s_mb_2u(sch_1):page296_i21@pure_quanta.q_res(chips)',
 PATH='I21',
 DRAWING='@S9S_MB_2U_LIB.S9S_MB_2U(SCH_1):PAGE282',
 PHYS_PAGE='296',
 XY='(-4925,3450)',
 ROT='0',
 VER='1',
 PACK_TYPE='0402LF',
 LOCATION='PR216',
 CDS_LIB='pure_quanta',
 CDS_PART_NAME='Q_RES_0402LF-0,5%,1/16W,CHIP,CA',
 WATTAGE='1/16W',
 TOLERANCE='5%',
 MATERIAL='CHIP',
 VALUE='0',
 PRIM_FILE='./archive_libs/logical/q_res/chips/chips.prt';

PART_NAME
 PR217 'Q_RES_0402LF-1K,1%,1/16W,CHIP,A':;

SECTION_NUMBER 1
 '@S9S_MB_2U_LIB.S9S_MB_2U(SCH_1):PAGE282_I20@PURE_QUANTA.Q_RES(CHIPS)':
 C_PATH='@s9s_mb_2u_lib.s9s_mb_2u(sch_1):page282_i20@pure_quanta.q_res(chips)',
 P_PATH='@s9s_mb_2u_lib.s9s_mb_2u(sch_1):page296_i20@pure_quanta.q_res(chips)',
 PATH='I20',
 DRAWING='@S9S_MB_2U_LIB.S9S_MB_2U(SCH_1):PAGE282',
 PHYS_PAGE='296',
 XY='(-4750,1750)',
 ROT='0',
 VER='2',
 PACK_TYPE='0402LF',
 LOCATION='PR217',
 CDS_LIB='pure_quanta',
 CDS_PART_NAME='Q_RES_0402LF-1K,1%,1/16W,CHIP,A',
 WATTAGE='1/16W',
 TOLERANCE='1%',
 MATERIAL='CHIP',
 VALUE='1K',
 PRIM_FILE='./archive_libs/logical/q_res/chips/chips.prt';

PART_NAME
 PR218 'Q_RES_0402LF-1K,1%,1/16W,EMPTYA':;

SECTION_NUMBER 1
 '@S9S_MB_2U_LIB.S9S_MB_2U(SCH_1):PAGE282_I48@PURE_QUANTA.Q_RES(CHIPS)':
 C_PATH='@s9s_mb_2u_lib.s9s_mb_2u(sch_1):page282_i48@pure_quanta.q_res(chips)',
 P_PATH='@s9s_mb_2u_lib.s9s_mb_2u(sch_1):page296_i48@pure_quanta.q_res(chips)',
 PATH='I48',
 DRAWING='@S9S_MB_2U_LIB.S9S_MB_2U(SCH_1):PAGE282',
 PHYS_PAGE='296',
 XY='(-4150,-200)',
 ROT='2',
 VER='2',
 PACK_TYPE='0402LF',
 LOCATION='PR218',
 CDS_LIB='pure_quanta',
 CDS_PART_NAME='Q_RES_0402LF-1K,1%,1/16W,EMPTYA',
 WATTAGE='1/16W',
 TOLERANCE='1%',
 MATERIAL='EMPTY',
 VALUE='1K',
 PRIM_FILE='./archive_libs/logical/q_res/chips/chips.prt';

PART_NAME
 PR220 'Q_RES_0402LF-1,1%,1/16W,CHIP,CA':;

SECTION_NUMBER 1
 '@S9S_MB_2U_LIB.S9S_MB_2U(SCH_1):PAGE282_I78@PURE_QUANTA.Q_RES(CHIPS)':
 C_PATH='@s9s_mb_2u_lib.s9s_mb_2u(sch_1):page282_i78@pure_quanta.q_res(chips)',
 P_PATH='@s9s_mb_2u_lib.s9s_mb_2u(sch_1):page296_i78@pure_quanta.q_res(chips)',
 PATH='I78',
 DRAWING='@S9S_MB_2U_LIB.S9S_MB_2U(SCH_1):PAGE282',
 PHYS_PAGE='296',
 XY='(-975,5450)',
 ROT='0',
 VER='1',
 PACK_TYPE='0402LF',
 LOCATION='PR220',
 CDS_LIB='pure_quanta',
 CDS_PART_NAME='Q_RES_0402LF-1,1%,1/16W,CHIP,CA',
 WATTAGE='1/16W',
 TOLERANCE='1%',
 MATERIAL='CHIP',
 VALUE='1',
 PRIM_FILE='./archive_libs/logical/q_res/chips/chips.prt';

PART_NAME
 PR224 'Q_RES_0402LF-8.87K,1%,1/16W,EMA':;

SECTION_NUMBER 1
 '@S9S_MB_2U_LIB.S9S_MB_2U(SCH_1):PAGE275_I2@PURE_QUANTA.Q_RES(CHIPS)':
 C_PATH='@s9s_mb_2u_lib.s9s_mb_2u(sch_1):page275_i2@pure_quanta.q_res(chips)',
 P_PATH='@s9s_mb_2u_lib.s9s_mb_2u(sch_1):page289_i2@pure_quanta.q_res(chips)',
 PATH='I2',
 DRAWING='@S9S_MB_2U_LIB.S9S_MB_2U(SCH_1):PAGE275',
 PHYS_PAGE='289',
 XY='(-10750,1375)',
 ROT='2',
 VER='2',
 PACK_TYPE='0402LF',
 LOCATION='PR224',
 CDS_LIB='pure_quanta',
 CDS_PART_NAME='Q_RES_0402LF-8.87K,1%,1/16W,EMA',
 WATTAGE='1/16W',
 TOLERANCE='1%',
 MATERIAL='EMPTY',
 VALUE='8.87K',
 PRIM_FILE='./archive_libs/logical/q_res/chips/chips.prt';

PART_NAME
 PR225 'Q_RES_0402LF-8.87K,1%,1/16W,EMA':;

SECTION_NUMBER 1
 '@S9S_MB_2U_LIB.S9S_MB_2U(SCH_1):PAGE275_I20@PURE_QUANTA.Q_RES(CHIPS)':
 C_PATH='@s9s_mb_2u_lib.s9s_mb_2u(sch_1):page275_i20@pure_quanta.q_res(chips)',
 P_PATH='@s9s_mb_2u_lib.s9s_mb_2u(sch_1):page289_i20@pure_quanta.q_res(chips)',
 PATH='I20',
 DRAWING='@S9S_MB_2U_LIB.S9S_MB_2U(SCH_1):PAGE275',
 PHYS_PAGE='289',
 XY='(-10725,4175)',
 ROT='2',
 VER='2',
 PACK_TYPE='0402LF',
 LOCATION='PR225',
 CDS_LIB='pure_quanta',
 CDS_PART_NAME='Q_RES_0402LF-8.87K,1%,1/16W,EMA',
 WATTAGE='1/16W',
 TOLERANCE='1%',
 MATERIAL='EMPTY',
 VALUE='8.87K',
 PRIM_FILE='./archive_libs/logical/q_res/chips/chips.prt';

PART_NAME
 PR226 'Q_RES_0402LF-2.2,1%,1/16W,CHIPA':;

SECTION_NUMBER 1
 '@S9S_MB_2U_LIB.S9S_MB_2U(SCH_1):PAGE275_I28@PURE_QUANTA.Q_RES(CHIPS)':
 C_PATH='@s9s_mb_2u_lib.s9s_mb_2u(sch_1):page275_i28@pure_quanta.q_res(chips)',
 P_PATH='@s9s_mb_2u_lib.s9s_mb_2u(sch_1):page289_i28@pure_quanta.q_res(chips)',
 PATH='I28',
 DRAWING='@S9S_MB_2U_LIB.S9S_MB_2U(SCH_1):PAGE275',
 PHYS_PAGE='289',
 XY='(-10250,5525)',
 ROT='0',
 VER='2',
 PACK_TYPE='0402LF',
 LOCATION='PR226',
 CDS_LIB='pure_quanta',
 CDS_PART_NAME='Q_RES_0402LF-2.2,1%,1/16W,CHIPA',
 WATTAGE='1/16W',
 TOLERANCE='1%',
 MATERIAL='CHIP',
 VALUE='2.2',
 PRIM_FILE='./archive_libs/logical/q_res/chips/chips.prt';

PART_NAME
 PR227 'Q_RES_0402LF-2.2,1%,1/16W,CHIPA':;

SECTION_NUMBER 1
 '@S9S_MB_2U_LIB.S9S_MB_2U(SCH_1):PAGE275_I12@PURE_QUANTA.Q_RES(CHIPS)':
 C_PATH='@s9s_mb_2u_lib.s9s_mb_2u(sch_1):page275_i12@pure_quanta.q_res(chips)',
 P_PATH='@s9s_mb_2u_lib.s9s_mb_2u(sch_1):page289_i12@pure_quanta.q_res(chips)',
 PATH='I12',
 DRAWING='@S9S_MB_2U_LIB.S9S_MB_2U(SCH_1):PAGE275',
 PHYS_PAGE='289',
 XY='(-10250,2725)',
 ROT='0',
 VER='2',
 PACK_TYPE='0402LF',
 LOCATION='PR227',
 CDS_LIB='pure_quanta',
 CDS_PART_NAME='Q_RES_0402LF-2.2,1%,1/16W,CHIPA',
 WATTAGE='1/16W',
 TOLERANCE='1%',
 MATERIAL='CHIP',
 VALUE='2.2',
 PRIM_FILE='./archive_libs/logical/q_res/chips/chips.prt';

PART_NAME
 PR242 'Q_RES_0402LF-0,5%,1/16W,CHIP,CA':;

SECTION_NUMBER 1
 '@S9S_MB_2U_LIB.S9S_MB_2U(SCH_1):PAGE270_I37@PURE_QUANTA.Q_RES(CHIPS)':
 C_PATH='@s9s_mb_2u_lib.s9s_mb_2u(sch_1):page270_i37@pure_quanta.q_res(chips)',
 P_PATH='@s9s_mb_2u_lib.s9s_mb_2u(sch_1):page284_i37@pure_quanta.q_res(chips)',
 PATH='I37',
 DRAWING='@S9S_MB_2U_LIB.S9S_MB_2U(SCH_1):PAGE270',
 PHYS_PAGE='284',
 XY='(-1775,-75)',
 ROT='0',
 VER='1',
 PACK_TYPE='0402LF',
 LOCATION='PR242',
 CDS_LIB='pure_quanta',
 CDS_PART_NAME='Q_RES_0402LF-0,5%,1/16W,CHIP,CA',
 WATTAGE='1/16W',
 TOLERANCE='5%',
 MATERIAL='CHIP',
 VALUE='0',
 PRIM_FILE='./archive_libs/logical/q_res/chips/chips.prt';

PART_NAME
 PR250 'Q_RES_0402LF-2.2,1%,1/16W,CHIPA':;

SECTION_NUMBER 1
 '@S9S_MB_2U_LIB.S9S_MB_2U(SCH_1):PAGE280_I15@PURE_QUANTA.Q_RES(CHIPS)':
 C_PATH='@s9s_mb_2u_lib.s9s_mb_2u(sch_1):page280_i15@pure_quanta.q_res(chips)',
 P_PATH='@s9s_mb_2u_lib.s9s_mb_2u(sch_1):page294_i15@pure_quanta.q_res(chips)',
 PATH='I15',
 DRAWING='@S9S_MB_2U_LIB.S9S_MB_2U(SCH_1):PAGE280',
 PHYS_PAGE='294',
 XY='(-6100,10050)',
 ROT='0',
 VER='2',
 PACK_TYPE='0402LF',
 LOCATION='PR250',
 CDS_LIB='pure_quanta',
 CDS_PART_NAME='Q_RES_0402LF-2.2,1%,1/16W,CHIPA',
 WATTAGE='1/16W',
 TOLERANCE='1%',
 MATERIAL='CHIP',
 VALUE='2.2',
 PRIM_FILE='./archive_libs/logical/q_res/chips/chips.prt';

PART_NAME
 PR254 'Q_RES_0402LF-2.2,1%,1/16W,CHIPA':;

SECTION_NUMBER 1
 '@S9S_MB_2U_LIB.S9S_MB_2U(SCH_1):PAGE279_I25@PURE_QUANTA.Q_RES(CHIPS)':
 C_PATH='@s9s_mb_2u_lib.s9s_mb_2u(sch_1):page279_i25@pure_quanta.q_res(chips)',
 P_PATH='@s9s_mb_2u_lib.s9s_mb_2u(sch_1):page293_i25@pure_quanta.q_res(chips)',
 PATH='I25',
 DRAWING='@S9S_MB_2U_LIB.S9S_MB_2U(SCH_1):PAGE279',
 PHYS_PAGE='293',
 XY='(-8500,12075)',
 ROT='0',
 VER='2',
 PACK_TYPE='0402LF',
 LOCATION='PR254',
 CDS_LIB='pure_quanta',
 CDS_PART_NAME='Q_RES_0402LF-2.2,1%,1/16W,CHIPA',
 WATTAGE='1/16W',
 TOLERANCE='1%',
 MATERIAL='CHIP',
 VALUE='2.2',
 PRIM_FILE='./archive_libs/logical/q_res/chips/chips.prt';

PART_NAME
 PR255 'Q_RES_0402LF-2.2,1%,1/16W,CHIPA':;

SECTION_NUMBER 1
 '@S9S_MB_2U_LIB.S9S_MB_2U(SCH_1):PAGE279_I11@PURE_QUANTA.Q_RES(CHIPS)':
 C_PATH='@s9s_mb_2u_lib.s9s_mb_2u(sch_1):page279_i11@pure_quanta.q_res(chips)',
 P_PATH='@s9s_mb_2u_lib.s9s_mb_2u(sch_1):page293_i11@pure_quanta.q_res(chips)',
 PATH='I11',
 DRAWING='@S9S_MB_2U_LIB.S9S_MB_2U(SCH_1):PAGE279',
 PHYS_PAGE='293',
 XY='(-8500,9275)',
 ROT='0',
 VER='2',
 PACK_TYPE='0402LF',
 LOCATION='PR255',
 CDS_LIB='pure_quanta',
 CDS_PART_NAME='Q_RES_0402LF-2.2,1%,1/16W,CHIPA',
 WATTAGE='1/16W',
 TOLERANCE='1%',
 MATERIAL='CHIP',
 VALUE='2.2',
 PRIM_FILE='./archive_libs/logical/q_res/chips/chips.prt';

PART_NAME
 PR258 'Q_RES_0402LF-28K,1%,1/16W,EMPTA':;

SECTION_NUMBER 1
 '@S9S_MB_2U_LIB.S9S_MB_2U(SCH_1):PAGE278_I23@PURE_QUANTA.Q_RES(CHIPS)':
 C_PATH='@s9s_mb_2u_lib.s9s_mb_2u(sch_1):page278_i23@pure_quanta.q_res(chips)',
 P_PATH='@s9s_mb_2u_lib.s9s_mb_2u(sch_1):page292_i23@pure_quanta.q_res(chips)',
 PATH='I23',
 DRAWING='@S9S_MB_2U_LIB.S9S_MB_2U(SCH_1):PAGE278',
 PHYS_PAGE='292',
 XY='(500,4050)',
 ROT='0',
 VER='1',
 PACK_TYPE='0402LF',
 LOCATION='PR258',
 CDS_LIB='pure_quanta',
 CDS_PART_NAME='Q_RES_0402LF-28K,1%,1/16W,EMPTA',
 WATTAGE='1/16W',
 TOLERANCE='1%',
 MATERIAL='EMPTY',
 VALUE='28K',
 PRIM_FILE='./archive_libs/logical/q_res/chips/chips.prt';

PART_NAME
 PR259 'Q_RES_0402LF-8.45K,1%,1/16W,CHA':;

SECTION_NUMBER 1
 '@S9S_MB_2U_LIB.S9S_MB_2U(SCH_1):PAGE278_I110@PURE_QUANTA.Q_RES(CHIPS)':
 C_PATH='@s9s_mb_2u_lib.s9s_mb_2u(sch_1):page278_i110@pure_quanta.q_res(chips)',
 P_PATH='@s9s_mb_2u_lib.s9s_mb_2u(sch_1):page292_i110@pure_quanta.q_res(chips)',
 PATH='I110',
 DRAWING='@S9S_MB_2U_LIB.S9S_MB_2U(SCH_1):PAGE278',
 PHYS_PAGE='292',
 XY='(625,3825)',
 ROT='0',
 VER='2',
 PACK_TYPE='0402LF',
 LOCATION='PR259',
 CDS_LIB='pure_quanta',
 CDS_PART_NAME='Q_RES_0402LF-8.45K,1%,1/16W,CHA',
 WATTAGE='1/16W',
 TOLERANCE='1%',
 MATERIAL='CHIP',
 VALUE='8.45K',
 PRIM_FILE='./archive_libs/logical/q_res/chips/chips.prt';

PART_NAME
 PR260 'Q_RES_0402LF-0,5%,1/16W,EMPTY,A':;

SECTION_NUMBER 1
 '@S9S_MB_2U_LIB.S9S_MB_2U(SCH_1):PAGE278_I22@PURE_QUANTA.Q_RES(CHIPS)':
 C_PATH='@s9s_mb_2u_lib.s9s_mb_2u(sch_1):page278_i22@pure_quanta.q_res(chips)',
 P_PATH='@s9s_mb_2u_lib.s9s_mb_2u(sch_1):page292_i22@pure_quanta.q_res(chips)',
 PATH='I22',
 DRAWING='@S9S_MB_2U_LIB.S9S_MB_2U(SCH_1):PAGE278',
 PHYS_PAGE='292',
 XY='(1100,3800)',
 ROT='0',
 VER='1',
 PACK_TYPE='0402LF',
 LOCATION='PR260',
 CDS_LIB='pure_quanta',
 CDS_PART_NAME='Q_RES_0402LF-0,5%,1/16W,EMPTY,A',
 WATTAGE='1/16W',
 TOLERANCE='5%',
 MATERIAL='EMPTY',
 VALUE='0',
 PRIM_FILE='./archive_libs/logical/q_res/chips/chips.prt';

PART_NAME
 PR261 'Q_RES_0402LF-0,5%,1/16W,CHIP,CA':;

SECTION_NUMBER 1
 '@S9S_MB_2U_LIB.S9S_MB_2U(SCH_1):PAGE278_I21@PURE_QUANTA.Q_RES(CHIPS)':
 C_PATH='@s9s_mb_2u_lib.s9s_mb_2u(sch_1):page278_i21@pure_quanta.q_res(chips)',
 P_PATH='@s9s_mb_2u_lib.s9s_mb_2u(sch_1):page292_i21@pure_quanta.q_res(chips)',
 PATH='I21',
 DRAWING='@S9S_MB_2U_LIB.S9S_MB_2U(SCH_1):PAGE278',
 PHYS_PAGE='292',
 XY='(1100,3700)',
 ROT='0',
 VER='1',
 PACK_TYPE='0402LF',
 LOCATION='PR261',
 CDS_LIB='pure_quanta',
 CDS_PART_NAME='Q_RES_0402LF-0,5%,1/16W,CHIP,CA',
 WATTAGE='1/16W',
 TOLERANCE='5%',
 MATERIAL='CHIP',
 VALUE='0',
 PRIM_FILE='./archive_libs/logical/q_res/chips/chips.prt';

PART_NAME
 PR273 'Q_RES_0402LF-0,5%,1/16W,CHIP,CA':;

SECTION_NUMBER 1
 '@S9S_MB_2U_LIB.S9S_MB_2U(SCH_1):PAGE278_I62@PURE_QUANTA.Q_RES(CHIPS)':
 C_PATH='@s9s_mb_2u_lib.s9s_mb_2u(sch_1):page278_i62@pure_quanta.q_res(chips)',
 P_PATH='@s9s_mb_2u_lib.s9s_mb_2u(sch_1):page292_i62@pure_quanta.q_res(chips)',
 PATH='I62',
 DRAWING='@S9S_MB_2U_LIB.S9S_MB_2U(SCH_1):PAGE278',
 PHYS_PAGE='292',
 XY='(1525,7150)',
 ROT='0',
 VER='1',
 PACK_TYPE='0402LF',
 LOCATION='PR273',
 CDS_LIB='pure_quanta',
 CDS_PART_NAME='Q_RES_0402LF-0,5%,1/16W,CHIP,CA',
 WATTAGE='1/16W',
 TOLERANCE='5%',
 MATERIAL='CHIP',
 VALUE='0',
 PRIM_FILE='./archive_libs/logical/q_res/chips/chips.prt';

PART_NAME
 PR274 'Q_RES_0402LF-0,5%,1/16W,CHIP,CA':;

SECTION_NUMBER 1
 '@S9S_MB_2U_LIB.S9S_MB_2U(SCH_1):PAGE278_I52@PURE_QUANTA.Q_RES(CHIPS)':
 C_PATH='@s9s_mb_2u_lib.s9s_mb_2u(sch_1):page278_i52@pure_quanta.q_res(chips)',
 P_PATH='@s9s_mb_2u_lib.s9s_mb_2u(sch_1):page292_i52@pure_quanta.q_res(chips)',
 PATH='I52',
 DRAWING='@S9S_MB_2U_LIB.S9S_MB_2U(SCH_1):PAGE278',
 PHYS_PAGE='292',
 XY='(1525,6050)',
 ROT='0',
 VER='1',
 PACK_TYPE='0402LF',
 LOCATION='PR274',
 CDS_LIB='pure_quanta',
 CDS_PART_NAME='Q_RES_0402LF-0,5%,1/16W,CHIP,CA',
 WATTAGE='1/16W',
 TOLERANCE='5%',
 MATERIAL='CHIP',
 VALUE='0',
 PRIM_FILE='./archive_libs/logical/q_res/chips/chips.prt';

PART_NAME
 PR275 'Q_RES_0402LF-0,5%,1/16W,CHIP,CA':;

SECTION_NUMBER 1
 '@S9S_MB_2U_LIB.S9S_MB_2U(SCH_1):PAGE278_I26@PURE_QUANTA.Q_RES(CHIPS)':
 C_PATH='@s9s_mb_2u_lib.s9s_mb_2u(sch_1):page278_i26@pure_quanta.q_res(chips)',
 P_PATH='@s9s_mb_2u_lib.s9s_mb_2u(sch_1):page292_i26@pure_quanta.q_res(chips)',
 PATH='I26',
 DRAWING='@S9S_MB_2U_LIB.S9S_MB_2U(SCH_1):PAGE278',
 PHYS_PAGE='292',
 XY='(1550,3500)',
 ROT='0',
 VER='2',
 PACK_TYPE='0402LF',
 LOCATION='PR275',
 CDS_LIB='pure_quanta',
 CDS_PART_NAME='Q_RES_0402LF-0,5%,1/16W,CHIP,CA',
 WATTAGE='1/16W',
 TOLERANCE='5%',
 MATERIAL='CHIP',
 VALUE='0',
 PRIM_FILE='./archive_libs/logical/q_res/chips/chips.prt';

PART_NAME
 PR276 'Q_RES_0402LF-1K,1%,1/16W,EMPTYA':;

SECTION_NUMBER 1
 '@S9S_MB_2U_LIB.S9S_MB_2U(SCH_1):PAGE278_I35@PURE_QUANTA.Q_RES(CHIPS)':
 C_PATH='@s9s_mb_2u_lib.s9s_mb_2u(sch_1):page278_i35@pure_quanta.q_res(chips)',
 P_PATH='@s9s_mb_2u_lib.s9s_mb_2u(sch_1):page292_i35@pure_quanta.q_res(chips)',
 PATH='I35',
 DRAWING='@S9S_MB_2U_LIB.S9S_MB_2U(SCH_1):PAGE278',
 PHYS_PAGE='292',
 XY='(2300,3500)',
 ROT='0',
 VER='2',
 PACK_TYPE='0402LF',
 LOCATION='PR276',
 CDS_LIB='pure_quanta',
 CDS_PART_NAME='Q_RES_0402LF-1K,1%,1/16W,EMPTYA',
 WATTAGE='1/16W',
 TOLERANCE='1%',
 MATERIAL='EMPTY',
 VALUE='1K',
 PRIM_FILE='./archive_libs/logical/q_res/chips/chips.prt';

PART_NAME
 PR283 'Q_RES_0402LF-1,1%,1/16W,CHIP,CA':;

SECTION_NUMBER 1
 '@S9S_MB_2U_LIB.S9S_MB_2U(SCH_1):PAGE278_I108@PURE_QUANTA.Q_RES(CHIPS)':
 C_PATH='@s9s_mb_2u_lib.s9s_mb_2u(sch_1):page278_i108@pure_quanta.q_res(chips)',
 P_PATH='@s9s_mb_2u_lib.s9s_mb_2u(sch_1):page292_i108@pure_quanta.q_res(chips)',
 PATH='I108',
 DRAWING='@S9S_MB_2U_LIB.S9S_MB_2U(SCH_1):PAGE278',
 PHYS_PAGE='292',
 XY='(5525,9150)',
 ROT='0',
 VER='1',
 PACK_TYPE='0402LF',
 LOCATION='PR283',
 CDS_LIB='pure_quanta',
 CDS_PART_NAME='Q_RES_0402LF-1,1%,1/16W,CHIP,CA',
 WATTAGE='1/16W',
 TOLERANCE='1%',
 MATERIAL='CHIP',
 VALUE='1',
 PRIM_FILE='./archive_libs/logical/q_res/chips/chips.prt';

PART_NAME
 PR285 'Q_RES_0402LF-8.87K,1%,1/16W,EMA':;

SECTION_NUMBER 1
 '@S9S_MB_2U_LIB.S9S_MB_2U(SCH_1):PAGE274_I3@PURE_QUANTA.Q_RES(CHIPS)':
 C_PATH='@s9s_mb_2u_lib.s9s_mb_2u(sch_1):page274_i3@pure_quanta.q_res(chips)',
 P_PATH='@s9s_mb_2u_lib.s9s_mb_2u(sch_1):page288_i3@pure_quanta.q_res(chips)',
 PATH='I3',
 DRAWING='@S9S_MB_2U_LIB.S9S_MB_2U(SCH_1):PAGE274',
 PHYS_PAGE='288',
 XY='(-7950,1200)',
 ROT='2',
 VER='2',
 PACK_TYPE='0402LF',
 LOCATION='PR285',
 CDS_LIB='pure_quanta',
 CDS_PART_NAME='Q_RES_0402LF-8.87K,1%,1/16W,EMA',
 WATTAGE='1/16W',
 TOLERANCE='1%',
 MATERIAL='EMPTY',
 VALUE='8.87K',
 PRIM_FILE='./archive_libs/logical/q_res/chips/chips.prt';

PART_NAME
 PR286 'Q_RES_0402LF-8.87K,1%,1/16W,EMA':;

SECTION_NUMBER 1
 '@S9S_MB_2U_LIB.S9S_MB_2U(SCH_1):PAGE274_I15@PURE_QUANTA.Q_RES(CHIPS)':
 C_PATH='@s9s_mb_2u_lib.s9s_mb_2u(sch_1):page274_i15@pure_quanta.q_res(chips)',
 P_PATH='@s9s_mb_2u_lib.s9s_mb_2u(sch_1):page288_i15@pure_quanta.q_res(chips)',
 PATH='I15',
 DRAWING='@S9S_MB_2U_LIB.S9S_MB_2U(SCH_1):PAGE274',
 PHYS_PAGE='288',
 XY='(-7925,4025)',
 ROT='2',
 VER='2',
 PACK_TYPE='0402LF',
 LOCATION='PR286',
 CDS_LIB='pure_quanta',
 CDS_PART_NAME='Q_RES_0402LF-8.87K,1%,1/16W,EMA',
 WATTAGE='1/16W',
 TOLERANCE='1%',
 MATERIAL='EMPTY',
 VALUE='8.87K',
 PRIM_FILE='./archive_libs/logical/q_res/chips/chips.prt';

PART_NAME
 PR287 'Q_RES_0402LF-2.2,1%,1/16W,CHIPA':;

SECTION_NUMBER 1
 '@S9S_MB_2U_LIB.S9S_MB_2U(SCH_1):PAGE274_I12@PURE_QUANTA.Q_RES(CHIPS)':
 C_PATH='@s9s_mb_2u_lib.s9s_mb_2u(sch_1):page274_i12@pure_quanta.q_res(chips)',
 P_PATH='@s9s_mb_2u_lib.s9s_mb_2u(sch_1):page288_i12@pure_quanta.q_res(chips)',
 PATH='I12',
 DRAWING='@S9S_MB_2U_LIB.S9S_MB_2U(SCH_1):PAGE274',
 PHYS_PAGE='288',
 XY='(-7550,2700)',
 ROT='0',
 VER='2',
 PACK_TYPE='0402LF',
 LOCATION='PR287',
 CDS_LIB='pure_quanta',
 CDS_PART_NAME='Q_RES_0402LF-2.2,1%,1/16W,CHIPA',
 WATTAGE='1/16W',
 TOLERANCE='1%',
 MATERIAL='CHIP',
 VALUE='2.2',
 PRIM_FILE='./archive_libs/logical/q_res/chips/chips.prt';

PART_NAME
 PR288 'Q_RES_0402LF-2.2,1%,1/16W,CHIPA':;

SECTION_NUMBER 1
 '@S9S_MB_2U_LIB.S9S_MB_2U(SCH_1):PAGE274_I68@PURE_QUANTA.Q_RES(CHIPS)':
 C_PATH='@s9s_mb_2u_lib.s9s_mb_2u(sch_1):page274_i68@pure_quanta.q_res(chips)',
 P_PATH='@s9s_mb_2u_lib.s9s_mb_2u(sch_1):page288_i68@pure_quanta.q_res(chips)',
 PATH='I68',
 DRAWING='@S9S_MB_2U_LIB.S9S_MB_2U(SCH_1):PAGE274',
 PHYS_PAGE='288',
 XY='(-7525,5525)',
 ROT='0',
 VER='2',
 PACK_TYPE='0402LF',
 LOCATION='PR288',
 CDS_LIB='pure_quanta',
 CDS_PART_NAME='Q_RES_0402LF-2.2,1%,1/16W,CHIPA',
 WATTAGE='1/16W',
 TOLERANCE='1%',
 MATERIAL='CHIP',
 VALUE='2.2',
 PRIM_FILE='./archive_libs/logical/q_res/chips/chips.prt';

PART_NAME
 PR289 'Q_RES_0402LF-0,5%,1/16W,CHIP,CA':;

SECTION_NUMBER 1
 '@S9S_MB_2U_LIB.S9S_MB_2U(SCH_1):PAGE274_I44@PURE_QUANTA.Q_RES(CHIPS)':
 C_PATH='@s9s_mb_2u_lib.s9s_mb_2u(sch_1):page274_i44@pure_quanta.q_res(chips)',
 P_PATH='@s9s_mb_2u_lib.s9s_mb_2u(sch_1):page288_i44@pure_quanta.q_res(chips)',
 PATH='I44',
 DRAWING='@S9S_MB_2U_LIB.S9S_MB_2U(SCH_1):PAGE274',
 PHYS_PAGE='288',
 XY='(-3525,1125)',
 ROT='0',
 VER='1',
 PACK_TYPE='0402LF',
 LOCATION='PR289',
 CDS_LIB='pure_quanta',
 CDS_PART_NAME='Q_RES_0402LF-0,5%,1/16W,CHIP,CA',
 WATTAGE='1/16W',
 TOLERANCE='5%',
 MATERIAL='CHIP',
 VALUE='0',
 PRIM_FILE='./archive_libs/logical/q_res/chips/chips.prt';

PART_NAME
 PR290 'Q_RES_0402LF-0,5%,1/16W,CHIP,CA':;

SECTION_NUMBER 1
 '@S9S_MB_2U_LIB.S9S_MB_2U(SCH_1):PAGE274_I50@PURE_QUANTA.Q_RES(CHIPS)':
 C_PATH='@s9s_mb_2u_lib.s9s_mb_2u(sch_1):page274_i50@pure_quanta.q_res(chips)',
 P_PATH='@s9s_mb_2u_lib.s9s_mb_2u(sch_1):page288_i50@pure_quanta.q_res(chips)',
 PATH='I50',
 DRAWING='@S9S_MB_2U_LIB.S9S_MB_2U(SCH_1):PAGE274',
 PHYS_PAGE='288',
 XY='(-3525,3950)',
 ROT='0',
 VER='1',
 PACK_TYPE='0402LF',
 LOCATION='PR290',
 CDS_LIB='pure_quanta',
 CDS_PART_NAME='Q_RES_0402LF-0,5%,1/16W,CHIP,CA',
 WATTAGE='1/16W',
 TOLERANCE='5%',
 MATERIAL='CHIP',
 VALUE='0',
 PRIM_FILE='./archive_libs/logical/q_res/chips/chips.prt';

PART_NAME
 PR291 'Q_RES_0402LF-8.87K,1%,1/16W,EMA':;

SECTION_NUMBER 1
 '@S9S_MB_2U_LIB.S9S_MB_2U(SCH_1):PAGE273_I2@PURE_QUANTA.Q_RES(CHIPS)':
 C_PATH='@s9s_mb_2u_lib.s9s_mb_2u(sch_1):page273_i2@pure_quanta.q_res(chips)',
 P_PATH='@s9s_mb_2u_lib.s9s_mb_2u(sch_1):page287_i2@pure_quanta.q_res(chips)',
 PATH='I2',
 DRAWING='@S9S_MB_2U_LIB.S9S_MB_2U(SCH_1):PAGE273',
 PHYS_PAGE='287',
 XY='(3375,-825)',
 ROT='2',
 VER='2',
 PACK_TYPE='0402LF',
 LOCATION='PR291',
 CDS_LIB='pure_quanta',
 CDS_PART_NAME='Q_RES_0402LF-8.87K,1%,1/16W,EMA',
 WATTAGE='1/16W',
 TOLERANCE='1%',
 MATERIAL='EMPTY',
 VALUE='8.87K',
 PRIM_FILE='./archive_libs/logical/q_res/chips/chips.prt';

PART_NAME
 PR292 'Q_RES_0402LF-8.87K,1%,1/16W,EMA':;

SECTION_NUMBER 1
 '@S9S_MB_2U_LIB.S9S_MB_2U(SCH_1):PAGE273_I7@PURE_QUANTA.Q_RES(CHIPS)':
 C_PATH='@s9s_mb_2u_lib.s9s_mb_2u(sch_1):page273_i7@pure_quanta.q_res(chips)',
 P_PATH='@s9s_mb_2u_lib.s9s_mb_2u(sch_1):page287_i7@pure_quanta.q_res(chips)',
 PATH='I7',
 DRAWING='@S9S_MB_2U_LIB.S9S_MB_2U(SCH_1):PAGE273',
 PHYS_PAGE='287',
 XY='(3400,2000)',
 ROT='2',
 VER='2',
 PACK_TYPE='0402LF',
 LOCATION='PR292',
 CDS_LIB='pure_quanta',
 CDS_PART_NAME='Q_RES_0402LF-8.87K,1%,1/16W,EMA',
 WATTAGE='1/16W',
 TOLERANCE='1%',
 MATERIAL='EMPTY',
 VALUE='8.87K',
 PRIM_FILE='./archive_libs/logical/q_res/chips/chips.prt';

PART_NAME
 PR293 'Q_RES_0402LF-2.2,1%,1/16W,CHIPA':;

SECTION_NUMBER 1
 '@S9S_MB_2U_LIB.S9S_MB_2U(SCH_1):PAGE273_I19@PURE_QUANTA.Q_RES(CHIPS)':
 C_PATH='@s9s_mb_2u_lib.s9s_mb_2u(sch_1):page273_i19@pure_quanta.q_res(chips)',
 P_PATH='@s9s_mb_2u_lib.s9s_mb_2u(sch_1):page287_i19@pure_quanta.q_res(chips)',
 PATH='I19',
 DRAWING='@S9S_MB_2U_LIB.S9S_MB_2U(SCH_1):PAGE273',
 PHYS_PAGE='287',
 XY='(3775,675)',
 ROT='0',
 VER='2',
 PACK_TYPE='0402LF',
 LOCATION='PR293',
 CDS_LIB='pure_quanta',
 CDS_PART_NAME='Q_RES_0402LF-2.2,1%,1/16W,CHIPA',
 WATTAGE='1/16W',
 TOLERANCE='1%',
 MATERIAL='CHIP',
 VALUE='2.2',
 PRIM_FILE='./archive_libs/logical/q_res/chips/chips.prt';

PART_NAME
 PR294 'Q_RES_0402LF-2.2,1%,1/16W,CHIPA':;

SECTION_NUMBER 1
 '@S9S_MB_2U_LIB.S9S_MB_2U(SCH_1):PAGE273_I39@PURE_QUANTA.Q_RES(CHIPS)':
 C_PATH='@s9s_mb_2u_lib.s9s_mb_2u(sch_1):page273_i39@pure_quanta.q_res(chips)',
 P_PATH='@s9s_mb_2u_lib.s9s_mb_2u(sch_1):page287_i39@pure_quanta.q_res(chips)',
 PATH='I39',
 DRAWING='@S9S_MB_2U_LIB.S9S_MB_2U(SCH_1):PAGE273',
 PHYS_PAGE='287',
 XY='(3800,3500)',
 ROT='0',
 VER='2',
 PACK_TYPE='0402LF',
 LOCATION='PR294',
 CDS_LIB='pure_quanta',
 CDS_PART_NAME='Q_RES_0402LF-2.2,1%,1/16W,CHIPA',
 WATTAGE='1/16W',
 TOLERANCE='1%',
 MATERIAL='CHIP',
 VALUE='2.2',
 PRIM_FILE='./archive_libs/logical/q_res/chips/chips.prt';

PART_NAME
 PR295 'Q_RES_0402LF-0,5%,1/16W,CHIP,CA':;

SECTION_NUMBER 1
 '@S9S_MB_2U_LIB.S9S_MB_2U(SCH_1):PAGE273_I27@PURE_QUANTA.Q_RES(CHIPS)':
 C_PATH='@s9s_mb_2u_lib.s9s_mb_2u(sch_1):page273_i27@pure_quanta.q_res(chips)',
 P_PATH='@s9s_mb_2u_lib.s9s_mb_2u(sch_1):page287_i27@pure_quanta.q_res(chips)',
 PATH='I27',
 DRAWING='@S9S_MB_2U_LIB.S9S_MB_2U(SCH_1):PAGE273',
 PHYS_PAGE='287',
 XY='(7850,-900)',
 ROT='0',
 VER='1',
 PACK_TYPE='0402LF',
 LOCATION='PR295',
 CDS_LIB='pure_quanta',
 CDS_PART_NAME='Q_RES_0402LF-0,5%,1/16W,CHIP,CA',
 WATTAGE='1/16W',
 TOLERANCE='5%',
 MATERIAL='CHIP',
 VALUE='0',
 PRIM_FILE='./archive_libs/logical/q_res/chips/chips.prt';

PART_NAME
 PR296 'Q_RES_0402LF-0,5%,1/16W,CHIP,CA':;

SECTION_NUMBER 1
 '@S9S_MB_2U_LIB.S9S_MB_2U(SCH_1):PAGE273_I49@PURE_QUANTA.Q_RES(CHIPS)':
 C_PATH='@s9s_mb_2u_lib.s9s_mb_2u(sch_1):page273_i49@pure_quanta.q_res(chips)',
 P_PATH='@s9s_mb_2u_lib.s9s_mb_2u(sch_1):page287_i49@pure_quanta.q_res(chips)',
 PATH='I49',
 DRAWING='@S9S_MB_2U_LIB.S9S_MB_2U(SCH_1):PAGE273',
 PHYS_PAGE='287',
 XY='(7900,1975)',
 ROT='0',
 VER='1',
 PACK_TYPE='0402LF',
 LOCATION='PR296',
 CDS_LIB='pure_quanta',
 CDS_PART_NAME='Q_RES_0402LF-0,5%,1/16W,CHIP,CA',
 WATTAGE='1/16W',
 TOLERANCE='5%',
 MATERIAL='CHIP',
 VALUE='0',
 PRIM_FILE='./archive_libs/logical/q_res/chips/chips.prt';

PART_NAME
 PR297 'Q_RES_0402LF-8.87K,1%,1/16W,EMA':;

SECTION_NUMBER 1
 '@S9S_MB_2U_LIB.S9S_MB_2U(SCH_1):PAGE272_I3@PURE_QUANTA.Q_RES(CHIPS)':
 C_PATH='@s9s_mb_2u_lib.s9s_mb_2u(sch_1):page272_i3@pure_quanta.q_res(chips)',
 P_PATH='@s9s_mb_2u_lib.s9s_mb_2u(sch_1):page286_i3@pure_quanta.q_res(chips)',
 PATH='I3',
 DRAWING='@S9S_MB_2U_LIB.S9S_MB_2U(SCH_1):PAGE272',
 PHYS_PAGE='286',
 XY='(-2775,-2050)',
 ROT='2',
 VER='2',
 PACK_TYPE='0402LF',
 LOCATION='PR297',
 CDS_LIB='pure_quanta',
 CDS_PART_NAME='Q_RES_0402LF-8.87K,1%,1/16W,EMA',
 WATTAGE='1/16W',
 TOLERANCE='1%',
 MATERIAL='EMPTY',
 VALUE='8.87K',
 PRIM_FILE='./archive_libs/logical/q_res/chips/chips.prt';

PART_NAME
 PR298 'Q_RES_0402LF-8.87K,1%,1/16W,EMA':;

SECTION_NUMBER 1
 '@S9S_MB_2U_LIB.S9S_MB_2U(SCH_1):PAGE272_I15@PURE_QUANTA.Q_RES(CHIPS)':
 C_PATH='@s9s_mb_2u_lib.s9s_mb_2u(sch_1):page272_i15@pure_quanta.q_res(chips)',
 P_PATH='@s9s_mb_2u_lib.s9s_mb_2u(sch_1):page286_i15@pure_quanta.q_res(chips)',
 PATH='I15',
 DRAWING='@S9S_MB_2U_LIB.S9S_MB_2U(SCH_1):PAGE272',
 PHYS_PAGE='286',
 XY='(-2750,775)',
 ROT='2',
 VER='2',
 PACK_TYPE='0402LF',
 LOCATION='PR298',
 CDS_LIB='pure_quanta',
 CDS_PART_NAME='Q_RES_0402LF-8.87K,1%,1/16W,EMA',
 WATTAGE='1/16W',
 TOLERANCE='1%',
 MATERIAL='EMPTY',
 VALUE='8.87K',
 PRIM_FILE='./archive_libs/logical/q_res/chips/chips.prt';

PART_NAME
 PR299 'Q_RES_0402LF-2.2,1%,1/16W,CHIPA':;

SECTION_NUMBER 1
 '@S9S_MB_2U_LIB.S9S_MB_2U(SCH_1):PAGE272_I12@PURE_QUANTA.Q_RES(CHIPS)':
 C_PATH='@s9s_mb_2u_lib.s9s_mb_2u(sch_1):page272_i12@pure_quanta.q_res(chips)',
 P_PATH='@s9s_mb_2u_lib.s9s_mb_2u(sch_1):page286_i12@pure_quanta.q_res(chips)',
 PATH='I12',
 DRAWING='@S9S_MB_2U_LIB.S9S_MB_2U(SCH_1):PAGE272',
 PHYS_PAGE='286',
 XY='(-2375,-550)',
 ROT='0',
 VER='2',
 PACK_TYPE='0402LF',
 LOCATION='PR299',
 CDS_LIB='pure_quanta',
 CDS_PART_NAME='Q_RES_0402LF-2.2,1%,1/16W,CHIPA',
 WATTAGE='1/16W',
 TOLERANCE='1%',
 MATERIAL='CHIP',
 VALUE='2.2',
 PRIM_FILE='./archive_libs/logical/q_res/chips/chips.prt';

PART_NAME
 PR300 'Q_RES_0402LF-2.2,1%,1/16W,CHIPA':;

SECTION_NUMBER 1
 '@S9S_MB_2U_LIB.S9S_MB_2U(SCH_1):PAGE272_I25@PURE_QUANTA.Q_RES(CHIPS)':
 C_PATH='@s9s_mb_2u_lib.s9s_mb_2u(sch_1):page272_i25@pure_quanta.q_res(chips)',
 P_PATH='@s9s_mb_2u_lib.s9s_mb_2u(sch_1):page286_i25@pure_quanta.q_res(chips)',
 PATH='I25',
 DRAWING='@S9S_MB_2U_LIB.S9S_MB_2U(SCH_1):PAGE272',
 PHYS_PAGE='286',
 XY='(-2350,2275)',
 ROT='0',
 VER='2',
 PACK_TYPE='0402LF',
 LOCATION='PR300',
 CDS_LIB='pure_quanta',
 CDS_PART_NAME='Q_RES_0402LF-2.2,1%,1/16W,CHIPA',
 WATTAGE='1/16W',
 TOLERANCE='1%',
 MATERIAL='CHIP',
 VALUE='2.2',
 PRIM_FILE='./archive_libs/logical/q_res/chips/chips.prt';

PART_NAME
 PR301 'Q_RES_0402LF-0,5%,1/16W,CHIP,CA':;

SECTION_NUMBER 1
 '@S9S_MB_2U_LIB.S9S_MB_2U(SCH_1):PAGE272_I38@PURE_QUANTA.Q_RES(CHIPS)':
 C_PATH='@s9s_mb_2u_lib.s9s_mb_2u(sch_1):page272_i38@pure_quanta.q_res(chips)',
 P_PATH='@s9s_mb_2u_lib.s9s_mb_2u(sch_1):page286_i38@pure_quanta.q_res(chips)',
 PATH='I38',
 DRAWING='@S9S_MB_2U_LIB.S9S_MB_2U(SCH_1):PAGE272',
 PHYS_PAGE='286',
 XY='(1525,-2175)',
 ROT='0',
 VER='1',
 PACK_TYPE='0402LF',
 LOCATION='PR301',
 CDS_LIB='pure_quanta',
 CDS_PART_NAME='Q_RES_0402LF-0,5%,1/16W,CHIP,CA',
 WATTAGE='1/16W',
 TOLERANCE='5%',
 MATERIAL='CHIP',
 VALUE='0',
 PRIM_FILE='./archive_libs/logical/q_res/chips/chips.prt';

PART_NAME
 PR302 'Q_RES_0402LF-0,5%,1/16W,CHIP,CA':;

SECTION_NUMBER 1
 '@S9S_MB_2U_LIB.S9S_MB_2U(SCH_1):PAGE272_I45@PURE_QUANTA.Q_RES(CHIPS)':
 C_PATH='@s9s_mb_2u_lib.s9s_mb_2u(sch_1):page272_i45@pure_quanta.q_res(chips)',
 P_PATH='@s9s_mb_2u_lib.s9s_mb_2u(sch_1):page286_i45@pure_quanta.q_res(chips)',
 PATH='I45',
 DRAWING='@S9S_MB_2U_LIB.S9S_MB_2U(SCH_1):PAGE272',
 PHYS_PAGE='286',
 XY='(1575,650)',
 ROT='0',
 VER='1',
 PACK_TYPE='0402LF',
 LOCATION='PR302',
 CDS_LIB='pure_quanta',
 CDS_PART_NAME='Q_RES_0402LF-0,5%,1/16W,CHIP,CA',
 WATTAGE='1/16W',
 TOLERANCE='5%',
 MATERIAL='CHIP',
 VALUE='0',
 PRIM_FILE='./archive_libs/logical/q_res/chips/chips.prt';

PART_NAME
 PR303 'Q_RES_0402LF-0,5%,1/16W,CHIP,CA':;

SECTION_NUMBER 1
 '@S9S_MB_2U_LIB.S9S_MB_2U(SCH_1):PAGE270_I7@PURE_QUANTA.Q_RES(CHIPS)':
 C_PATH='@s9s_mb_2u_lib.s9s_mb_2u(sch_1):page270_i7@pure_quanta.q_res(chips)',
 P_PATH='@s9s_mb_2u_lib.s9s_mb_2u(sch_1):page284_i7@pure_quanta.q_res(chips)',
 PATH='I7',
 DRAWING='@S9S_MB_2U_LIB.S9S_MB_2U(SCH_1):PAGE270',
 PHYS_PAGE='284',
 XY='(-2250,-2425)',
 ROT='0',
 VER='1',
 PACK_TYPE='0402LF',
 LOCATION='PR303',
 CDS_LIB='pure_quanta',
 CDS_PART_NAME='Q_RES_0402LF-0,5%,1/16W,CHIP,CA',
 WATTAGE='1/16W',
 TOLERANCE='5%',
 MATERIAL='CHIP',
 VALUE='0',
 PRIM_FILE='./archive_libs/logical/q_res/chips/chips.prt';

PART_NAME
 PR304 'Q_RES_0402LF-0,5%,1/16W,EMPTY,A':;

SECTION_NUMBER 1
 '@S9S_MB_2U_LIB.S9S_MB_2U(SCH_1):PAGE270_I9@PURE_QUANTA.Q_RES(CHIPS)':
 C_PATH='@s9s_mb_2u_lib.s9s_mb_2u(sch_1):page270_i9@pure_quanta.q_res(chips)',
 P_PATH='@s9s_mb_2u_lib.s9s_mb_2u(sch_1):page284_i9@pure_quanta.q_res(chips)',
 PATH='I9',
 DRAWING='@S9S_MB_2U_LIB.S9S_MB_2U(SCH_1):PAGE270',
 PHYS_PAGE='284',
 XY='(-2250,-2325)',
 ROT='0',
 VER='1',
 PACK_TYPE='0402LF',
 LOCATION='PR304',
 CDS_LIB='pure_quanta',
 CDS_PART_NAME='Q_RES_0402LF-0,5%,1/16W,EMPTY,A',
 WATTAGE='1/16W',
 TOLERANCE='5%',
 MATERIAL='EMPTY',
 VALUE='0',
 PRIM_FILE='./archive_libs/logical/q_res/chips/chips.prt';

PART_NAME
 PR305 'Q_RES_0402LF-0,5%,1/16W,CHIP,CA':;

SECTION_NUMBER 1
 '@S9S_MB_2U_LIB.S9S_MB_2U(SCH_1):PAGE270_I27@PURE_QUANTA.Q_RES(CHIPS)':
 C_PATH='@s9s_mb_2u_lib.s9s_mb_2u(sch_1):page270_i27@pure_quanta.q_res(chips)',
 P_PATH='@s9s_mb_2u_lib.s9s_mb_2u(sch_1):page284_i27@pure_quanta.q_res(chips)',
 PATH='I27',
 DRAWING='@S9S_MB_2U_LIB.S9S_MB_2U(SCH_1):PAGE270',
 PHYS_PAGE='284',
 XY='(-1800,-2625)',
 ROT='0',
 VER='2',
 PACK_TYPE='0402LF',
 LOCATION='PR305',
 CDS_LIB='pure_quanta',
 CDS_PART_NAME='Q_RES_0402LF-0,5%,1/16W,CHIP,CA',
 WATTAGE='1/16W',
 TOLERANCE='5%',
 MATERIAL='CHIP',
 VALUE='0',
 PRIM_FILE='./archive_libs/logical/q_res/chips/chips.prt';

PART_NAME
 PR306 'Q_RES_0402LF-28K,1%,1/16W,EMPTA':;

SECTION_NUMBER 1
 '@S9S_MB_2U_LIB.S9S_MB_2U(SCH_1):PAGE270_I4@PURE_QUANTA.Q_RES(CHIPS)':
 C_PATH='@s9s_mb_2u_lib.s9s_mb_2u(sch_1):page270_i4@pure_quanta.q_res(chips)',
 P_PATH='@s9s_mb_2u_lib.s9s_mb_2u(sch_1):page284_i4@pure_quanta.q_res(chips)',
 PATH='I4',
 DRAWING='@S9S_MB_2U_LIB.S9S_MB_2U(SCH_1):PAGE270',
 PHYS_PAGE='284',
 XY='(-3100,-2075)',
 ROT='0',
 VER='1',
 PACK_TYPE='0402LF',
 LOCATION='PR306',
 CDS_LIB='pure_quanta',
 CDS_PART_NAME='Q_RES_0402LF-28K,1%,1/16W,EMPTA',
 WATTAGE='1/16W',
 TOLERANCE='1%',
 MATERIAL='EMPTY',
 VALUE='28K',
 PRIM_FILE='./archive_libs/logical/q_res/chips/chips.prt';

PART_NAME
 PR313 'Q_RES_0402LF-1K,1%,1/16W,EMPTYA':;

SECTION_NUMBER 1
 '@S9S_MB_2U_LIB.S9S_MB_2U(SCH_1):PAGE270_I29@PURE_QUANTA.Q_RES(CHIPS)':
 C_PATH='@s9s_mb_2u_lib.s9s_mb_2u(sch_1):page270_i29@pure_quanta.q_res(chips)',
 P_PATH='@s9s_mb_2u_lib.s9s_mb_2u(sch_1):page284_i29@pure_quanta.q_res(chips)',
 PATH='I29',
 DRAWING='@S9S_MB_2U_LIB.S9S_MB_2U(SCH_1):PAGE270',
 PHYS_PAGE='284',
 XY='(-1050,-2625)',
 ROT='0',
 VER='2',
 PACK_TYPE='0402LF',
 LOCATION='PR313',
 CDS_LIB='pure_quanta',
 CDS_PART_NAME='Q_RES_0402LF-1K,1%,1/16W,EMPTYA',
 WATTAGE='1/16W',
 TOLERANCE='1%',
 MATERIAL='EMPTY',
 VALUE='1K',
 PRIM_FILE='./archive_libs/logical/q_res/chips/chips.prt';

PART_NAME
 PR317 'Q_RES_0402LF-0,5%,1/16W,CHIP,CA':;

SECTION_NUMBER 1
 '@S9S_MB_2U_LIB.S9S_MB_2U(SCH_1):PAGE270_I63@PURE_QUANTA.Q_RES(CHIPS)':
 C_PATH='@s9s_mb_2u_lib.s9s_mb_2u(sch_1):page270_i63@pure_quanta.q_res(chips)',
 P_PATH='@s9s_mb_2u_lib.s9s_mb_2u(sch_1):page284_i63@pure_quanta.q_res(chips)',
 PATH='I63',
 DRAWING='@S9S_MB_2U_LIB.S9S_MB_2U(SCH_1):PAGE270',
 PHYS_PAGE='284',
 XY='(-1825,1025)',
 ROT='0',
 VER='1',
 PACK_TYPE='0402LF',
 LOCATION='PR317',
 CDS_LIB='pure_quanta',
 CDS_PART_NAME='Q_RES_0402LF-0,5%,1/16W,CHIP,CA',
 WATTAGE='1/16W',
 TOLERANCE='5%',
 MATERIAL='CHIP',
 VALUE='0',
 PRIM_FILE='./archive_libs/logical/q_res/chips/chips.prt';

PART_NAME
 PR318 'Q_RES_0402LF-5.23K,1%,1/16W,CHA':;

SECTION_NUMBER 1
 '@S9S_MB_2U_LIB.S9S_MB_2U(SCH_1):PAGE270_I6@PURE_QUANTA.Q_RES(CHIPS)':
 C_PATH='@s9s_mb_2u_lib.s9s_mb_2u(sch_1):page270_i6@pure_quanta.q_res(chips)',
 P_PATH='@s9s_mb_2u_lib.s9s_mb_2u(sch_1):page284_i6@pure_quanta.q_res(chips)',
 PATH='I6',
 DRAWING='@S9S_MB_2U_LIB.S9S_MB_2U(SCH_1):PAGE270',
 PHYS_PAGE='284',
 XY='(-2725,-2300)',
 ROT='2',
 VER='2',
 PACK_TYPE='0402LF',
 LOCATION='PR318',
 CDS_LIB='pure_quanta',
 CDS_PART_NAME='Q_RES_0402LF-5.23K,1%,1/16W,CHA',
 WATTAGE='1/16W',
 TOLERANCE='1%',
 MATERIAL='CHIP',
 VALUE='5.23K',
 PRIM_FILE='./archive_libs/logical/q_res/chips/chips.prt';

PART_NAME
 PR323 'Q_RES_0402LF-1,1%,1/16W,CHIP,CA':;

SECTION_NUMBER 1
 '@S9S_MB_2U_LIB.S9S_MB_2U(SCH_1):PAGE270_I126@PURE_QUANTA.Q_RES(CHIPS)':
 C_PATH='@s9s_mb_2u_lib.s9s_mb_2u(sch_1):page270_i126@pure_quanta.q_res(chips)',
 P_PATH='@s9s_mb_2u_lib.s9s_mb_2u(sch_1):page284_i126@pure_quanta.q_res(chips)',
 PATH='I126',
 DRAWING='@S9S_MB_2U_LIB.S9S_MB_2U(SCH_1):PAGE270',
 PHYS_PAGE='284',
 XY='(2175,3025)',
 ROT='0',
 VER='1',
 PACK_TYPE='0402LF',
 LOCATION='PR323',
 CDS_LIB='pure_quanta',
 CDS_PART_NAME='Q_RES_0402LF-1,1%,1/16W,CHIP,CA',
 WATTAGE='1/16W',
 TOLERANCE='1%',
 MATERIAL='CHIP',
 VALUE='1',
 PRIM_FILE='./archive_libs/logical/q_res/chips/chips.prt';

PART_NAME
 PR325 'Q_RES_0402LF-8.87K,1%,1/16W,EMA':;

SECTION_NUMBER 1
 '@S9S_MB_2U_LIB.S9S_MB_2U(SCH_1):PAGE271_I3@PURE_QUANTA.Q_RES(CHIPS)':
 C_PATH='@s9s_mb_2u_lib.s9s_mb_2u(sch_1):page271_i3@pure_quanta.q_res(chips)',
 P_PATH='@s9s_mb_2u_lib.s9s_mb_2u(sch_1):page285_i3@pure_quanta.q_res(chips)',
 PATH='I3',
 DRAWING='@S9S_MB_2U_LIB.S9S_MB_2U(SCH_1):PAGE271',
 PHYS_PAGE='285',
 XY='(-4050,-2200)',
 ROT='2',
 VER='2',
 PACK_TYPE='0402LF',
 LOCATION='PR325',
 CDS_LIB='pure_quanta',
 CDS_PART_NAME='Q_RES_0402LF-8.87K,1%,1/16W,EMA',
 WATTAGE='1/16W',
 TOLERANCE='1%',
 MATERIAL='EMPTY',
 VALUE='8.87K',
 PRIM_FILE='./archive_libs/logical/q_res/chips/chips.prt';

PART_NAME
 PR326 'Q_RES_0402LF-8.87K,1%,1/16W,EMA':;

SECTION_NUMBER 1
 '@S9S_MB_2U_LIB.S9S_MB_2U(SCH_1):PAGE271_I29@PURE_QUANTA.Q_RES(CHIPS)':
 C_PATH='@s9s_mb_2u_lib.s9s_mb_2u(sch_1):page271_i29@pure_quanta.q_res(chips)',
 P_PATH='@s9s_mb_2u_lib.s9s_mb_2u(sch_1):page285_i29@pure_quanta.q_res(chips)',
 PATH='I29',
 DRAWING='@S9S_MB_2U_LIB.S9S_MB_2U(SCH_1):PAGE271',
 PHYS_PAGE='285',
 XY='(-4025,625)',
 ROT='2',
 VER='2',
 PACK_TYPE='0402LF',
 LOCATION='PR326',
 CDS_LIB='pure_quanta',
 CDS_PART_NAME='Q_RES_0402LF-8.87K,1%,1/16W,EMA',
 WATTAGE='1/16W',
 TOLERANCE='1%',
 MATERIAL='EMPTY',
 VALUE='8.87K',
 PRIM_FILE='./archive_libs/logical/q_res/chips/chips.prt';

PART_NAME
 PR327 'Q_RES_0402LF-2.2,1%,1/16W,CHIPA':;

SECTION_NUMBER 1
 '@S9S_MB_2U_LIB.S9S_MB_2U(SCH_1):PAGE271_I13@PURE_QUANTA.Q_RES(CHIPS)':
 C_PATH='@s9s_mb_2u_lib.s9s_mb_2u(sch_1):page271_i13@pure_quanta.q_res(chips)',
 P_PATH='@s9s_mb_2u_lib.s9s_mb_2u(sch_1):page285_i13@pure_quanta.q_res(chips)',
 PATH='I13',
 DRAWING='@S9S_MB_2U_LIB.S9S_MB_2U(SCH_1):PAGE271',
 PHYS_PAGE='285',
 XY='(-3650,-700)',
 ROT='0',
 VER='2',
 PACK_TYPE='0402LF',
 LOCATION='PR327',
 CDS_LIB='pure_quanta',
 CDS_PART_NAME='Q_RES_0402LF-2.2,1%,1/16W,CHIPA',
 WATTAGE='1/16W',
 TOLERANCE='1%',
 MATERIAL='CHIP',
 VALUE='2.2',
 PRIM_FILE='./archive_libs/logical/q_res/chips/chips.prt';

PART_NAME
 PR328 'Q_RES_0402LF-2.2,1%,1/16W,CHIPA':;

SECTION_NUMBER 1
 '@S9S_MB_2U_LIB.S9S_MB_2U(SCH_1):PAGE271_I37@PURE_QUANTA.Q_RES(CHIPS)':
 C_PATH='@s9s_mb_2u_lib.s9s_mb_2u(sch_1):page271_i37@pure_quanta.q_res(chips)',
 P_PATH='@s9s_mb_2u_lib.s9s_mb_2u(sch_1):page285_i37@pure_quanta.q_res(chips)',
 PATH='I37',
 DRAWING='@S9S_MB_2U_LIB.S9S_MB_2U(SCH_1):PAGE271',
 PHYS_PAGE='285',
 XY='(-3625,2125)',
 ROT='0',
 VER='2',
 PACK_TYPE='0402LF',
 LOCATION='PR328',
 CDS_LIB='pure_quanta',
 CDS_PART_NAME='Q_RES_0402LF-2.2,1%,1/16W,CHIPA',
 WATTAGE='1/16W',
 TOLERANCE='1%',
 MATERIAL='CHIP',
 VALUE='2.2',
 PRIM_FILE='./archive_libs/logical/q_res/chips/chips.prt';

PART_NAME
 PR329 'Q_RES_0402LF-0,5%,1/16W,CHIP,CA':;

SECTION_NUMBER 1
 '@S9S_MB_2U_LIB.S9S_MB_2U(SCH_1):PAGE271_I51@PURE_QUANTA.Q_RES(CHIPS)':
 C_PATH='@s9s_mb_2u_lib.s9s_mb_2u(sch_1):page271_i51@pure_quanta.q_res(chips)',
 P_PATH='@s9s_mb_2u_lib.s9s_mb_2u(sch_1):page285_i51@pure_quanta.q_res(chips)',
 PATH='I51',
 DRAWING='@S9S_MB_2U_LIB.S9S_MB_2U(SCH_1):PAGE271',
 PHYS_PAGE='285',
 XY='(375,-2250)',
 ROT='0',
 VER='1',
 PACK_TYPE='0402LF',
 LOCATION='PR329',
 CDS_LIB='pure_quanta',
 CDS_PART_NAME='Q_RES_0402LF-0,5%,1/16W,CHIP,CA',
 WATTAGE='1/16W',
 TOLERANCE='5%',
 MATERIAL='CHIP',
 VALUE='0',
 PRIM_FILE='./archive_libs/logical/q_res/chips/chips.prt';

PART_NAME
 PR330 'Q_RES_0402LF-0,5%,1/16W,CHIP,CA':;

SECTION_NUMBER 1
 '@S9S_MB_2U_LIB.S9S_MB_2U(SCH_1):PAGE271_I73@PURE_QUANTA.Q_RES(CHIPS)':
 C_PATH='@s9s_mb_2u_lib.s9s_mb_2u(sch_1):page271_i73@pure_quanta.q_res(chips)',
 P_PATH='@s9s_mb_2u_lib.s9s_mb_2u(sch_1):page285_i73@pure_quanta.q_res(chips)',
 PATH='I73',
 DRAWING='@S9S_MB_2U_LIB.S9S_MB_2U(SCH_1):PAGE271',
 PHYS_PAGE='285',
 XY='(175,600)',
 ROT='0',
 VER='1',
 PACK_TYPE='0402LF',
 LOCATION='PR330',
 CDS_LIB='pure_quanta',
 CDS_PART_NAME='Q_RES_0402LF-0,5%,1/16W,CHIP,CA',
 WATTAGE='1/16W',
 TOLERANCE='5%',
 MATERIAL='CHIP',
 VALUE='0',
 PRIM_FILE='./archive_libs/logical/q_res/chips/chips.prt';

PART_NAME
 PR338 'Q_RES_0402LF-0,5%,1/16W,CHIP,CA':;

SECTION_NUMBER 1
 '@S9S_MB_2U_LIB.S9S_MB_2U(SCH_1):PAGE248_I10@PURE_QUANTA.Q_RES(CHIPS)':
 C_PATH='@s9s_mb_2u_lib.s9s_mb_2u(sch_1):page248_i10@pure_quanta.q_res(chips)',
 P_PATH='@s9s_mb_2u_lib.s9s_mb_2u(sch_1):page262_i10@pure_quanta.q_res(chips)',
 PATH='I10',
 DRAWING='@S9S_MB_2U_LIB.S9S_MB_2U(SCH_1):PAGE248',
 PHYS_PAGE='262',
 XY='(-1625,-650)',
 ROT='0',
 VER='1',
 PACK_TYPE='0402LF',
 LOCATION='PR338',
 CDS_LIB='pure_quanta',
 CDS_PART_NAME='Q_RES_0402LF-0,5%,1/16W,CHIP,CA',
 WATTAGE='1/16W',
 TOLERANCE='5%',
 MATERIAL='CHIP',
 VALUE='0',
 PRIM_FILE='./archive_libs/logical/q_res/chips/chips.prt';

PART_NAME
 PR345 'Q_RES_0402LF-0,5%,1/16W,CHIP,CA':;

SECTION_NUMBER 1
 '@S9S_MB_2U_LIB.S9S_MB_2U(SCH_1):PAGE252_I68@PURE_QUANTA.Q_RES(CHIPS)':
 C_PATH='@s9s_mb_2u_lib.s9s_mb_2u(sch_1):page252_i68@pure_quanta.q_res(chips)',
 P_PATH='@s9s_mb_2u_lib.s9s_mb_2u(sch_1):page266_i68@pure_quanta.q_res(chips)',
 PATH='I68',
 DRAWING='@S9S_MB_2U_LIB.S9S_MB_2U(SCH_1):PAGE252',
 PHYS_PAGE='266',
 XY='(-4725,3450)',
 ROT='0',
 VER='1',
 PACK_TYPE='0402LF',
 LOCATION='PR345',
 CDS_LIB='pure_quanta',
 CDS_PART_NAME='Q_RES_0402LF-0,5%,1/16W,CHIP,CA',
 WATTAGE='1/16W',
 TOLERANCE='5%',
 MATERIAL='CHIP',
 VALUE='0',
 PRIM_FILE='./archive_libs/logical/q_res/chips/chips.prt';

PART_NAME
 PR353 'Q_RES_0402LF-8.87K,1%,1/16W,EMA':;

SECTION_NUMBER 1
 '@S9S_MB_2U_LIB.S9S_MB_2U(SCH_1):PAGE257_I2@PURE_QUANTA.Q_RES(CHIPS)':
 C_PATH='@s9s_mb_2u_lib.s9s_mb_2u(sch_1):page257_i2@pure_quanta.q_res(chips)',
 P_PATH='@s9s_mb_2u_lib.s9s_mb_2u(sch_1):page271_i2@pure_quanta.q_res(chips)',
 PATH='I2',
 DRAWING='@S9S_MB_2U_LIB.S9S_MB_2U(SCH_1):PAGE257',
 PHYS_PAGE='271',
 XY='(-4750,1900)',
 ROT='2',
 VER='2',
 PACK_TYPE='0402LF',
 LOCATION='PR353',
 CDS_LIB='pure_quanta',
 CDS_PART_NAME='Q_RES_0402LF-8.87K,1%,1/16W,EMA',
 WATTAGE='1/16W',
 TOLERANCE='1%',
 MATERIAL='EMPTY',
 VALUE='8.87K',
 PRIM_FILE='./archive_libs/logical/q_res/chips/chips.prt';

PART_NAME
 PR354 'Q_RES_0402LF-8.87K,1%,1/16W,EMA':;

SECTION_NUMBER 1
 '@S9S_MB_2U_LIB.S9S_MB_2U(SCH_1):PAGE257_I8@PURE_QUANTA.Q_RES(CHIPS)':
 C_PATH='@s9s_mb_2u_lib.s9s_mb_2u(sch_1):page257_i8@pure_quanta.q_res(chips)',
 P_PATH='@s9s_mb_2u_lib.s9s_mb_2u(sch_1):page271_i8@pure_quanta.q_res(chips)',
 PATH='I8',
 DRAWING='@S9S_MB_2U_LIB.S9S_MB_2U(SCH_1):PAGE257',
 PHYS_PAGE='271',
 XY='(-4725,4750)',
 ROT='2',
 VER='2',
 PACK_TYPE='0402LF',
 LOCATION='PR354',
 CDS_LIB='pure_quanta',
 CDS_PART_NAME='Q_RES_0402LF-8.87K,1%,1/16W,EMA',
 WATTAGE='1/16W',
 TOLERANCE='1%',
 MATERIAL='EMPTY',
 VALUE='8.87K',
 PRIM_FILE='./archive_libs/logical/q_res/chips/chips.prt';

PART_NAME
 PR355 'Q_RES_0402LF-2.2,1%,1/16W,CHIPA':;

SECTION_NUMBER 1
 '@S9S_MB_2U_LIB.S9S_MB_2U(SCH_1):PAGE257_I39@PURE_QUANTA.Q_RES(CHIPS)':
 C_PATH='@s9s_mb_2u_lib.s9s_mb_2u(sch_1):page257_i39@pure_quanta.q_res(chips)',
 P_PATH='@s9s_mb_2u_lib.s9s_mb_2u(sch_1):page271_i39@pure_quanta.q_res(chips)',
 PATH='I39',
 DRAWING='@S9S_MB_2U_LIB.S9S_MB_2U(SCH_1):PAGE257',
 PHYS_PAGE='271',
 XY='(-4250,6050)',
 ROT='0',
 VER='2',
 PACK_TYPE='0402LF',
 LOCATION='PR355',
 CDS_LIB='pure_quanta',
 CDS_PART_NAME='Q_RES_0402LF-2.2,1%,1/16W,CHIPA',
 WATTAGE='1/16W',
 TOLERANCE='1%',
 MATERIAL='CHIP',
 VALUE='2.2',
 PRIM_FILE='./archive_libs/logical/q_res/chips/chips.prt';

PART_NAME
 PR356 'Q_RES_0402LF-2.2,1%,1/16W,CHIPA':;

SECTION_NUMBER 1
 '@S9S_MB_2U_LIB.S9S_MB_2U(SCH_1):PAGE257_I19@PURE_QUANTA.Q_RES(CHIPS)':
 C_PATH='@s9s_mb_2u_lib.s9s_mb_2u(sch_1):page257_i19@pure_quanta.q_res(chips)',
 P_PATH='@s9s_mb_2u_lib.s9s_mb_2u(sch_1):page271_i19@pure_quanta.q_res(chips)',
 PATH='I19',
 DRAWING='@S9S_MB_2U_LIB.S9S_MB_2U(SCH_1):PAGE257',
 PHYS_PAGE='271',
 XY='(-4250,3250)',
 ROT='0',
 VER='2',
 PACK_TYPE='0402LF',
 LOCATION='PR356',
 CDS_LIB='pure_quanta',
 CDS_PART_NAME='Q_RES_0402LF-2.2,1%,1/16W,CHIPA',
 WATTAGE='1/16W',
 TOLERANCE='1%',
 MATERIAL='CHIP',
 VALUE='2.2',
 PRIM_FILE='./archive_libs/logical/q_res/chips/chips.prt';

PART_NAME
 PR357 'Q_RES_0402LF-28K,1%,1/16W,EMPTA':;

SECTION_NUMBER 1
 '@S9S_MB_2U_LIB.S9S_MB_2U(SCH_1):PAGE264_I5@PURE_QUANTA.Q_RES(CHIPS)':
 C_PATH='@s9s_mb_2u_lib.s9s_mb_2u(sch_1):page264_i5@pure_quanta.q_res(chips)',
 P_PATH='@s9s_mb_2u_lib.s9s_mb_2u(sch_1):page278_i5@pure_quanta.q_res(chips)',
 PATH='I5',
 DRAWING='@S9S_MB_2U_LIB.S9S_MB_2U(SCH_1):PAGE264',
 PHYS_PAGE='278',
 XY='(-10725,3850)',
 ROT='0',
 VER='1',
 PACK_TYPE='0402LF',
 LOCATION='PR357',
 CDS_LIB='pure_quanta',
 CDS_PART_NAME='Q_RES_0402LF-28K,1%,1/16W,EMPTA',
 WATTAGE='1/16W',
 TOLERANCE='1%',
 MATERIAL='EMPTY',
 VALUE='28K',
 PRIM_FILE='./archive_libs/logical/q_res/chips/chips.prt';

PART_NAME
 PR358 'Q_RES_0402LF-3.57K,1%,1/16W,CHA':;

SECTION_NUMBER 1
 '@S9S_MB_2U_LIB.S9S_MB_2U(SCH_1):PAGE264_I95@PURE_QUANTA.Q_RES(CHIPS)':
 C_PATH='@s9s_mb_2u_lib.s9s_mb_2u(sch_1):page264_i95@pure_quanta.q_res(chips)',
 P_PATH='@s9s_mb_2u_lib.s9s_mb_2u(sch_1):page278_i95@pure_quanta.q_res(chips)',
 PATH='I95',
 DRAWING='@S9S_MB_2U_LIB.S9S_MB_2U(SCH_1):PAGE264',
 PHYS_PAGE='278',
 XY='(-10725,3725)',
 ROT='0',
 VER='1',
 PACK_TYPE='0402LF',
 LOCATION='PR358',
 CDS_LIB='pure_quanta',
 CDS_PART_NAME='Q_RES_0402LF-3.57K,1%,1/16W,CHA',
 WATTAGE='1/16W',
 TOLERANCE='1%',
 MATERIAL='CHIP',
 VALUE='3.57K',
 PRIM_FILE='./archive_libs/logical/q_res/chips/chips.prt';

PART_NAME
 PR369 'Q_RES_0402LF-1K,1%,1/16W,EMPTYA':;

SECTION_NUMBER 1
 '@S9S_MB_2U_LIB.S9S_MB_2U(SCH_1):PAGE264_I7@PURE_QUANTA.Q_RES(CHIPS)':
 C_PATH='@s9s_mb_2u_lib.s9s_mb_2u(sch_1):page264_i7@pure_quanta.q_res(chips)',
 P_PATH='@s9s_mb_2u_lib.s9s_mb_2u(sch_1):page278_i7@pure_quanta.q_res(chips)',
 PATH='I7',
 DRAWING='@S9S_MB_2U_LIB.S9S_MB_2U(SCH_1):PAGE264',
 PHYS_PAGE='278',
 XY='(-9350,3175)',
 ROT='2',
 VER='2',
 PACK_TYPE='0402LF',
 LOCATION='PR369',
 CDS_LIB='pure_quanta',
 CDS_PART_NAME='Q_RES_0402LF-1K,1%,1/16W,EMPTYA',
 WATTAGE='1/16W',
 TOLERANCE='1%',
 MATERIAL='EMPTY',
 VALUE='1K',
 PRIM_FILE='./archive_libs/logical/q_res/chips/chips.prt';

PART_NAME
 PR370 'Q_RES_0402LF-1K,1%,1/16W,CHIP,A':;

SECTION_NUMBER 1
 '@S9S_MB_2U_LIB.S9S_MB_2U(SCH_1):PAGE264_I13@PURE_QUANTA.Q_RES(CHIPS)':
 C_PATH='@s9s_mb_2u_lib.s9s_mb_2u(sch_1):page264_i13@pure_quanta.q_res(chips)',
 P_PATH='@s9s_mb_2u_lib.s9s_mb_2u(sch_1):page278_i13@pure_quanta.q_res(chips)',
 PATH='I13',
 DRAWING='@S9S_MB_2U_LIB.S9S_MB_2U(SCH_1):PAGE264',
 PHYS_PAGE='278',
 XY='(-9600,5250)',
 ROT='0',
 VER='2',
 PACK_TYPE='0402LF',
 LOCATION='PR370',
 CDS_LIB='pure_quanta',
 CDS_PART_NAME='Q_RES_0402LF-1K,1%,1/16W,CHIP,A',
 WATTAGE='1/16W',
 TOLERANCE='1%',
 MATERIAL='CHIP',
 VALUE='1K',
 PRIM_FILE='./archive_libs/logical/q_res/chips/chips.prt';

PART_NAME
 PR371 'Q_RES_0402LF-0,5%,1/16W,CHIP,CA':;

SECTION_NUMBER 1
 '@S9S_MB_2U_LIB.S9S_MB_2U(SCH_1):PAGE264_I36@PURE_QUANTA.Q_RES(CHIPS)':
 C_PATH='@s9s_mb_2u_lib.s9s_mb_2u(sch_1):page264_i36@pure_quanta.q_res(chips)',
 P_PATH='@s9s_mb_2u_lib.s9s_mb_2u(sch_1):page278_i36@pure_quanta.q_res(chips)',
 PATH='I36',
 DRAWING='@S9S_MB_2U_LIB.S9S_MB_2U(SCH_1):PAGE264',
 PHYS_PAGE='278',
 XY='(-9450,6950)',
 ROT='0',
 VER='1',
 PACK_TYPE='0402LF',
 LOCATION='PR371',
 CDS_LIB='pure_quanta',
 CDS_PART_NAME='Q_RES_0402LF-0,5%,1/16W,CHIP,CA',
 WATTAGE='1/16W',
 TOLERANCE='5%',
 MATERIAL='CHIP',
 VALUE='0',
 PRIM_FILE='./archive_libs/logical/q_res/chips/chips.prt';

PART_NAME
 PR372 'Q_RES_0402LF-1K,1%,1/16W,CHIP,A':;

SECTION_NUMBER 1
 '@S9S_MB_2U_LIB.S9S_MB_2U(SCH_1):PAGE264_I14@PURE_QUANTA.Q_RES(CHIPS)':
 C_PATH='@s9s_mb_2u_lib.s9s_mb_2u(sch_1):page264_i14@pure_quanta.q_res(chips)',
 P_PATH='@s9s_mb_2u_lib.s9s_mb_2u(sch_1):page278_i14@pure_quanta.q_res(chips)',
 PATH='I14',
 DRAWING='@S9S_MB_2U_LIB.S9S_MB_2U(SCH_1):PAGE264',
 PHYS_PAGE='278',
 XY='(-9275,5250)',
 ROT='0',
 VER='2',
 PACK_TYPE='0402LF',
 LOCATION='PR372',
 CDS_LIB='pure_quanta',
 CDS_PART_NAME='Q_RES_0402LF-1K,1%,1/16W,CHIP,A',
 WATTAGE='1/16W',
 TOLERANCE='1%',
 MATERIAL='CHIP',
 VALUE='1K',
 PRIM_FILE='./archive_libs/logical/q_res/chips/chips.prt';

PART_NAME
 PR373 'Q_RES_0402LF-1K,1%,1/16W,EMPTYA':;

SECTION_NUMBER 1
 '@S9S_MB_2U_LIB.S9S_MB_2U(SCH_1):PAGE264_I48@PURE_QUANTA.Q_RES(CHIPS)':
 C_PATH='@s9s_mb_2u_lib.s9s_mb_2u(sch_1):page264_i48@pure_quanta.q_res(chips)',
 P_PATH='@s9s_mb_2u_lib.s9s_mb_2u(sch_1):page278_i48@pure_quanta.q_res(chips)',
 PATH='I48',
 DRAWING='@S9S_MB_2U_LIB.S9S_MB_2U(SCH_1):PAGE264',
 PHYS_PAGE='278',
 XY='(-8600,3175)',
 ROT='2',
 VER='2',
 PACK_TYPE='0402LF',
 LOCATION='PR373',
 CDS_LIB='pure_quanta',
 CDS_PART_NAME='Q_RES_0402LF-1K,1%,1/16W,EMPTYA',
 WATTAGE='1/16W',
 TOLERANCE='1%',
 MATERIAL='EMPTY',
 VALUE='1K',
 PRIM_FILE='./archive_libs/logical/q_res/chips/chips.prt';

PART_NAME
 PR375 'Q_RES_0402LF-1,1%,1/16W,CHIP,CA':;

SECTION_NUMBER 1
 '@S9S_MB_2U_LIB.S9S_MB_2U(SCH_1):PAGE264_I80@PURE_QUANTA.Q_RES(CHIPS)':
 C_PATH='@s9s_mb_2u_lib.s9s_mb_2u(sch_1):page264_i80@pure_quanta.q_res(chips)',
 P_PATH='@s9s_mb_2u_lib.s9s_mb_2u(sch_1):page278_i80@pure_quanta.q_res(chips)',
 PATH='I80',
 DRAWING='@S9S_MB_2U_LIB.S9S_MB_2U(SCH_1):PAGE264',
 PHYS_PAGE='278',
 XY='(-5500,8950)',
 ROT='0',
 VER='1',
 PACK_TYPE='0402LF',
 LOCATION='PR375',
 CDS_LIB='pure_quanta',
 CDS_PART_NAME='Q_RES_0402LF-1,1%,1/16W,CHIP,CA',
 WATTAGE='1/16W',
 TOLERANCE='1%',
 MATERIAL='CHIP',
 VALUE='1',
 PRIM_FILE='./archive_libs/logical/q_res/chips/chips.prt';

PART_NAME
 PR380 'Q_RES_0402LF-2.2,1%,1/16W,CHIPA':;

SECTION_NUMBER 1
 '@S9S_MB_2U_LIB.S9S_MB_2U(SCH_1):PAGE265_I12@PURE_QUANTA.Q_RES(CHIPS)':
 C_PATH='@s9s_mb_2u_lib.s9s_mb_2u(sch_1):page265_i12@pure_quanta.q_res(chips)',
 P_PATH='@s9s_mb_2u_lib.s9s_mb_2u(sch_1):page279_i12@pure_quanta.q_res(chips)',
 PATH='I12',
 DRAWING='@S9S_MB_2U_LIB.S9S_MB_2U(SCH_1):PAGE265',
 PHYS_PAGE='279',
 XY='(-8225,2775)',
 ROT='0',
 VER='2',
 PACK_TYPE='0402LF',
 LOCATION='PR380',
 CDS_LIB='pure_quanta',
 CDS_PART_NAME='Q_RES_0402LF-2.2,1%,1/16W,CHIPA',
 WATTAGE='1/16W',
 TOLERANCE='1%',
 MATERIAL='CHIP',
 VALUE='2.2',
 PRIM_FILE='./archive_libs/logical/q_res/chips/chips.prt';

PART_NAME
 PR389 'Q_RES_0402LF-1,1%,1/16W,CHIP,CA':;

SECTION_NUMBER 1
 '@S9S_MB_2U_LIB.S9S_MB_2U(SCH_1):PAGE245_I94@PURE_QUANTA.Q_RES(CHIPS)':
 C_PATH='@s9s_mb_2u_lib.s9s_mb_2u(sch_1):page245_i94@pure_quanta.q_res(chips)',
 P_PATH='@s9s_mb_2u_lib.s9s_mb_2u(sch_1):page259_i94@pure_quanta.q_res(chips)',
 PATH='I94',
 DRAWING='@S9S_MB_2U_LIB.S9S_MB_2U(SCH_1):PAGE245',
 PHYS_PAGE='259',
 XY='(-1800,-400)',
 ROT='0',
 VER='1',
 PACK_TYPE='0402LF',
 LOCATION='PR389',
 CDS_LIB='pure_quanta',
 CDS_PART_NAME='Q_RES_0402LF-1,1%,1/16W,CHIP,CA',
 WATTAGE='1/16W',
 TOLERANCE='1%',
 MATERIAL='CHIP',
 VALUE='1',
 PRIM_FILE='./archive_libs/logical/q_res/chips/chips.prt';

PART_NAME
 PR395 'Q_RES_0402LF-0,5%,1/16W,CHIP,CA':;

SECTION_NUMBER 1
 '@S9S_MB_2U_LIB.S9S_MB_2U(SCH_1):PAGE249_I8@PURE_QUANTA.Q_RES(CHIPS)':
 C_PATH='@s9s_mb_2u_lib.s9s_mb_2u(sch_1):page249_i8@pure_quanta.q_res(chips)',
 P_PATH='@s9s_mb_2u_lib.s9s_mb_2u(sch_1):page263_i8@pure_quanta.q_res(chips)',
 PATH='I8',
 DRAWING='@S9S_MB_2U_LIB.S9S_MB_2U(SCH_1):PAGE249',
 PHYS_PAGE='263',
 XY='(-4750,4375)',
 ROT='0',
 VER='1',
 PACK_TYPE='0402LF',
 LOCATION='PR395',
 CDS_LIB='pure_quanta',
 CDS_PART_NAME='Q_RES_0402LF-0,5%,1/16W,CHIP,CA',
 WATTAGE='1/16W',
 TOLERANCE='5%',
 MATERIAL='CHIP',
 VALUE='0',
 PRIM_FILE='./archive_libs/logical/q_res/chips/chips.prt';

PART_NAME
 PR396 'Q_RES_0402LF-0,5%,1/16W,EMPTY,A':;

SECTION_NUMBER 1
 '@S9S_MB_2U_LIB.S9S_MB_2U(SCH_1):PAGE249_I2@PURE_QUANTA.Q_RES(CHIPS)':
 C_PATH='@s9s_mb_2u_lib.s9s_mb_2u(sch_1):page249_i2@pure_quanta.q_res(chips)',
 P_PATH='@s9s_mb_2u_lib.s9s_mb_2u(sch_1):page263_i2@pure_quanta.q_res(chips)',
 PATH='I2',
 DRAWING='@S9S_MB_2U_LIB.S9S_MB_2U(SCH_1):PAGE249',
 PHYS_PAGE='263',
 XY='(-4750,3950)',
 ROT='0',
 VER='1',
 PACK_TYPE='0402LF',
 LOCATION='PR396',
 CDS_LIB='pure_quanta',
 CDS_PART_NAME='Q_RES_0402LF-0,5%,1/16W,EMPTY,A',
 WATTAGE='1/16W',
 TOLERANCE='5%',
 MATERIAL='EMPTY',
 VALUE='0',
 PRIM_FILE='./archive_libs/logical/q_res/chips/chips.prt';

PART_NAME
 PR400 'Q_RES_0402LF-10K,1%,1/16W,EMPTA':;

SECTION_NUMBER 1
 '@S9S_MB_2U_LIB.S9S_MB_2U(SCH_1):PAGE252_I72@PURE_QUANTA.Q_RES(CHIPS)':
 C_PATH='@s9s_mb_2u_lib.s9s_mb_2u(sch_1):page252_i72@pure_quanta.q_res(chips)',
 P_PATH='@s9s_mb_2u_lib.s9s_mb_2u(sch_1):page266_i72@pure_quanta.q_res(chips)',
 PATH='I72',
 DRAWING='@S9S_MB_2U_LIB.S9S_MB_2U(SCH_1):PAGE252',
 PHYS_PAGE='266',
 XY='(-1175,1150)',
 ROT='0',
 VER='2',
 PACK_TYPE='0402LF',
 LOCATION='PR400',
 CDS_LIB='pure_quanta',
 CDS_PART_NAME='Q_RES_0402LF-10K,1%,1/16W,EMPTA',
 WATTAGE='1/16W',
 TOLERANCE='1%',
 MATERIAL='EMPTY',
 VALUE='10K',
 PRIM_FILE='./archive_libs/logical/q_res/chips/chips.prt';

PART_NAME
 PR402 'Q_RES_0402LF-0,5%,1/16W,CHIP,CA':;

SECTION_NUMBER 1
 '@S9S_MB_2U_LIB.S9S_MB_2U(SCH_1):PAGE253_I26@PURE_QUANTA.Q_RES(CHIPS)':
 C_PATH='@s9s_mb_2u_lib.s9s_mb_2u(sch_1):page253_i26@pure_quanta.q_res(chips)',
 P_PATH='@s9s_mb_2u_lib.s9s_mb_2u(sch_1):page267_i26@pure_quanta.q_res(chips)',
 PATH='I26',
 DRAWING='@S9S_MB_2U_LIB.S9S_MB_2U(SCH_1):PAGE253',
 PHYS_PAGE='267',
 XY='(-4325,2375)',
 ROT='0',
 VER='2',
 PACK_TYPE='0402LF',
 LOCATION='PR402',
 CDS_LIB='pure_quanta',
 CDS_PART_NAME='Q_RES_0402LF-0,5%,1/16W,CHIP,CA',
 WATTAGE='1/16W',
 TOLERANCE='5%',
 MATERIAL='CHIP',
 VALUE='0',
 PRIM_FILE='./archive_libs/logical/q_res/chips/chips.prt';

PART_NAME
 PR403 'Q_RES_0402LF-0,5%,1/16W,EMPTY,A':;

SECTION_NUMBER 1
 '@S9S_MB_2U_LIB.S9S_MB_2U(SCH_1):PAGE253_I42@PURE_QUANTA.Q_RES(CHIPS)':
 C_PATH='@s9s_mb_2u_lib.s9s_mb_2u(sch_1):page253_i42@pure_quanta.q_res(chips)',
 P_PATH='@s9s_mb_2u_lib.s9s_mb_2u(sch_1):page267_i42@pure_quanta.q_res(chips)',
 PATH='I42',
 DRAWING='@S9S_MB_2U_LIB.S9S_MB_2U(SCH_1):PAGE253',
 PHYS_PAGE='267',
 XY='(-3675,2375)',
 ROT='0',
 VER='2',
 PACK_TYPE='0402LF',
 LOCATION='PR403',
 CDS_LIB='pure_quanta',
 CDS_PART_NAME='Q_RES_0402LF-0,5%,1/16W,EMPTY,A',
 WATTAGE='1/16W',
 TOLERANCE='5%',
 MATERIAL='EMPTY',
 VALUE='0',
 PRIM_FILE='./archive_libs/logical/q_res/chips/chips.prt';

PART_NAME
 PR409 'Q_RES_0402LF-0,5%,1/16W,EMPTY,A':;

SECTION_NUMBER 1
 '@S9S_MB_2U_LIB.S9S_MB_2U(SCH_1):PAGE264_I63@PURE_QUANTA.Q_RES(CHIPS)':
 C_PATH='@s9s_mb_2u_lib.s9s_mb_2u(sch_1):page264_i63@pure_quanta.q_res(chips)',
 P_PATH='@s9s_mb_2u_lib.s9s_mb_2u(sch_1):page278_i63@pure_quanta.q_res(chips)',
 PATH='I63',
 DRAWING='@S9S_MB_2U_LIB.S9S_MB_2U(SCH_1):PAGE264',
 PHYS_PAGE='278',
 XY='(-4875,4300)',
 ROT='0',
 VER='1',
 PACK_TYPE='0402LF',
 LOCATION='PR409',
 CDS_LIB='pure_quanta',
 CDS_PART_NAME='Q_RES_0402LF-0,5%,1/16W,EMPTY,A',
 WATTAGE='1/16W',
 TOLERANCE='5%',
 MATERIAL='EMPTY',
 VALUE='0',
 PRIM_FILE='./archive_libs/logical/q_res/chips/chips.prt';

PART_NAME
 PR410 'Q_RES_0402LF-0,5%,1/16W,EMPTY,A':;

SECTION_NUMBER 1
 '@S9S_MB_2U_LIB.S9S_MB_2U(SCH_1):PAGE282_I61@PURE_QUANTA.Q_RES(CHIPS)':
 C_PATH='@s9s_mb_2u_lib.s9s_mb_2u(sch_1):page282_i61@pure_quanta.q_res(chips)',
 P_PATH='@s9s_mb_2u_lib.s9s_mb_2u(sch_1):page296_i61@pure_quanta.q_res(chips)',
 PATH='I61',
 DRAWING='@S9S_MB_2U_LIB.S9S_MB_2U(SCH_1):PAGE282',
 PHYS_PAGE='296',
 XY='(-475,800)',
 ROT='0',
 VER='1',
 PACK_TYPE='0402LF',
 LOCATION='PR410',
 CDS_LIB='pure_quanta',
 CDS_PART_NAME='Q_RES_0402LF-0,5%,1/16W,EMPTY,A',
 WATTAGE='1/16W',
 TOLERANCE='5%',
 MATERIAL='EMPTY',
 VALUE='0',
 PRIM_FILE='./archive_libs/logical/q_res/chips/chips.prt';

PART_NAME
 PR435 'Q_RES_0402LF-10K,1%,1/16W,EMPTA':;

SECTION_NUMBER 1
 '@S9S_MB_2U_LIB.S9S_MB_2U(SCH_1):PAGE260_I71@PURE_QUANTA.Q_RES(CHIPS)':
 C_PATH='@s9s_mb_2u_lib.s9s_mb_2u(sch_1):page260_i71@pure_quanta.q_res(chips)',
 P_PATH='@s9s_mb_2u_lib.s9s_mb_2u(sch_1):page274_i71@pure_quanta.q_res(chips)',
 PATH='I71',
 DRAWING='@S9S_MB_2U_LIB.S9S_MB_2U(SCH_1):PAGE260',
 PHYS_PAGE='274',
 XY='(-5250,2175)',
 ROT='0',
 VER='2',
 PACK_TYPE='0402LF',
 LOCATION='PR435',
 CDS_LIB='pure_quanta',
 CDS_PART_NAME='Q_RES_0402LF-10K,1%,1/16W,EMPTA',
 WATTAGE='1/16W',
 TOLERANCE='1%',
 MATERIAL='EMPTY',
 VALUE='10K',
 PRIM_FILE='./archive_libs/logical/q_res/chips/chips.prt';

PART_NAME
 PR436 'Q_RES_0402LF-10K,1%,1/16W,EMPTA':;

SECTION_NUMBER 1
 '@S9S_MB_2U_LIB.S9S_MB_2U(SCH_1):PAGE260_I106@PURE_QUANTA.Q_RES(CHIPS)':
 C_PATH='@s9s_mb_2u_lib.s9s_mb_2u(sch_1):page260_i106@pure_quanta.q_res(chips)',
 P_PATH='@s9s_mb_2u_lib.s9s_mb_2u(sch_1):page274_i106@pure_quanta.q_res(chips)',
 PATH='I106',
 DRAWING='@S9S_MB_2U_LIB.S9S_MB_2U(SCH_1):PAGE260',
 PHYS_PAGE='274',
 XY='(-3750,2475)',
 ROT='0',
 VER='2',
 PACK_TYPE='0402LF',
 LOCATION='PR436',
 CDS_LIB='pure_quanta',
 CDS_PART_NAME='Q_RES_0402LF-10K,1%,1/16W,EMPTA',
 WATTAGE='1/16W',
 TOLERANCE='1%',
 MATERIAL='EMPTY',
 VALUE='10K',
 PRIM_FILE='./archive_libs/logical/q_res/chips/chips.prt';

PART_NAME
 PR442 'Q_RES_0402LF-0,5%,1/16W,CHIP,CA':;

SECTION_NUMBER 1
 '@S9S_MB_2U_LIB.S9S_MB_2U(SCH_1):PAGE262_I8@PURE_QUANTA.Q_RES(CHIPS)':
 C_PATH='@s9s_mb_2u_lib.s9s_mb_2u(sch_1):page262_i8@pure_quanta.q_res(chips)',
 P_PATH='@s9s_mb_2u_lib.s9s_mb_2u(sch_1):page276_i8@pure_quanta.q_res(chips)',
 PATH='I8',
 DRAWING='@S9S_MB_2U_LIB.S9S_MB_2U(SCH_1):PAGE262',
 PHYS_PAGE='276',
 XY='(-10075,5025)',
 ROT='0',
 VER='2',
 PACK_TYPE='0402LF',
 LOCATION='PR442',
 CDS_LIB='pure_quanta',
 CDS_PART_NAME='Q_RES_0402LF-0,5%,1/16W,CHIP,CA',
 WATTAGE='1/16W',
 TOLERANCE='5%',
 MATERIAL='CHIP',
 VALUE='0',
 PRIM_FILE='./archive_libs/logical/q_res/chips/chips.prt';

PART_NAME
 PR443 'Q_RES_0402LF-0,5%,1/16W,EMPTY,A':;

SECTION_NUMBER 1
 '@S9S_MB_2U_LIB.S9S_MB_2U(SCH_1):PAGE262_I22@PURE_QUANTA.Q_RES(CHIPS)':
 C_PATH='@s9s_mb_2u_lib.s9s_mb_2u(sch_1):page262_i22@pure_quanta.q_res(chips)',
 P_PATH='@s9s_mb_2u_lib.s9s_mb_2u(sch_1):page276_i22@pure_quanta.q_res(chips)',
 PATH='I22',
 DRAWING='@S9S_MB_2U_LIB.S9S_MB_2U(SCH_1):PAGE262',
 PHYS_PAGE='276',
 XY='(-9225,5025)',
 ROT='0',
 VER='2',
 PACK_TYPE='0402LF',
 LOCATION='PR443',
 CDS_LIB='pure_quanta',
 CDS_PART_NAME='Q_RES_0402LF-0,5%,1/16W,EMPTY,A',
 WATTAGE='1/16W',
 TOLERANCE='5%',
 MATERIAL='EMPTY',
 VALUE='0',
 PRIM_FILE='./archive_libs/logical/q_res/chips/chips.prt';

PART_NAME
 PR444 'Q_RES_0402LF-0,5%,1/16W,CHIP,CA':;

SECTION_NUMBER 1
 '@S9S_MB_2U_LIB.S9S_MB_2U(SCH_1):PAGE257_I9@PURE_QUANTA.Q_RES(CHIPS)':
 C_PATH='@s9s_mb_2u_lib.s9s_mb_2u(sch_1):page257_i9@pure_quanta.q_res(chips)',
 P_PATH='@s9s_mb_2u_lib.s9s_mb_2u(sch_1):page271_i9@pure_quanta.q_res(chips)',
 PATH='I9',
 DRAWING='@S9S_MB_2U_LIB.S9S_MB_2U(SCH_1):PAGE257',
 PHYS_PAGE='271',
 XY='(-4825,6700)',
 ROT='0',
 VER='2',
 PACK_TYPE='0402LF',
 LOCATION='PR444',
 CDS_LIB='pure_quanta',
 CDS_PART_NAME='Q_RES_0402LF-0,5%,1/16W,CHIP,CA',
 WATTAGE='1/16W',
 TOLERANCE='5%',
 MATERIAL='CHIP',
 VALUE='0',
 PRIM_FILE='./archive_libs/logical/q_res/chips/chips.prt';

PART_NAME
 PR447 'Q_RES_0402LF-0,5%,1/16W,CHIP,CA':;

SECTION_NUMBER 1
 '@S9S_MB_2U_LIB.S9S_MB_2U(SCH_1):PAGE257_I4@PURE_QUANTA.Q_RES(CHIPS)':
 C_PATH='@s9s_mb_2u_lib.s9s_mb_2u(sch_1):page257_i4@pure_quanta.q_res(chips)',
 P_PATH='@s9s_mb_2u_lib.s9s_mb_2u(sch_1):page271_i4@pure_quanta.q_res(chips)',
 PATH='I4',
 DRAWING='@S9S_MB_2U_LIB.S9S_MB_2U(SCH_1):PAGE257',
 PHYS_PAGE='271',
 XY='(-4825,3900)',
 ROT='0',
 VER='2',
 PACK_TYPE='0402LF',
 LOCATION='PR447',
 CDS_LIB='pure_quanta',
 CDS_PART_NAME='Q_RES_0402LF-0,5%,1/16W,CHIP,CA',
 WATTAGE='1/16W',
 TOLERANCE='5%',
 MATERIAL='CHIP',
 VALUE='0',
 PRIM_FILE='./archive_libs/logical/q_res/chips/chips.prt';

PART_NAME
 PR451 'Q_RES_0402LF-10K,1%,1/16W,EMPTA':;

SECTION_NUMBER 1
 '@S9S_MB_2U_LIB.S9S_MB_2U(SCH_1):PAGE252_I121@PURE_QUANTA.Q_RES(CHIPS)':
 C_PATH='@s9s_mb_2u_lib.s9s_mb_2u(sch_1):page252_i121@pure_quanta.q_res(chips)',
 P_PATH='@s9s_mb_2u_lib.s9s_mb_2u(sch_1):page266_i121@pure_quanta.q_res(chips)',
 PATH='I121',
 DRAWING='@S9S_MB_2U_LIB.S9S_MB_2U(SCH_1):PAGE252',
 PHYS_PAGE='266',
 XY='(550,1425)',
 ROT='0',
 VER='2',
 PACK_TYPE='0402LF',
 LOCATION='PR451',
 CDS_LIB='pure_quanta',
 CDS_PART_NAME='Q_RES_0402LF-10K,1%,1/16W,EMPTA',
 WATTAGE='1/16W',
 TOLERANCE='1%',
 MATERIAL='EMPTY',
 VALUE='10K',
 PRIM_FILE='./archive_libs/logical/q_res/chips/chips.prt';

PART_NAME
 PR453 'Q_RES_0402LF-10K,1%,1/16W,EMPTA':;

SECTION_NUMBER 1
 '@S9S_MB_2U_LIB.S9S_MB_2U(SCH_1):PAGE270_I94@PURE_QUANTA.Q_RES(CHIPS)':
 C_PATH='@s9s_mb_2u_lib.s9s_mb_2u(sch_1):page270_i94@pure_quanta.q_res(chips)',
 P_PATH='@s9s_mb_2u_lib.s9s_mb_2u(sch_1):page284_i94@pure_quanta.q_res(chips)',
 PATH='I94',
 DRAWING='@S9S_MB_2U_LIB.S9S_MB_2U(SCH_1):PAGE270',
 PHYS_PAGE='284',
 XY='(3575,-2100)',
 ROT='0',
 VER='2',
 PACK_TYPE='0402LF',
 LOCATION='PR453',
 CDS_LIB='pure_quanta',
 CDS_PART_NAME='Q_RES_0402LF-10K,1%,1/16W,EMPTA',
 WATTAGE='1/16W',
 TOLERANCE='1%',
 MATERIAL='EMPTY',
 VALUE='10K',
 PRIM_FILE='./archive_libs/logical/q_res/chips/chips.prt';

PART_NAME
 PR501 'Q_RES_0402LF-8.25K,0.1%,1/16W,A':;

SECTION_NUMBER 1
 '@S9S_MB_2U_LIB.S9S_MB_2U(SCH_1):PAGE268_I36@PURE_QUANTA.Q_RES(CHIPS)':
 C_PATH='@s9s_mb_2u_lib.s9s_mb_2u(sch_1):page268_i36@pure_quanta.q_res(chips)',
 P_PATH='@s9s_mb_2u_lib.s9s_mb_2u(sch_1):page282_i36@pure_quanta.q_res(chips)',
 PATH='I36',
 DRAWING='@S9S_MB_2U_LIB.S9S_MB_2U(SCH_1):PAGE268',
 PHYS_PAGE='282',
 XY='(-3425,9000)',
 ROT='0',
 VER='1',
 PACK_TYPE='0402LF',
 LOCATION='PR501',
 CDS_LIB='pure_quanta',
 CDS_PART_NAME='Q_RES_0402LF-8.25K,0.1%,1/16W,A',
 WATTAGE='1/16W',
 TOLERANCE='0.1%',
 MATERIAL='CHIP',
 VALUE='8.25K',
 PRIM_FILE='./archive_libs/logical/q_res/chips/chips.prt';

PART_NAME
 PR502 'Q_RES_0402LF-8.25K,0.1%,1/16W,A':;

SECTION_NUMBER 1
 '@S9S_MB_2U_LIB.S9S_MB_2U(SCH_1):PAGE286_I34@PURE_QUANTA.Q_RES(CHIPS)':
 C_PATH='@s9s_mb_2u_lib.s9s_mb_2u(sch_1):page286_i34@pure_quanta.q_res(chips)',
 P_PATH='@s9s_mb_2u_lib.s9s_mb_2u(sch_1):page300_i34@pure_quanta.q_res(chips)',
 PATH='I34',
 DRAWING='@S9S_MB_2U_LIB.S9S_MB_2U(SCH_1):PAGE286',
 PHYS_PAGE='300',
 XY='(8075,6375)',
 ROT='0',
 VER='1',
 PACK_TYPE='0402LF',
 LOCATION='PR502',
 CDS_LIB='pure_quanta',
 CDS_PART_NAME='Q_RES_0402LF-8.25K,0.1%,1/16W,A',
 WATTAGE='1/16W',
 TOLERANCE='0.1%',
 MATERIAL='CHIP',
 VALUE='8.25K',
 PRIM_FILE='./archive_libs/logical/q_res/chips/chips.prt';

PART_NAME
 PR519 'Q_RES_0402LF-100,1%,1/16W,CHIPA':;

SECTION_NUMBER 1
 '@S9S_MB_2U_LIB.S9S_MB_2U(SCH_1):PAGE260_I42@PURE_QUANTA.Q_RES(CHIPS)':
 C_PATH='@s9s_mb_2u_lib.s9s_mb_2u(sch_1):page260_i42@pure_quanta.q_res(chips)',
 P_PATH='@s9s_mb_2u_lib.s9s_mb_2u(sch_1):page274_i42@pure_quanta.q_res(chips)',
 PATH='I42',
 DRAWING='@S9S_MB_2U_LIB.S9S_MB_2U(SCH_1):PAGE260',
 PHYS_PAGE='274',
 XY='(-9875,5050)',
 ROT='0',
 VER='1',
 PACK_TYPE='0402LF',
 LOCATION='PR519',
 CDS_LIB='pure_quanta',
 CDS_PART_NAME='Q_RES_0402LF-100,1%,1/16W,CHIPA',
 WATTAGE='1/16W',
 TOLERANCE='1%',
 MATERIAL='CHIP',
 VALUE='100',
 PRIM_FILE='./archive_libs/logical/q_res/chips/chips.prt';

PART_NAME
 PR520 'Q_RES_0402LF-100,1%,1/16W,CHIPA':;

SECTION_NUMBER 1
 '@S9S_MB_2U_LIB.S9S_MB_2U(SCH_1):PAGE260_I38@PURE_QUANTA.Q_RES(CHIPS)':
 C_PATH='@s9s_mb_2u_lib.s9s_mb_2u(sch_1):page260_i38@pure_quanta.q_res(chips)',
 P_PATH='@s9s_mb_2u_lib.s9s_mb_2u(sch_1):page274_i38@pure_quanta.q_res(chips)',
 PATH='I38',
 DRAWING='@S9S_MB_2U_LIB.S9S_MB_2U(SCH_1):PAGE260',
 PHYS_PAGE='274',
 XY='(-9875,3950)',
 ROT='0',
 VER='1',
 PACK_TYPE='0402LF',
 LOCATION='PR520',
 CDS_LIB='pure_quanta',
 CDS_PART_NAME='Q_RES_0402LF-100,1%,1/16W,CHIPA',
 WATTAGE='1/16W',
 TOLERANCE='1%',
 MATERIAL='CHIP',
 VALUE='100',
 PRIM_FILE='./archive_libs/logical/q_res/chips/chips.prt';

PART_NAME
 PR521 'Q_RES_0402LF-100,1%,1/16W,CHIPA':;

SECTION_NUMBER 1
 '@S9S_MB_2U_LIB.S9S_MB_2U(SCH_1):PAGE260_I44@PURE_QUANTA.Q_RES(CHIPS)':
 C_PATH='@s9s_mb_2u_lib.s9s_mb_2u(sch_1):page260_i44@pure_quanta.q_res(chips)',
 P_PATH='@s9s_mb_2u_lib.s9s_mb_2u(sch_1):page274_i44@pure_quanta.q_res(chips)',
 PATH='I44',
 DRAWING='@S9S_MB_2U_LIB.S9S_MB_2U(SCH_1):PAGE260',
 PHYS_PAGE='274',
 XY='(-9825,5725)',
 ROT='0',
 VER='1',
 PACK_TYPE='0402LF',
 LOCATION='PR521',
 CDS_LIB='pure_quanta',
 CDS_PART_NAME='Q_RES_0402LF-100,1%,1/16W,CHIPA',
 WATTAGE='1/16W',
 TOLERANCE='1%',
 MATERIAL='CHIP',
 VALUE='100',
 PRIM_FILE='./archive_libs/logical/q_res/chips/chips.prt';

PART_NAME
 PR522 'Q_RES_0402LF-100,1%,1/16W,CHIPA':;

SECTION_NUMBER 1
 '@S9S_MB_2U_LIB.S9S_MB_2U(SCH_1):PAGE260_I40@PURE_QUANTA.Q_RES(CHIPS)':
 C_PATH='@s9s_mb_2u_lib.s9s_mb_2u(sch_1):page260_i40@pure_quanta.q_res(chips)',
 P_PATH='@s9s_mb_2u_lib.s9s_mb_2u(sch_1):page274_i40@pure_quanta.q_res(chips)',
 PATH='I40',
 DRAWING='@S9S_MB_2U_LIB.S9S_MB_2U(SCH_1):PAGE260',
 PHYS_PAGE='274',
 XY='(-9825,4625)',
 ROT='0',
 VER='1',
 PACK_TYPE='0402LF',
 LOCATION='PR522',
 CDS_LIB='pure_quanta',
 CDS_PART_NAME='Q_RES_0402LF-100,1%,1/16W,CHIPA',
 WATTAGE='1/16W',
 TOLERANCE='1%',
 MATERIAL='CHIP',
 VALUE='100',
 PRIM_FILE='./archive_libs/logical/q_res/chips/chips.prt';

PART_NAME
 PR527 'Q_RES_0402LF-100,1%,1/16W,CHIPA':;

SECTION_NUMBER 1
 '@S9S_MB_2U_LIB.S9S_MB_2U(SCH_1):PAGE252_I26@PURE_QUANTA.Q_RES(CHIPS)':
 C_PATH='@s9s_mb_2u_lib.s9s_mb_2u(sch_1):page252_i26@pure_quanta.q_res(chips)',
 P_PATH='@s9s_mb_2u_lib.s9s_mb_2u(sch_1):page266_i26@pure_quanta.q_res(chips)',
 PATH='I26',
 DRAWING='@S9S_MB_2U_LIB.S9S_MB_2U(SCH_1):PAGE252',
 PHYS_PAGE='266',
 XY='(-5800,4025)',
 ROT='0',
 VER='1',
 PACK_TYPE='0402LF',
 LOCATION='PR527',
 CDS_LIB='pure_quanta',
 CDS_PART_NAME='Q_RES_0402LF-100,1%,1/16W,CHIPA',
 WATTAGE='1/16W',
 TOLERANCE='1%',
 MATERIAL='CHIP',
 VALUE='100',
 PRIM_FILE='./archive_libs/logical/q_res/chips/chips.prt';

PART_NAME
 PR531 'Q_RES_0402LF-100,1%,1/16W,CHIPA':;

SECTION_NUMBER 1
 '@S9S_MB_2U_LIB.S9S_MB_2U(SCH_1):PAGE252_I38@PURE_QUANTA.Q_RES(CHIPS)':
 C_PATH='@s9s_mb_2u_lib.s9s_mb_2u(sch_1):page252_i38@pure_quanta.q_res(chips)',
 P_PATH='@s9s_mb_2u_lib.s9s_mb_2u(sch_1):page266_i38@pure_quanta.q_res(chips)',
 PATH='I38',
 DRAWING='@S9S_MB_2U_LIB.S9S_MB_2U(SCH_1):PAGE252',
 PHYS_PAGE='266',
 XY='(-5750,4700)',
 ROT='0',
 VER='1',
 PACK_TYPE='0402LF',
 LOCATION='PR531',
 CDS_LIB='pure_quanta',
 CDS_PART_NAME='Q_RES_0402LF-100,1%,1/16W,CHIPA',
 WATTAGE='1/16W',
 TOLERANCE='1%',
 MATERIAL='CHIP',
 VALUE='100',
 PRIM_FILE='./archive_libs/logical/q_res/chips/chips.prt';

PART_NAME
 PR558 'Q_RES_0402LF-100,1%,1/16W,CHIPA':;

SECTION_NUMBER 1
 '@S9S_MB_2U_LIB.S9S_MB_2U(SCH_1):PAGE282_I15@PURE_QUANTA.Q_RES(CHIPS)':
 C_PATH='@s9s_mb_2u_lib.s9s_mb_2u(sch_1):page282_i15@pure_quanta.q_res(chips)',
 P_PATH='@s9s_mb_2u_lib.s9s_mb_2u(sch_1):page296_i15@pure_quanta.q_res(chips)',
 PATH='I15',
 DRAWING='@S9S_MB_2U_LIB.S9S_MB_2U(SCH_1):PAGE282',
 PHYS_PAGE='296',
 XY='(-5975,2925)',
 ROT='0',
 VER='1',
 PACK_TYPE='0402LF',
 LOCATION='PR558',
 CDS_LIB='pure_quanta',
 CDS_PART_NAME='Q_RES_0402LF-100,1%,1/16W,CHIPA',
 WATTAGE='1/16W',
 TOLERANCE='1%',
 MATERIAL='CHIP',
 VALUE='100',
 PRIM_FILE='./archive_libs/logical/q_res/chips/chips.prt';

PART_NAME
 PR559 'Q_RES_0402LF-100,1%,1/16W,CHIPA':;

SECTION_NUMBER 1
 '@S9S_MB_2U_LIB.S9S_MB_2U(SCH_1):PAGE282_I36@PURE_QUANTA.Q_RES(CHIPS)':
 C_PATH='@s9s_mb_2u_lib.s9s_mb_2u(sch_1):page282_i36@pure_quanta.q_res(chips)',
 P_PATH='@s9s_mb_2u_lib.s9s_mb_2u(sch_1):page296_i36@pure_quanta.q_res(chips)',
 PATH='I36',
 DRAWING='@S9S_MB_2U_LIB.S9S_MB_2U(SCH_1):PAGE282',
 PHYS_PAGE='296',
 XY='(-5950,3600)',
 ROT='0',
 VER='1',
 PACK_TYPE='0402LF',
 LOCATION='PR559',
 CDS_LIB='pure_quanta',
 CDS_PART_NAME='Q_RES_0402LF-100,1%,1/16W,CHIPA',
 WATTAGE='1/16W',
 TOLERANCE='1%',
 MATERIAL='CHIP',
 VALUE='100',
 PRIM_FILE='./archive_libs/logical/q_res/chips/chips.prt';

PART_NAME
 PR560 'Q_RES_0402LF-100,1%,1/16W,CHIPA':;

SECTION_NUMBER 1
 '@S9S_MB_2U_LIB.S9S_MB_2U(SCH_1):PAGE270_I12@PURE_QUANTA.Q_RES(CHIPS)':
 C_PATH='@s9s_mb_2u_lib.s9s_mb_2u(sch_1):page270_i12@pure_quanta.q_res(chips)',
 P_PATH='@s9s_mb_2u_lib.s9s_mb_2u(sch_1):page284_i12@pure_quanta.q_res(chips)',
 PATH='I12',
 DRAWING='@S9S_MB_2U_LIB.S9S_MB_2U(SCH_1):PAGE270',
 PHYS_PAGE='284',
 XY='(-3100,-600)',
 ROT='0',
 VER='1',
 PACK_TYPE='0402LF',
 LOCATION='PR560',
 CDS_LIB='pure_quanta',
 CDS_PART_NAME='Q_RES_0402LF-100,1%,1/16W,CHIPA',
 WATTAGE='1/16W',
 TOLERANCE='1%',
 MATERIAL='CHIP',
 VALUE='100',
 PRIM_FILE='./archive_libs/logical/q_res/chips/chips.prt';

PART_NAME
 PR561 'Q_RES_0402LF-100,1%,1/16W,CHIPA':;

SECTION_NUMBER 1
 '@S9S_MB_2U_LIB.S9S_MB_2U(SCH_1):PAGE270_I23@PURE_QUANTA.Q_RES(CHIPS)':
 C_PATH='@s9s_mb_2u_lib.s9s_mb_2u(sch_1):page270_i23@pure_quanta.q_res(chips)',
 P_PATH='@s9s_mb_2u_lib.s9s_mb_2u(sch_1):page284_i23@pure_quanta.q_res(chips)',
 PATH='I23',
 DRAWING='@S9S_MB_2U_LIB.S9S_MB_2U(SCH_1):PAGE270',
 PHYS_PAGE='284',
 XY='(-2800,75)',
 ROT='0',
 VER='1',
 PACK_TYPE='0402LF',
 LOCATION='PR561',
 CDS_LIB='pure_quanta',
 CDS_PART_NAME='Q_RES_0402LF-100,1%,1/16W,CHIPA',
 WATTAGE='1/16W',
 TOLERANCE='1%',
 MATERIAL='CHIP',
 VALUE='100',
 PRIM_FILE='./archive_libs/logical/q_res/chips/chips.prt';

PART_NAME
 PR566 'Q_RES_0402LF-100,1%,1/16W,CHIPA':;

SECTION_NUMBER 1
 '@S9S_MB_2U_LIB.S9S_MB_2U(SCH_1):PAGE278_I46@PURE_QUANTA.Q_RES(CHIPS)':
 C_PATH='@s9s_mb_2u_lib.s9s_mb_2u(sch_1):page278_i46@pure_quanta.q_res(chips)',
 P_PATH='@s9s_mb_2u_lib.s9s_mb_2u(sch_1):page292_i46@pure_quanta.q_res(chips)',
 PATH='I46',
 DRAWING='@S9S_MB_2U_LIB.S9S_MB_2U(SCH_1):PAGE278',
 PHYS_PAGE='292',
 XY='(550,6625)',
 ROT='0',
 VER='1',
 PACK_TYPE='0402LF',
 LOCATION='PR566',
 CDS_LIB='pure_quanta',
 CDS_PART_NAME='Q_RES_0402LF-100,1%,1/16W,CHIPA',
 WATTAGE='1/16W',
 TOLERANCE='1%',
 MATERIAL='CHIP',
 VALUE='100',
 PRIM_FILE='./archive_libs/logical/q_res/chips/chips.prt';

PART_NAME
 PR567 'Q_RES_0402LF-100,1%,1/16W,CHIPA':;

SECTION_NUMBER 1
 '@S9S_MB_2U_LIB.S9S_MB_2U(SCH_1):PAGE278_I41@PURE_QUANTA.Q_RES(CHIPS)':
 C_PATH='@s9s_mb_2u_lib.s9s_mb_2u(sch_1):page278_i41@pure_quanta.q_res(chips)',
 P_PATH='@s9s_mb_2u_lib.s9s_mb_2u(sch_1):page292_i41@pure_quanta.q_res(chips)',
 PATH='I41',
 DRAWING='@S9S_MB_2U_LIB.S9S_MB_2U(SCH_1):PAGE278',
 PHYS_PAGE='292',
 XY='(550,5525)',
 ROT='0',
 VER='1',
 PACK_TYPE='0402LF',
 LOCATION='PR567',
 CDS_LIB='pure_quanta',
 CDS_PART_NAME='Q_RES_0402LF-100,1%,1/16W,CHIPA',
 WATTAGE='1/16W',
 TOLERANCE='1%',
 MATERIAL='CHIP',
 VALUE='100',
 PRIM_FILE='./archive_libs/logical/q_res/chips/chips.prt';

PART_NAME
 PR568 'Q_RES_0402LF-100,1%,1/16W,CHIPA':;

SECTION_NUMBER 1
 '@S9S_MB_2U_LIB.S9S_MB_2U(SCH_1):PAGE278_I55@PURE_QUANTA.Q_RES(CHIPS)':
 C_PATH='@s9s_mb_2u_lib.s9s_mb_2u(sch_1):page278_i55@pure_quanta.q_res(chips)',
 P_PATH='@s9s_mb_2u_lib.s9s_mb_2u(sch_1):page292_i55@pure_quanta.q_res(chips)',
 PATH='I55',
 DRAWING='@S9S_MB_2U_LIB.S9S_MB_2U(SCH_1):PAGE278',
 PHYS_PAGE='292',
 XY='(550,7300)',
 ROT='0',
 VER='1',
 PACK_TYPE='0402LF',
 LOCATION='PR568',
 CDS_LIB='pure_quanta',
 CDS_PART_NAME='Q_RES_0402LF-100,1%,1/16W,CHIPA',
 WATTAGE='1/16W',
 TOLERANCE='1%',
 MATERIAL='CHIP',
 VALUE='100',
 PRIM_FILE='./archive_libs/logical/q_res/chips/chips.prt';

PART_NAME
 PR569 'Q_RES_0402LF-100,1%,1/16W,CHIPA':;

SECTION_NUMBER 1
 '@S9S_MB_2U_LIB.S9S_MB_2U(SCH_1):PAGE278_I45@PURE_QUANTA.Q_RES(CHIPS)':
 C_PATH='@s9s_mb_2u_lib.s9s_mb_2u(sch_1):page278_i45@pure_quanta.q_res(chips)',
 P_PATH='@s9s_mb_2u_lib.s9s_mb_2u(sch_1):page292_i45@pure_quanta.q_res(chips)',
 PATH='I45',
 DRAWING='@S9S_MB_2U_LIB.S9S_MB_2U(SCH_1):PAGE278',
 PHYS_PAGE='292',
 XY='(550,6200)',
 ROT='0',
 VER='1',
 PACK_TYPE='0402LF',
 LOCATION='PR569',
 CDS_LIB='pure_quanta',
 CDS_PART_NAME='Q_RES_0402LF-100,1%,1/16W,CHIPA',
 WATTAGE='1/16W',
 TOLERANCE='1%',
 MATERIAL='CHIP',
 VALUE='100',
 PRIM_FILE='./archive_libs/logical/q_res/chips/chips.prt';

PART_NAME
 PR574 'Q_RES_0402LF-100,1%,1/16W,CHIPA':;

SECTION_NUMBER 1
 '@S9S_MB_2U_LIB.S9S_MB_2U(SCH_1):PAGE270_I45@PURE_QUANTA.Q_RES(CHIPS)':
 C_PATH='@s9s_mb_2u_lib.s9s_mb_2u(sch_1):page270_i45@pure_quanta.q_res(chips)',
 P_PATH='@s9s_mb_2u_lib.s9s_mb_2u(sch_1):page284_i45@pure_quanta.q_res(chips)',
 PATH='I45',
 DRAWING='@S9S_MB_2U_LIB.S9S_MB_2U(SCH_1):PAGE270',
 PHYS_PAGE='284',
 XY='(-2850,500)',
 ROT='0',
 VER='1',
 PACK_TYPE='0402LF',
 LOCATION='PR574',
 CDS_LIB='pure_quanta',
 CDS_PART_NAME='Q_RES_0402LF-100,1%,1/16W,CHIPA',
 WATTAGE='1/16W',
 TOLERANCE='1%',
 MATERIAL='CHIP',
 VALUE='100',
 PRIM_FILE='./archive_libs/logical/q_res/chips/chips.prt';

PART_NAME
 PR578 'Q_RES_0402LF-100,1%,1/16W,CHIPA':;

SECTION_NUMBER 1
 '@S9S_MB_2U_LIB.S9S_MB_2U(SCH_1):PAGE270_I49@PURE_QUANTA.Q_RES(CHIPS)':
 C_PATH='@s9s_mb_2u_lib.s9s_mb_2u(sch_1):page270_i49@pure_quanta.q_res(chips)',
 P_PATH='@s9s_mb_2u_lib.s9s_mb_2u(sch_1):page284_i49@pure_quanta.q_res(chips)',
 PATH='I49',
 DRAWING='@S9S_MB_2U_LIB.S9S_MB_2U(SCH_1):PAGE270',
 PHYS_PAGE='284',
 XY='(-2800,1175)',
 ROT='0',
 VER='1',
 PACK_TYPE='0402LF',
 LOCATION='PR578',
 CDS_LIB='pure_quanta',
 CDS_PART_NAME='Q_RES_0402LF-100,1%,1/16W,CHIPA',
 WATTAGE='1/16W',
 TOLERANCE='1%',
 MATERIAL='CHIP',
 VALUE='100',
 PRIM_FILE='./archive_libs/logical/q_res/chips/chips.prt';

PART_NAME
 PR586 'Q_RES_0402LF-100,1%,1/16W,CHIPA':;

SECTION_NUMBER 1
 '@S9S_MB_2U_LIB.S9S_MB_2U(SCH_1):PAGE252_I15@PURE_QUANTA.Q_RES(CHIPS)':
 C_PATH='@s9s_mb_2u_lib.s9s_mb_2u(sch_1):page252_i15@pure_quanta.q_res(chips)',
 P_PATH='@s9s_mb_2u_lib.s9s_mb_2u(sch_1):page266_i15@pure_quanta.q_res(chips)',
 PATH='I15',
 DRAWING='@S9S_MB_2U_LIB.S9S_MB_2U(SCH_1):PAGE252',
 PHYS_PAGE='266',
 XY='(-6025,2925)',
 ROT='0',
 VER='1',
 PACK_TYPE='0402LF',
 LOCATION='PR586',
 CDS_LIB='pure_quanta',
 CDS_PART_NAME='Q_RES_0402LF-100,1%,1/16W,CHIPA',
 WATTAGE='1/16W',
 TOLERANCE='1%',
 MATERIAL='CHIP',
 VALUE='100',
 PRIM_FILE='./archive_libs/logical/q_res/chips/chips.prt';

PART_NAME
 PR587 'Q_RES_0402LF-100,1%,1/16W,CHIPA':;

SECTION_NUMBER 1
 '@S9S_MB_2U_LIB.S9S_MB_2U(SCH_1):PAGE252_I25@PURE_QUANTA.Q_RES(CHIPS)':
 C_PATH='@s9s_mb_2u_lib.s9s_mb_2u(sch_1):page252_i25@pure_quanta.q_res(chips)',
 P_PATH='@s9s_mb_2u_lib.s9s_mb_2u(sch_1):page266_i25@pure_quanta.q_res(chips)',
 PATH='I25',
 DRAWING='@S9S_MB_2U_LIB.S9S_MB_2U(SCH_1):PAGE252',
 PHYS_PAGE='266',
 XY='(-5750,3600)',
 ROT='0',
 VER='1',
 PACK_TYPE='0402LF',
 LOCATION='PR587',
 CDS_LIB='pure_quanta',
 CDS_PART_NAME='Q_RES_0402LF-100,1%,1/16W,CHIPA',
 WATTAGE='1/16W',
 TOLERANCE='1%',
 MATERIAL='CHIP',
 VALUE='100',
 PRIM_FILE='./archive_libs/logical/q_res/chips/chips.prt';

PART_NAME
 PR591 'Q_RES_0402LF-100,1%,1/16W,CHIPA':;

SECTION_NUMBER 1
 '@S9S_MB_2U_LIB.S9S_MB_2U(SCH_1):PAGE264_I30@PURE_QUANTA.Q_RES(CHIPS)':
 C_PATH='@s9s_mb_2u_lib.s9s_mb_2u(sch_1):page264_i30@pure_quanta.q_res(chips)',
 P_PATH='@s9s_mb_2u_lib.s9s_mb_2u(sch_1):page278_i30@pure_quanta.q_res(chips)',
 PATH='I30',
 DRAWING='@S9S_MB_2U_LIB.S9S_MB_2U(SCH_1):PAGE264',
 PHYS_PAGE='278',
 XY='(-10525,6425)',
 ROT='0',
 VER='1',
 PACK_TYPE='0402LF',
 LOCATION='PR591',
 CDS_LIB='pure_quanta',
 CDS_PART_NAME='Q_RES_0402LF-100,1%,1/16W,CHIPA',
 WATTAGE='1/16W',
 TOLERANCE='1%',
 MATERIAL='CHIP',
 VALUE='100',
 PRIM_FILE='./archive_libs/logical/q_res/chips/chips.prt';

PART_NAME
 PR592 'Q_RES_0402LF-100,1%,1/16W,CHIPA':;

SECTION_NUMBER 1
 '@S9S_MB_2U_LIB.S9S_MB_2U(SCH_1):PAGE264_I31@PURE_QUANTA.Q_RES(CHIPS)':
 C_PATH='@s9s_mb_2u_lib.s9s_mb_2u(sch_1):page264_i31@pure_quanta.q_res(chips)',
 P_PATH='@s9s_mb_2u_lib.s9s_mb_2u(sch_1):page278_i31@pure_quanta.q_res(chips)',
 PATH='I31',
 DRAWING='@S9S_MB_2U_LIB.S9S_MB_2U(SCH_1):PAGE264',
 PHYS_PAGE='278',
 XY='(-10475,7100)',
 ROT='0',
 VER='1',
 PACK_TYPE='0402LF',
 LOCATION='PR592',
 CDS_LIB='pure_quanta',
 CDS_PART_NAME='Q_RES_0402LF-100,1%,1/16W,CHIPA',
 WATTAGE='1/16W',
 TOLERANCE='1%',
 MATERIAL='CHIP',
 VALUE='100',
 PRIM_FILE='./archive_libs/logical/q_res/chips/chips.prt';

PART_NAME
 PR632 'Q_RES_0402LF-0,5%,1/16W,EMPTY,A':;

SECTION_NUMBER 1
 '@S9S_MB_2U_LIB.S9S_MB_2U(SCH_1):PAGE257_I40@PURE_QUANTA.Q_RES(CHIPS)':
 C_PATH='@s9s_mb_2u_lib.s9s_mb_2u(sch_1):page257_i40@pure_quanta.q_res(chips)',
 P_PATH='@s9s_mb_2u_lib.s9s_mb_2u(sch_1):page271_i40@pure_quanta.q_res(chips)',
 PATH='I40',
 DRAWING='@S9S_MB_2U_LIB.S9S_MB_2U(SCH_1):PAGE257',
 PHYS_PAGE='271',
 XY='(-4175,6700)',
 ROT='0',
 VER='2',
 PACK_TYPE='0402LF',
 LOCATION='PR632',
 CDS_LIB='pure_quanta',
 CDS_PART_NAME='Q_RES_0402LF-0,5%,1/16W,EMPTY,A',
 WATTAGE='1/16W',
 TOLERANCE='5%',
 MATERIAL='EMPTY',
 VALUE='0',
 PRIM_FILE='./archive_libs/logical/q_res/chips/chips.prt';

PART_NAME
 PR633 'Q_RES_0402LF-0,5%,1/16W,EMPTY,A':;

SECTION_NUMBER 1
 '@S9S_MB_2U_LIB.S9S_MB_2U(SCH_1):PAGE257_I22@PURE_QUANTA.Q_RES(CHIPS)':
 C_PATH='@s9s_mb_2u_lib.s9s_mb_2u(sch_1):page257_i22@pure_quanta.q_res(chips)',
 P_PATH='@s9s_mb_2u_lib.s9s_mb_2u(sch_1):page271_i22@pure_quanta.q_res(chips)',
 PATH='I22',
 DRAWING='@S9S_MB_2U_LIB.S9S_MB_2U(SCH_1):PAGE257',
 PHYS_PAGE='271',
 XY='(-4175,3900)',
 ROT='0',
 VER='2',
 PACK_TYPE='0402LF',
 LOCATION='PR633',
 CDS_LIB='pure_quanta',
 CDS_PART_NAME='Q_RES_0402LF-0,5%,1/16W,EMPTY,A',
 WATTAGE='1/16W',
 TOLERANCE='5%',
 MATERIAL='EMPTY',
 VALUE='0',
 PRIM_FILE='./archive_libs/logical/q_res/chips/chips.prt';

PART_NAME
 PR634 'Q_RES_0402LF-10K,1%,1/16W,EMPTA':;

SECTION_NUMBER 1
 '@S9S_MB_2U_LIB.S9S_MB_2U(SCH_1):PAGE264_I57@PURE_QUANTA.Q_RES(CHIPS)':
 C_PATH='@s9s_mb_2u_lib.s9s_mb_2u(sch_1):page264_i57@pure_quanta.q_res(chips)',
 P_PATH='@s9s_mb_2u_lib.s9s_mb_2u(sch_1):page278_i57@pure_quanta.q_res(chips)',
 PATH='I57',
 DRAWING='@S9S_MB_2U_LIB.S9S_MB_2U(SCH_1):PAGE264',
 PHYS_PAGE='278',
 XY='(-5150,3550)',
 ROT='0',
 VER='2',
 PACK_TYPE='0402LF',
 LOCATION='PR634',
 CDS_LIB='pure_quanta',
 CDS_PART_NAME='Q_RES_0402LF-10K,1%,1/16W,EMPTA',
 WATTAGE='1/16W',
 TOLERANCE='1%',
 MATERIAL='EMPTY',
 VALUE='10K',
 PRIM_FILE='./archive_libs/logical/q_res/chips/chips.prt';

PART_NAME
 PR637 'Q_RES_0402LF-10K,1%,1/16W,EMPTA':;

SECTION_NUMBER 1
 '@S9S_MB_2U_LIB.S9S_MB_2U(SCH_1):PAGE270_I74@PURE_QUANTA.Q_RES(CHIPS)':
 C_PATH='@s9s_mb_2u_lib.s9s_mb_2u(sch_1):page270_i74@pure_quanta.q_res(chips)',
 P_PATH='@s9s_mb_2u_lib.s9s_mb_2u(sch_1):page284_i74@pure_quanta.q_res(chips)',
 PATH='I74',
 DRAWING='@S9S_MB_2U_LIB.S9S_MB_2U(SCH_1):PAGE270',
 PHYS_PAGE='284',
 XY='(1850,-2375)',
 ROT='0',
 VER='2',
 PACK_TYPE='0402LF',
 LOCATION='PR637',
 CDS_LIB='pure_quanta',
 CDS_PART_NAME='Q_RES_0402LF-10K,1%,1/16W,EMPTA',
 WATTAGE='1/16W',
 TOLERANCE='1%',
 MATERIAL='EMPTY',
 VALUE='10K',
 PRIM_FILE='./archive_libs/logical/q_res/chips/chips.prt';

PART_NAME
 PR639 'Q_RES_0402LF-0,5%,1/16W,CHIP,CA':;

SECTION_NUMBER 1
 '@S9S_MB_2U_LIB.S9S_MB_2U(SCH_1):PAGE271_I26@PURE_QUANTA.Q_RES(CHIPS)':
 C_PATH='@s9s_mb_2u_lib.s9s_mb_2u(sch_1):page271_i26@pure_quanta.q_res(chips)',
 P_PATH='@s9s_mb_2u_lib.s9s_mb_2u(sch_1):page285_i26@pure_quanta.q_res(chips)',
 PATH='I26',
 DRAWING='@S9S_MB_2U_LIB.S9S_MB_2U(SCH_1):PAGE271',
 PHYS_PAGE='285',
 XY='(-4125,2800)',
 ROT='0',
 VER='2',
 PACK_TYPE='0402LF',
 LOCATION='PR639',
 CDS_LIB='pure_quanta',
 CDS_PART_NAME='Q_RES_0402LF-0,5%,1/16W,CHIP,CA',
 WATTAGE='1/16W',
 TOLERANCE='5%',
 MATERIAL='CHIP',
 VALUE='0',
 PRIM_FILE='./archive_libs/logical/q_res/chips/chips.prt';

PART_NAME
 PR640 'Q_RES_0402LF-0,5%,1/16W,EMPTY,A':;

SECTION_NUMBER 1
 '@S9S_MB_2U_LIB.S9S_MB_2U(SCH_1):PAGE271_I41@PURE_QUANTA.Q_RES(CHIPS)':
 C_PATH='@s9s_mb_2u_lib.s9s_mb_2u(sch_1):page271_i41@pure_quanta.q_res(chips)',
 P_PATH='@s9s_mb_2u_lib.s9s_mb_2u(sch_1):page285_i41@pure_quanta.q_res(chips)',
 PATH='I41',
 DRAWING='@S9S_MB_2U_LIB.S9S_MB_2U(SCH_1):PAGE271',
 PHYS_PAGE='285',
 XY='(-3475,2800)',
 ROT='0',
 VER='2',
 PACK_TYPE='0402LF',
 LOCATION='PR640',
 CDS_LIB='pure_quanta',
 CDS_PART_NAME='Q_RES_0402LF-0,5%,1/16W,EMPTY,A',
 WATTAGE='1/16W',
 TOLERANCE='5%',
 MATERIAL='EMPTY',
 VALUE='0',
 PRIM_FILE='./archive_libs/logical/q_res/chips/chips.prt';

PART_NAME
 PR665 'Q_RES_0402LF-10K,1%,1/16W,EMPTA':;

SECTION_NUMBER 1
 '@S9S_MB_2U_LIB.S9S_MB_2U(SCH_1):PAGE278_I67@PURE_QUANTA.Q_RES(CHIPS)':
 C_PATH='@s9s_mb_2u_lib.s9s_mb_2u(sch_1):page278_i67@pure_quanta.q_res(chips)',
 P_PATH='@s9s_mb_2u_lib.s9s_mb_2u(sch_1):page292_i67@pure_quanta.q_res(chips)',
 PATH='I67',
 DRAWING='@S9S_MB_2U_LIB.S9S_MB_2U(SCH_1):PAGE278',
 PHYS_PAGE='292',
 XY='(5100,3750)',
 ROT='0',
 VER='2',
 PACK_TYPE='0402LF',
 LOCATION='PR665',
 CDS_LIB='pure_quanta',
 CDS_PART_NAME='Q_RES_0402LF-10K,1%,1/16W,EMPTA',
 WATTAGE='1/16W',
 TOLERANCE='1%',
 MATERIAL='EMPTY',
 VALUE='10K',
 PRIM_FILE='./archive_libs/logical/q_res/chips/chips.prt';

PART_NAME
 PR667 'Q_RES_0402LF-10K,1%,1/16W,EMPTA':;

SECTION_NUMBER 1
 '@S9S_MB_2U_LIB.S9S_MB_2U(SCH_1):PAGE278_I75@PURE_QUANTA.Q_RES(CHIPS)':
 C_PATH='@s9s_mb_2u_lib.s9s_mb_2u(sch_1):page278_i75@pure_quanta.q_res(chips)',
 P_PATH='@s9s_mb_2u_lib.s9s_mb_2u(sch_1):page292_i75@pure_quanta.q_res(chips)',
 PATH='I75',
 DRAWING='@S9S_MB_2U_LIB.S9S_MB_2U(SCH_1):PAGE278',
 PHYS_PAGE='292',
 XY='(6700,4050)',
 ROT='0',
 VER='2',
 PACK_TYPE='0402LF',
 LOCATION='PR667',
 CDS_LIB='pure_quanta',
 CDS_PART_NAME='Q_RES_0402LF-10K,1%,1/16W,EMPTA',
 WATTAGE='1/16W',
 TOLERANCE='1%',
 MATERIAL='EMPTY',
 VALUE='10K',
 PRIM_FILE='./archive_libs/logical/q_res/chips/chips.prt';

PART_NAME
 PR678 'Q_RES_0402LF-0,5%,1/16W,CHIP,CA':;

SECTION_NUMBER 1
 '@S9S_MB_2U_LIB.S9S_MB_2U(SCH_1):PAGE280_I4@PURE_QUANTA.Q_RES(CHIPS)':
 C_PATH='@s9s_mb_2u_lib.s9s_mb_2u(sch_1):page280_i4@pure_quanta.q_res(chips)',
 P_PATH='@s9s_mb_2u_lib.s9s_mb_2u(sch_1):page294_i4@pure_quanta.q_res(chips)',
 PATH='I4',
 DRAWING='@S9S_MB_2U_LIB.S9S_MB_2U(SCH_1):PAGE280',
 PHYS_PAGE='294',
 XY='(-6575,10675)',
 ROT='0',
 VER='2',
 PACK_TYPE='0402LF',
 LOCATION='PR678',
 CDS_LIB='pure_quanta',
 CDS_PART_NAME='Q_RES_0402LF-0,5%,1/16W,CHIP,CA',
 WATTAGE='1/16W',
 TOLERANCE='5%',
 MATERIAL='CHIP',
 VALUE='0',
 PRIM_FILE='./archive_libs/logical/q_res/chips/chips.prt';

PART_NAME
 PR699 'Q_RES_0402LF-0,5%,1/16W,EMPTY,A':;

SECTION_NUMBER 1
 '@S9S_MB_2U_LIB.S9S_MB_2U(SCH_1):PAGE280_I16@PURE_QUANTA.Q_RES(CHIPS)':
 C_PATH='@s9s_mb_2u_lib.s9s_mb_2u(sch_1):page280_i16@pure_quanta.q_res(chips)',
 P_PATH='@s9s_mb_2u_lib.s9s_mb_2u(sch_1):page294_i16@pure_quanta.q_res(chips)',
 PATH='I16',
 DRAWING='@S9S_MB_2U_LIB.S9S_MB_2U(SCH_1):PAGE280',
 PHYS_PAGE='294',
 XY='(-5750,10675)',
 ROT='0',
 VER='2',
 PACK_TYPE='0402LF',
 LOCATION='PR699',
 CDS_LIB='pure_quanta',
 CDS_PART_NAME='Q_RES_0402LF-0,5%,1/16W,EMPTY,A',
 WATTAGE='1/16W',
 TOLERANCE='5%',
 MATERIAL='EMPTY',
 VALUE='0',
 PRIM_FILE='./archive_libs/logical/q_res/chips/chips.prt';

PART_NAME
 PR701 'Q_RES_0402LF-0,5%,1/16W,CHIP,CA':;

SECTION_NUMBER 1
 '@S9S_MB_2U_LIB.S9S_MB_2U(SCH_1):PAGE275_I32@PURE_QUANTA.Q_RES(CHIPS)':
 C_PATH='@s9s_mb_2u_lib.s9s_mb_2u(sch_1):page275_i32@pure_quanta.q_res(chips)',
 P_PATH='@s9s_mb_2u_lib.s9s_mb_2u(sch_1):page289_i32@pure_quanta.q_res(chips)',
 PATH='I32',
 DRAWING='@S9S_MB_2U_LIB.S9S_MB_2U(SCH_1):PAGE275',
 PHYS_PAGE='289',
 XY='(-10775,6175)',
 ROT='0',
 VER='2',
 PACK_TYPE='0402LF',
 LOCATION='PR701',
 CDS_LIB='pure_quanta',
 CDS_PART_NAME='Q_RES_0402LF-0,5%,1/16W,CHIP,CA',
 WATTAGE='1/16W',
 TOLERANCE='5%',
 MATERIAL='CHIP',
 VALUE='0',
 PRIM_FILE='./archive_libs/logical/q_res/chips/chips.prt';

PART_NAME
 PR702 'Q_RES_0402LF-0,5%,1/16W,CHIP,CA':;

SECTION_NUMBER 1
 '@S9S_MB_2U_LIB.S9S_MB_2U(SCH_1):PAGE275_I13@PURE_QUANTA.Q_RES(CHIPS)':
 C_PATH='@s9s_mb_2u_lib.s9s_mb_2u(sch_1):page275_i13@pure_quanta.q_res(chips)',
 P_PATH='@s9s_mb_2u_lib.s9s_mb_2u(sch_1):page289_i13@pure_quanta.q_res(chips)',
 PATH='I13',
 DRAWING='@S9S_MB_2U_LIB.S9S_MB_2U(SCH_1):PAGE275',
 PHYS_PAGE='289',
 XY='(-10775,3375)',
 ROT='0',
 VER='2',
 PACK_TYPE='0402LF',
 LOCATION='PR702',
 CDS_LIB='pure_quanta',
 CDS_PART_NAME='Q_RES_0402LF-0,5%,1/16W,CHIP,CA',
 WATTAGE='1/16W',
 TOLERANCE='5%',
 MATERIAL='CHIP',
 VALUE='0',
 PRIM_FILE='./archive_libs/logical/q_res/chips/chips.prt';

PART_NAME
 PR703 'Q_RES_0402LF-0,5%,1/16W,EMPTY,A':;

SECTION_NUMBER 1
 '@S9S_MB_2U_LIB.S9S_MB_2U(SCH_1):PAGE275_I34@PURE_QUANTA.Q_RES(CHIPS)':
 C_PATH='@s9s_mb_2u_lib.s9s_mb_2u(sch_1):page275_i34@pure_quanta.q_res(chips)',
 P_PATH='@s9s_mb_2u_lib.s9s_mb_2u(sch_1):page289_i34@pure_quanta.q_res(chips)',
 PATH='I34',
 DRAWING='@S9S_MB_2U_LIB.S9S_MB_2U(SCH_1):PAGE275',
 PHYS_PAGE='289',
 XY='(-10125,6175)',
 ROT='0',
 VER='2',
 PACK_TYPE='0402LF',
 LOCATION='PR703',
 CDS_LIB='pure_quanta',
 CDS_PART_NAME='Q_RES_0402LF-0,5%,1/16W,EMPTY,A',
 WATTAGE='1/16W',
 TOLERANCE='5%',
 MATERIAL='EMPTY',
 VALUE='0',
 PRIM_FILE='./archive_libs/logical/q_res/chips/chips.prt';

PART_NAME
 PR704 'Q_RES_0402LF-0,5%,1/16W,EMPTY,A':;

SECTION_NUMBER 1
 '@S9S_MB_2U_LIB.S9S_MB_2U(SCH_1):PAGE275_I17@PURE_QUANTA.Q_RES(CHIPS)':
 C_PATH='@s9s_mb_2u_lib.s9s_mb_2u(sch_1):page275_i17@pure_quanta.q_res(chips)',
 P_PATH='@s9s_mb_2u_lib.s9s_mb_2u(sch_1):page289_i17@pure_quanta.q_res(chips)',
 PATH='I17',
 DRAWING='@S9S_MB_2U_LIB.S9S_MB_2U(SCH_1):PAGE275',
 PHYS_PAGE='289',
 XY='(-10125,3375)',
 ROT='0',
 VER='2',
 PACK_TYPE='0402LF',
 LOCATION='PR704',
 CDS_LIB='pure_quanta',
 CDS_PART_NAME='Q_RES_0402LF-0,5%,1/16W,EMPTY,A',
 WATTAGE='1/16W',
 TOLERANCE='5%',
 MATERIAL='EMPTY',
 VALUE='0',
 PRIM_FILE='./archive_libs/logical/q_res/chips/chips.prt';

PART_NAME
 PR705 'Q_RES_0402LF-10K,1%,1/16W,EMPTA':;

SECTION_NUMBER 1
 '@S9S_MB_2U_LIB.S9S_MB_2U(SCH_1):PAGE282_I81@PURE_QUANTA.Q_RES(CHIPS)':
 C_PATH='@s9s_mb_2u_lib.s9s_mb_2u(sch_1):page282_i81@pure_quanta.q_res(chips)',
 P_PATH='@s9s_mb_2u_lib.s9s_mb_2u(sch_1):page296_i81@pure_quanta.q_res(chips)',
 PATH='I81',
 DRAWING='@S9S_MB_2U_LIB.S9S_MB_2U(SCH_1):PAGE282',
 PHYS_PAGE='296',
 XY='(-175,50)',
 ROT='0',
 VER='2',
 PACK_TYPE='0402LF',
 LOCATION='PR705',
 CDS_LIB='pure_quanta',
 CDS_PART_NAME='Q_RES_0402LF-10K,1%,1/16W,EMPTA',
 WATTAGE='1/16W',
 TOLERANCE='1%',
 MATERIAL='EMPTY',
 VALUE='10K',
 PRIM_FILE='./archive_libs/logical/q_res/chips/chips.prt';

PART_NAME
 PR830 'Q_RES_0402LF-15K,0.1%,1/16W,CHA':;

SECTION_NUMBER 1
 '@S9S_MB_2U_LIB.S9S_MB_2U(SCH_1):PAGE245_I125@PURE_QUANTA.Q_RES(CHIPS)':
 C_PATH='@s9s_mb_2u_lib.s9s_mb_2u(sch_1):page245_i125@pure_quanta.q_res(chips)',
 P_PATH='@s9s_mb_2u_lib.s9s_mb_2u(sch_1):page259_i125@pure_quanta.q_res(chips)',
 PATH='I125',
 DRAWING='@S9S_MB_2U_LIB.S9S_MB_2U(SCH_1):PAGE245',
 PHYS_PAGE='259',
 XY='(1200,-1725)',
 ROT='0',
 VER='2',
 PACK_TYPE='0402LF',
 LOCATION='PR830',
 CDS_LIB='pure_quanta',
 CDS_PART_NAME='Q_RES_0402LF-15K,0.1%,1/16W,CHA',
 WATTAGE='1/16W',
 TOLERANCE='0.1%',
 MATERIAL='CHIP',
 VALUE='15K',
 PRIM_FILE='./archive_libs/logical/q_res/chips/chips.prt';

PART_NAME
 PR831 'Q_RES_0402LF-47K,0.1%,1/16W,CHA':;

SECTION_NUMBER 1
 '@S9S_MB_2U_LIB.S9S_MB_2U(SCH_1):PAGE245_I128@PURE_QUANTA.Q_RES(CHIPS)':
 C_PATH='@s9s_mb_2u_lib.s9s_mb_2u(sch_1):page245_i128@pure_quanta.q_res(chips)',
 P_PATH='@s9s_mb_2u_lib.s9s_mb_2u(sch_1):page259_i128@pure_quanta.q_res(chips)',
 PATH='I128',
 DRAWING='@S9S_MB_2U_LIB.S9S_MB_2U(SCH_1):PAGE245',
 PHYS_PAGE='259',
 XY='(2100,-1550)',
 ROT='0',
 VER='1',
 PACK_TYPE='0402LF',
 LOCATION='PR831',
 CDS_LIB='pure_quanta',
 CDS_PART_NAME='Q_RES_0402LF-47K,0.1%,1/16W,CHA',
 WATTAGE='1/16W',
 TOLERANCE='0.1%',
 MATERIAL='CHIP',
 VALUE='47K',
 PRIM_FILE='./archive_libs/logical/q_res/chips/chips.prt';

PART_NAME
 PR832 'Q_RES_0402LF-0,5%,1/16W,CHIP,CA':;

SECTION_NUMBER 1
 '@S9S_MB_2U_LIB.S9S_MB_2U(SCH_1):PAGE245_I84@PURE_QUANTA.Q_RES(CHIPS)':
 C_PATH='@s9s_mb_2u_lib.s9s_mb_2u(sch_1):page245_i84@pure_quanta.q_res(chips)',
 P_PATH='@s9s_mb_2u_lib.s9s_mb_2u(sch_1):page259_i84@pure_quanta.q_res(chips)',
 PATH='I84',
 DRAWING='@S9S_MB_2U_LIB.S9S_MB_2U(SCH_1):PAGE245',
 PHYS_PAGE='259',
 XY='(-2150,-1225)',
 ROT='0',
 VER='2',
 PACK_TYPE='0402LF',
 LOCATION='PR832',
 CDS_LIB='pure_quanta',
 CDS_PART_NAME='Q_RES_0402LF-0,5%,1/16W,CHIP,CA',
 WATTAGE='1/16W',
 TOLERANCE='5%',
 MATERIAL='CHIP',
 VALUE='0',
 PRIM_FILE='./archive_libs/logical/q_res/chips/chips.prt';

PART_NAME
 PR833 'Q_RES_0402LF-1.5K,1%,1/16W,EMPA':;

SECTION_NUMBER 1
 '@S9S_MB_2U_LIB.S9S_MB_2U(SCH_1):PAGE245_I89@PURE_QUANTA.Q_RES(CHIPS)':
 C_PATH='@s9s_mb_2u_lib.s9s_mb_2u(sch_1):page245_i89@pure_quanta.q_res(chips)',
 P_PATH='@s9s_mb_2u_lib.s9s_mb_2u(sch_1):page259_i89@pure_quanta.q_res(chips)',
 PATH='I89',
 DRAWING='@S9S_MB_2U_LIB.S9S_MB_2U(SCH_1):PAGE245',
 PHYS_PAGE='259',
 XY='(-1750,-1325)',
 ROT='0',
 VER='2',
 PACK_TYPE='0402LF',
 LOCATION='PR833',
 CDS_LIB='pure_quanta',
 CDS_PART_NAME='Q_RES_0402LF-1.5K,1%,1/16W,EMPA',
 WATTAGE='1/16W',
 TOLERANCE='1%',
 MATERIAL='EMPTY',
 VALUE='1.5K',
 PRIM_FILE='./archive_libs/logical/q_res/chips/chips.prt';

PART_NAME
 PR834 'Q_RES_0402LF-21.5K,1%,1/16W,CHA':;

SECTION_NUMBER 1
 '@S9S_MB_2U_LIB.S9S_MB_2U(SCH_1):PAGE245_I91@PURE_QUANTA.Q_RES(CHIPS)':
 C_PATH='@s9s_mb_2u_lib.s9s_mb_2u(sch_1):page245_i91@pure_quanta.q_res(chips)',
 P_PATH='@s9s_mb_2u_lib.s9s_mb_2u(sch_1):page259_i91@pure_quanta.q_res(chips)',
 PATH='I91',
 DRAWING='@S9S_MB_2U_LIB.S9S_MB_2U(SCH_1):PAGE245',
 PHYS_PAGE='259',
 XY='(-1350,-1425)',
 ROT='0',
 VER='2',
 PACK_TYPE='0402LF',
 LOCATION='PR834',
 CDS_LIB='pure_quanta',
 CDS_PART_NAME='Q_RES_0402LF-21.5K,1%,1/16W,CHA',
 WATTAGE='1/16W',
 TOLERANCE='1%',
 MATERIAL='CHIP',
 VALUE='21.5K',
 PRIM_FILE='./archive_libs/logical/q_res/chips/chips.prt';

PART_NAME
 PR835 'Q_RES_0402LF-0,5%,1/16W,CHIP,CA':;

SECTION_NUMBER 1
 '@S9S_MB_2U_LIB.S9S_MB_2U(SCH_1):PAGE245_I123@PURE_QUANTA.Q_RES(CHIPS)':
 C_PATH='@s9s_mb_2u_lib.s9s_mb_2u(sch_1):page245_i123@pure_quanta.q_res(chips)',
 P_PATH='@s9s_mb_2u_lib.s9s_mb_2u(sch_1):page259_i123@pure_quanta.q_res(chips)',
 PATH='I123',
 DRAWING='@S9S_MB_2U_LIB.S9S_MB_2U(SCH_1):PAGE245',
 PHYS_PAGE='259',
 XY='(800,-350)',
 ROT='0',
 VER='1',
 PACK_TYPE='0402LF',
 LOCATION='PR835',
 CDS_LIB='pure_quanta',
 CDS_PART_NAME='Q_RES_0402LF-0,5%,1/16W,CHIP,CA',
 WATTAGE='1/16W',
 TOLERANCE='5%',
 MATERIAL='CHIP',
 VALUE='0',
 PRIM_FILE='./archive_libs/logical/q_res/chips/chips.prt';

PART_NAME
 PR836 'Q_RES_0402LF-1K,1%,1/16W,EMPTYA':;

SECTION_NUMBER 1
 '@S9S_MB_2U_LIB.S9S_MB_2U(SCH_1):PAGE245_I121@PURE_QUANTA.Q_RES(CHIPS)':
 C_PATH='@s9s_mb_2u_lib.s9s_mb_2u(sch_1):page245_i121@pure_quanta.q_res(chips)',
 P_PATH='@s9s_mb_2u_lib.s9s_mb_2u(sch_1):page259_i121@pure_quanta.q_res(chips)',
 PATH='I121',
 DRAWING='@S9S_MB_2U_LIB.S9S_MB_2U(SCH_1):PAGE245',
 PHYS_PAGE='259',
 XY='(825,-1250)',
 ROT='0',
 VER='1',
 PACK_TYPE='0402LF',
 LOCATION='PR836',
 CDS_LIB='pure_quanta',
 CDS_PART_NAME='Q_RES_0402LF-1K,1%,1/16W,EMPTYA',
 WATTAGE='1/16W',
 TOLERANCE='1%',
 MATERIAL='EMPTY',
 VALUE='1K',
 PRIM_FILE='./archive_libs/logical/q_res/chips/chips.prt';

PART_NAME
 PR1101 'Q_RES_0402LF-2K,0.1%,1/16W,CHIA':
 ROOM='HSC1_BOM1';

SECTION_NUMBER 1
 '@S9S_MB_2U_LIB.S9S_MB_2U(SCH_1):PAGE301_I13@PURE_QUANTA.Q_RES(CHIPS)':
 C_PATH='@s9s_mb_2u_lib.s9s_mb_2u(sch_1):page301_i13@pure_quanta.q_res(chips)',
 P_PATH='@s9s_mb_2u_lib.s9s_mb_2u(sch_1):page302_i13@pure_quanta.q_res(chips)',
 PATH='I13',
 DRAWING='@S9S_MB_2U_LIB.S9S_MB_2U(SCH_1):PAGE301',
 PHYS_PAGE='302',
 XY='(-1200,-2025)',
 ROT='0',
 VER='2',
 PACK_TYPE='0402LF',
 CDS_LIB='pure_quanta',
 CDS_PART_NAME='Q_RES_0402LF-2K,0.1%,1/16W,CHIA',
 WATTAGE='1/16W',
 TOLERANCE='0.1%',
 MATERIAL='CHIP',
 ROOM='HSC1_BOM1',
 VALUE='2K',
 PRIM_FILE='./archive_libs/logical/q_res/chips/chips.prt';

PART_NAME
 PR1131 'Q_RES_0402LF-2K,0.1%,1/16W,CHIA':
 ROOM='HSC1_BOM1';

SECTION_NUMBER 1
 '@S9S_MB_2U_LIB.S9S_MB_2U(SCH_1):PAGE303_I58@PURE_QUANTA.Q_RES(CHIPS)':
 C_PATH='@s9s_mb_2u_lib.s9s_mb_2u(sch_1):page303_i58@pure_quanta.q_res(chips)',
 P_PATH='@s9s_mb_2u_lib.s9s_mb_2u(sch_1):page301_i58@pure_quanta.q_res(chips)',
 PATH='I58',
 DRAWING='@S9S_MB_2U_LIB.S9S_MB_2U(SCH_1):PAGE303',
 PHYS_PAGE='301',
 XY='(-11875,3675)',
 ROT='0',
 VER='1',
 PACK_TYPE='0402LF',
 CDS_LIB='pure_quanta',
 CDS_PART_NAME='Q_RES_0402LF-2K,0.1%,1/16W,CHIA',
 WATTAGE='1/16W',
 TOLERANCE='0.1%',
 MATERIAL='CHIP',
 ROOM='HSC1_BOM1',
 VALUE='2K',
 PRIM_FILE='./archive_libs/logical/q_res/chips/chips.prt';

PART_NAME
 PR1133 'Q_RES_0402LF-2K,0.1%,1/16W,CHIA':
 ROOM='HSC1_BOM1';

SECTION_NUMBER 1
 '@S9S_MB_2U_LIB.S9S_MB_2U(SCH_1):PAGE303_I91@PURE_QUANTA.Q_RES(CHIPS)':
 C_PATH='@s9s_mb_2u_lib.s9s_mb_2u(sch_1):page303_i91@pure_quanta.q_res(chips)',
 P_PATH='@s9s_mb_2u_lib.s9s_mb_2u(sch_1):page301_i91@pure_quanta.q_res(chips)',
 PATH='I91',
 DRAWING='@S9S_MB_2U_LIB.S9S_MB_2U(SCH_1):PAGE303',
 PHYS_PAGE='301',
 XY='(-9350,3575)',
 ROT='0',
 VER='2',
 PACK_TYPE='0402LF',
 CDS_LIB='pure_quanta',
 CDS_PART_NAME='Q_RES_0402LF-2K,0.1%,1/16W,CHIA',
 WATTAGE='1/16W',
 TOLERANCE='0.1%',
 MATERIAL='CHIP',
 ROOM='HSC1_BOM1',
 VALUE='2K',
 PRIM_FILE='./archive_libs/logical/q_res/chips/chips.prt';

PART_NAME
 PR1134 'Q_RES_0402LF-120K,1%,1/16W,CHIA':
 ROOM='HSC1_BOM1';

SECTION_NUMBER 1
 '@S9S_MB_2U_LIB.S9S_MB_2U(SCH_1):PAGE301_I32@PURE_QUANTA.Q_RES(CHIPS)':
 C_PATH='@s9s_mb_2u_lib.s9s_mb_2u(sch_1):page301_i32@pure_quanta.q_res(chips)',
 P_PATH='@s9s_mb_2u_lib.s9s_mb_2u(sch_1):page302_i32@pure_quanta.q_res(chips)',
 PATH='I32',
 DRAWING='@S9S_MB_2U_LIB.S9S_MB_2U(SCH_1):PAGE301',
 PHYS_PAGE='302',
 XY='(-2150,1600)',
 ROT='0',
 VER='1',
 PACK_TYPE='0402LF',
 CDS_LIB='pure_quanta',
 CDS_PART_NAME='Q_RES_0402LF-120K,1%,1/16W,CHIA',
 WATTAGE='1/16W',
 TOLERANCE='1%',
 MATERIAL='CHIP',
 ROOM='HSC1_BOM1',
 VALUE='120K',
 PRIM_FILE='./archive_libs/logical/q_res/chips/chips.prt';

PART_NAME
 PR1297 'Q_RES_0402LF-8.87K,1%,1/16W,EMA':;

SECTION_NUMBER 1
 '@S9S_MB_2U_LIB.S9S_MB_2U(SCH_1):PAGE258_I3@PURE_QUANTA.Q_RES(CHIPS)':
 C_PATH='@s9s_mb_2u_lib.s9s_mb_2u(sch_1):page258_i3@pure_quanta.q_res(chips)',
 P_PATH='@s9s_mb_2u_lib.s9s_mb_2u(sch_1):page272_i3@pure_quanta.q_res(chips)',
 PATH='I3',
 DRAWING='@S9S_MB_2U_LIB.S9S_MB_2U(SCH_1):PAGE258',
 PHYS_PAGE='272',
 XY='(-11200,1600)',
 ROT='2',
 VER='2',
 PACK_TYPE='0402LF',
 LOCATION='PR1297',
 CDS_LIB='pure_quanta',
 CDS_PART_NAME='Q_RES_0402LF-8.87K,1%,1/16W,EMA',
 WATTAGE='1/16W',
 TOLERANCE='1%',
 MATERIAL='EMPTY',
 VALUE='8.87K',
 PRIM_FILE='./archive_libs/logical/q_res/chips/chips.prt';

PART_NAME
 PR1298 'Q_RES_0402LF-8.87K,1%,1/16W,EMA':;

SECTION_NUMBER 1
 '@S9S_MB_2U_LIB.S9S_MB_2U(SCH_1):PAGE258_I15@PURE_QUANTA.Q_RES(CHIPS)':
 C_PATH='@s9s_mb_2u_lib.s9s_mb_2u(sch_1):page258_i15@pure_quanta.q_res(chips)',
 P_PATH='@s9s_mb_2u_lib.s9s_mb_2u(sch_1):page272_i15@pure_quanta.q_res(chips)',
 PATH='I15',
 DRAWING='@S9S_MB_2U_LIB.S9S_MB_2U(SCH_1):PAGE258',
 PHYS_PAGE='272',
 XY='(-11175,4450)',
 ROT='2',
 VER='2',
 PACK_TYPE='0402LF',
 LOCATION='PR1298',
 CDS_LIB='pure_quanta',
 CDS_PART_NAME='Q_RES_0402LF-8.87K,1%,1/16W,EMA',
 WATTAGE='1/16W',
 TOLERANCE='1%',
 MATERIAL='EMPTY',
 VALUE='8.87K',
 PRIM_FILE='./archive_libs/logical/q_res/chips/chips.prt';

PART_NAME
 PR1299 'Q_RES_0402LF-2.2,1%,1/16W,CHIPA':;

SECTION_NUMBER 1
 '@S9S_MB_2U_LIB.S9S_MB_2U(SCH_1):PAGE258_I26@PURE_QUANTA.Q_RES(CHIPS)':
 C_PATH='@s9s_mb_2u_lib.s9s_mb_2u(sch_1):page258_i26@pure_quanta.q_res(chips)',
 P_PATH='@s9s_mb_2u_lib.s9s_mb_2u(sch_1):page272_i26@pure_quanta.q_res(chips)',
 PATH='I26',
 DRAWING='@S9S_MB_2U_LIB.S9S_MB_2U(SCH_1):PAGE258',
 PHYS_PAGE='272',
 XY='(-10700,5750)',
 ROT='0',
 VER='2',
 PACK_TYPE='0402LF',
 LOCATION='PR1299',
 CDS_LIB='pure_quanta',
 CDS_PART_NAME='Q_RES_0402LF-2.2,1%,1/16W,CHIPA',
 WATTAGE='1/16W',
 TOLERANCE='1%',
 MATERIAL='CHIP',
 VALUE='2.2',
 PRIM_FILE='./archive_libs/logical/q_res/chips/chips.prt';

PART_NAME
 PR1300 'Q_RES_0402LF-2.2,1%,1/16W,CHIPA':;

SECTION_NUMBER 1
 '@S9S_MB_2U_LIB.S9S_MB_2U(SCH_1):PAGE258_I11@PURE_QUANTA.Q_RES(CHIPS)':
 C_PATH='@s9s_mb_2u_lib.s9s_mb_2u(sch_1):page258_i11@pure_quanta.q_res(chips)',
 P_PATH='@s9s_mb_2u_lib.s9s_mb_2u(sch_1):page272_i11@pure_quanta.q_res(chips)',
 PATH='I11',
 DRAWING='@S9S_MB_2U_LIB.S9S_MB_2U(SCH_1):PAGE258',
 PHYS_PAGE='272',
 XY='(-10700,2950)',
 ROT='0',
 VER='2',
 PACK_TYPE='0402LF',
 LOCATION='PR1300',
 CDS_LIB='pure_quanta',
 CDS_PART_NAME='Q_RES_0402LF-2.2,1%,1/16W,CHIPA',
 WATTAGE='1/16W',
 TOLERANCE='1%',
 MATERIAL='CHIP',
 VALUE='2.2',
 PRIM_FILE='./archive_libs/logical/q_res/chips/chips.prt';

PART_NAME
 PR1301 'Q_RES_0402LF-60.4K,1%,1/16W,CHA':;

SECTION_NUMBER 1
 '@S9S_MB_2U_LIB.S9S_MB_2U(SCH_1):PAGE268_I9@PURE_QUANTA.Q_RES(CHIPS)':
 C_PATH='@s9s_mb_2u_lib.s9s_mb_2u(sch_1):page268_i9@pure_quanta.q_res(chips)',
 P_PATH='@s9s_mb_2u_lib.s9s_mb_2u(sch_1):page282_i9@pure_quanta.q_res(chips)',
 PATH='I9',
 DRAWING='@S9S_MB_2U_LIB.S9S_MB_2U(SCH_1):PAGE268',
 PHYS_PAGE='282',
 XY='(-8650,9275)',
 ROT='0',
 VER='2',
 PACK_TYPE='0402LF',
 LOCATION='PR1301',
 CDS_LIB='pure_quanta',
 CDS_PART_NAME='Q_RES_0402LF-60.4K,1%,1/16W,CHA',
 WATTAGE='1/16W',
 TOLERANCE='1%',
 MATERIAL='CHIP',
 VALUE='60.4K',
 PRIM_FILE='./archive_libs/logical/q_res/chips/chips.prt';

PART_NAME
 PR1303 'Q_RES_0402LF-22.6K,1%,1/16W,CHA':;

SECTION_NUMBER 1
 '@S9S_MB_2U_LIB.S9S_MB_2U(SCH_1):PAGE268_I21@PURE_QUANTA.Q_RES(CHIPS)':
 C_PATH='@s9s_mb_2u_lib.s9s_mb_2u(sch_1):page268_i21@pure_quanta.q_res(chips)',
 P_PATH='@s9s_mb_2u_lib.s9s_mb_2u(sch_1):page282_i21@pure_quanta.q_res(chips)',
 PATH='I21',
 DRAWING='@S9S_MB_2U_LIB.S9S_MB_2U(SCH_1):PAGE268',
 PHYS_PAGE='282',
 XY='(-7825,8675)',
 ROT='0',
 VER='2',
 PACK_TYPE='0402LF',
 LOCATION='PR1303',
 CDS_LIB='pure_quanta',
 CDS_PART_NAME='Q_RES_0402LF-22.6K,1%,1/16W,CHA',
 WATTAGE='1/16W',
 TOLERANCE='1%',
 MATERIAL='CHIP',
 VALUE='22.6K',
 PRIM_FILE='./archive_libs/logical/q_res/chips/chips.prt';

PART_NAME
 PR1304 'Q_RES_0402LF-8.87K,1%,1/16W,EMA':;

SECTION_NUMBER 1
 '@S9S_MB_2U_LIB.S9S_MB_2U(SCH_1):PAGE276_I2@PURE_QUANTA.Q_RES(CHIPS)':
 C_PATH='@s9s_mb_2u_lib.s9s_mb_2u(sch_1):page276_i2@pure_quanta.q_res(chips)',
 P_PATH='@s9s_mb_2u_lib.s9s_mb_2u(sch_1):page290_i2@pure_quanta.q_res(chips)',
 PATH='I2',
 DRAWING='@S9S_MB_2U_LIB.S9S_MB_2U(SCH_1):PAGE276',
 PHYS_PAGE='290',
 XY='(-7825,3325)',
 ROT='2',
 VER='2',
 PACK_TYPE='0402LF',
 LOCATION='PR1304',
 CDS_LIB='pure_quanta',
 CDS_PART_NAME='Q_RES_0402LF-8.87K,1%,1/16W,EMA',
 WATTAGE='1/16W',
 TOLERANCE='1%',
 MATERIAL='EMPTY',
 VALUE='8.87K',
 PRIM_FILE='./archive_libs/logical/q_res/chips/chips.prt';

PART_NAME
 PR1305 'Q_RES_0402LF-8.87K,1%,1/16W,EMA':;

SECTION_NUMBER 1
 '@S9S_MB_2U_LIB.S9S_MB_2U(SCH_1):PAGE276_I5@PURE_QUANTA.Q_RES(CHIPS)':
 C_PATH='@s9s_mb_2u_lib.s9s_mb_2u(sch_1):page276_i5@pure_quanta.q_res(chips)',
 P_PATH='@s9s_mb_2u_lib.s9s_mb_2u(sch_1):page290_i5@pure_quanta.q_res(chips)',
 PATH='I5',
 DRAWING='@S9S_MB_2U_LIB.S9S_MB_2U(SCH_1):PAGE276',
 PHYS_PAGE='290',
 XY='(-7800,6125)',
 ROT='2',
 VER='2',
 PACK_TYPE='0402LF',
 LOCATION='PR1305',
 CDS_LIB='pure_quanta',
 CDS_PART_NAME='Q_RES_0402LF-8.87K,1%,1/16W,EMA',
 WATTAGE='1/16W',
 TOLERANCE='1%',
 MATERIAL='EMPTY',
 VALUE='8.87K',
 PRIM_FILE='./archive_libs/logical/q_res/chips/chips.prt';

PART_NAME
 PR1306 'Q_RES_0402LF-2.2,1%,1/16W,CHIPA':;

SECTION_NUMBER 1
 '@S9S_MB_2U_LIB.S9S_MB_2U(SCH_1):PAGE276_I29@PURE_QUANTA.Q_RES(CHIPS)':
 C_PATH='@s9s_mb_2u_lib.s9s_mb_2u(sch_1):page276_i29@pure_quanta.q_res(chips)',
 P_PATH='@s9s_mb_2u_lib.s9s_mb_2u(sch_1):page290_i29@pure_quanta.q_res(chips)',
 PATH='I29',
 DRAWING='@S9S_MB_2U_LIB.S9S_MB_2U(SCH_1):PAGE276',
 PHYS_PAGE='290',
 XY='(-7325,7475)',
 ROT='0',
 VER='2',
 PACK_TYPE='0402LF',
 LOCATION='PR1306',
 CDS_LIB='pure_quanta',
 CDS_PART_NAME='Q_RES_0402LF-2.2,1%,1/16W,CHIPA',
 WATTAGE='1/16W',
 TOLERANCE='1%',
 MATERIAL='CHIP',
 VALUE='2.2',
 PRIM_FILE='./archive_libs/logical/q_res/chips/chips.prt';

PART_NAME
 PR1307 'Q_RES_0402LF-2.2,1%,1/16W,CHIPA':;

SECTION_NUMBER 1
 '@S9S_MB_2U_LIB.S9S_MB_2U(SCH_1):PAGE276_I18@PURE_QUANTA.Q_RES(CHIPS)':
 C_PATH='@s9s_mb_2u_lib.s9s_mb_2u(sch_1):page276_i18@pure_quanta.q_res(chips)',
 P_PATH='@s9s_mb_2u_lib.s9s_mb_2u(sch_1):page290_i18@pure_quanta.q_res(chips)',
 PATH='I18',
 DRAWING='@S9S_MB_2U_LIB.S9S_MB_2U(SCH_1):PAGE276',
 PHYS_PAGE='290',
 XY='(-7325,4675)',
 ROT='0',
 VER='2',
 PACK_TYPE='0402LF',
 LOCATION='PR1307',
 CDS_LIB='pure_quanta',
 CDS_PART_NAME='Q_RES_0402LF-2.2,1%,1/16W,CHIPA',
 WATTAGE='1/16W',
 TOLERANCE='1%',
 MATERIAL='CHIP',
 VALUE='2.2',
 PRIM_FILE='./archive_libs/logical/q_res/chips/chips.prt';

PART_NAME
 PR1310 'Q_RES_0402LF-11.3K,0.1%,1/16W,A':;

SECTION_NUMBER 1
 '@S9S_MB_2U_LIB.S9S_MB_2U(SCH_1):PAGE267_I26@PURE_QUANTA.Q_RES(CHIPS)':
 C_PATH='@s9s_mb_2u_lib.s9s_mb_2u(sch_1):page267_i26@pure_quanta.q_res(chips)',
 P_PATH='@s9s_mb_2u_lib.s9s_mb_2u(sch_1):page281_i26@pure_quanta.q_res(chips)',
 PATH='I26',
 DRAWING='@S9S_MB_2U_LIB.S9S_MB_2U(SCH_1):PAGE267',
 BOM_COST='VR_PCH',
 PHYS_PAGE='281',
 XY='(-7000,2450)',
 ROT='0',
 VER='2',
 PACK_TYPE='0402LF',
 LOCATION='PR1310',
 CDS_LIB='pure_quanta',
 CDS_PART_NAME='Q_RES_0402LF-11.3K,0.1%,1/16W,A',
 WATTAGE='1/16W',
 TOLERANCE='0.1%',
 MATERIAL='CHIP',
 VALUE='11.3K',
 PRIM_FILE='./archive_libs/logical/q_res/chips/chips.prt';

PART_NAME
 PR1311 'Q_RES_0402LF-0,5%,1/16W,CHIP,CA':;

SECTION_NUMBER 1
 '@S9S_MB_2U_LIB.S9S_MB_2U(SCH_1):PAGE264_I59@PURE_QUANTA.Q_RES(CHIPS)':
 C_PATH='@s9s_mb_2u_lib.s9s_mb_2u(sch_1):page264_i59@pure_quanta.q_res(chips)',
 P_PATH='@s9s_mb_2u_lib.s9s_mb_2u(sch_1):page278_i59@pure_quanta.q_res(chips)',
 PATH='I59',
 DRAWING='@S9S_MB_2U_LIB.S9S_MB_2U(SCH_1):PAGE264',
 PHYS_PAGE='278',
 XY='(-4975,4050)',
 ROT='0',
 VER='1',
 PACK_TYPE='0402LF',
 LOCATION='PR1311',
 CDS_LIB='pure_quanta',
 CDS_PART_NAME='Q_RES_0402LF-0,5%,1/16W,CHIP,CA',
 WATTAGE='1/16W',
 TOLERANCE='5%',
 MATERIAL='CHIP',
 VALUE='0',
 PRIM_FILE='./archive_libs/logical/q_res/chips/chips.prt';

PART_NAME
 PR1314 'Q_RES_0402LF-11.3K,0.1%,1/16W,A':;

SECTION_NUMBER 1
 '@S9S_MB_2U_LIB.S9S_MB_2U(SCH_1):PAGE285_I28@PURE_QUANTA.Q_RES(CHIPS)':
 C_PATH='@s9s_mb_2u_lib.s9s_mb_2u(sch_1):page285_i28@pure_quanta.q_res(chips)',
 P_PATH='@s9s_mb_2u_lib.s9s_mb_2u(sch_1):page299_i28@pure_quanta.q_res(chips)',
 PATH='I28',
 DRAWING='@S9S_MB_2U_LIB.S9S_MB_2U(SCH_1):PAGE285',
 BOM_COST='VR_PCH',
 PHYS_PAGE='299',
 XY='(-6375,2000)',
 ROT='0',
 VER='2',
 PACK_TYPE='0402LF',
 LOCATION='PR1314',
 CDS_LIB='pure_quanta',
 CDS_PART_NAME='Q_RES_0402LF-11.3K,0.1%,1/16W,A',
 WATTAGE='1/16W',
 TOLERANCE='0.1%',
 MATERIAL='CHIP',
 VALUE='11.3K',
 PRIM_FILE='./archive_libs/logical/q_res/chips/chips.prt';

PART_NAME
 PR1315 'Q_RES_0402LF-0,5%,1/16W,CHIP,CA':;

SECTION_NUMBER 1
 '@S9S_MB_2U_LIB.S9S_MB_2U(SCH_1):PAGE282_I60@PURE_QUANTA.Q_RES(CHIPS)':
 C_PATH='@s9s_mb_2u_lib.s9s_mb_2u(sch_1):page282_i60@pure_quanta.q_res(chips)',
 P_PATH='@s9s_mb_2u_lib.s9s_mb_2u(sch_1):page296_i60@pure_quanta.q_res(chips)',
 PATH='I60',
 DRAWING='@S9S_MB_2U_LIB.S9S_MB_2U(SCH_1):PAGE282',
 PHYS_PAGE='296',
 XY='(-475,550)',
 ROT='0',
 VER='1',
 PACK_TYPE='0402LF',
 LOCATION='PR1315',
 CDS_LIB='pure_quanta',
 CDS_PART_NAME='Q_RES_0402LF-0,5%,1/16W,CHIP,CA',
 WATTAGE='1/16W',
 TOLERANCE='5%',
 MATERIAL='CHIP',
 VALUE='0',
 PRIM_FILE='./archive_libs/logical/q_res/chips/chips.prt';

PART_NAME
 PR1322 'Q_RES_0402LF-0,5%,1/16W,CHIP,CA':;

SECTION_NUMBER 1
 '@S9S_MB_2U_LIB.S9S_MB_2U(SCH_1):PAGE257_I69@PURE_QUANTA.Q_RES(CHIPS)':
 C_PATH='@s9s_mb_2u_lib.s9s_mb_2u(sch_1):page257_i69@pure_quanta.q_res(chips)',
 P_PATH='@s9s_mb_2u_lib.s9s_mb_2u(sch_1):page271_i69@pure_quanta.q_res(chips)',
 PATH='I69',
 DRAWING='@S9S_MB_2U_LIB.S9S_MB_2U(SCH_1):PAGE257',
 PHYS_PAGE='271',
 XY='(-25,4950)',
 ROT='0',
 VER='1',
 PACK_TYPE='0402LF',
 LOCATION='PR1322',
 CDS_LIB='pure_quanta',
 CDS_PART_NAME='Q_RES_0402LF-0,5%,1/16W,CHIP,CA',
 WATTAGE='1/16W',
 TOLERANCE='5%',
 MATERIAL='CHIP',
 VALUE='0',
 PRIM_FILE='./archive_libs/logical/q_res/chips/chips.prt';

PART_NAME
 PR1323 'Q_RES_0402LF-0,5%,1/16W,CHIP,CA':;

SECTION_NUMBER 1
 '@S9S_MB_2U_LIB.S9S_MB_2U(SCH_1):PAGE257_I50@PURE_QUANTA.Q_RES(CHIPS)':
 C_PATH='@s9s_mb_2u_lib.s9s_mb_2u(sch_1):page257_i50@pure_quanta.q_res(chips)',
 P_PATH='@s9s_mb_2u_lib.s9s_mb_2u(sch_1):page271_i50@pure_quanta.q_res(chips)',
 PATH='I50',
 DRAWING='@S9S_MB_2U_LIB.S9S_MB_2U(SCH_1):PAGE257',
 PHYS_PAGE='271',
 XY='(-25,2150)',
 ROT='0',
 VER='1',
 PACK_TYPE='0402LF',
 LOCATION='PR1323',
 CDS_LIB='pure_quanta',
 CDS_PART_NAME='Q_RES_0402LF-0,5%,1/16W,CHIP,CA',
 WATTAGE='1/16W',
 TOLERANCE='5%',
 MATERIAL='CHIP',
 VALUE='0',
 PRIM_FILE='./archive_libs/logical/q_res/chips/chips.prt';

PART_NAME
 PR1324 'Q_RES_0402LF-0,5%,1/16W,CHIP,CA':;

SECTION_NUMBER 1
 '@S9S_MB_2U_LIB.S9S_MB_2U(SCH_1):PAGE258_I50@PURE_QUANTA.Q_RES(CHIPS)':
 C_PATH='@s9s_mb_2u_lib.s9s_mb_2u(sch_1):page258_i50@pure_quanta.q_res(chips)',
 P_PATH='@s9s_mb_2u_lib.s9s_mb_2u(sch_1):page272_i50@pure_quanta.q_res(chips)',
 PATH='I50',
 DRAWING='@S9S_MB_2U_LIB.S9S_MB_2U(SCH_1):PAGE258',
 PHYS_PAGE='272',
 XY='(-6475,4650)',
 ROT='0',
 VER='1',
 PACK_TYPE='0402LF',
 LOCATION='PR1324',
 CDS_LIB='pure_quanta',
 CDS_PART_NAME='Q_RES_0402LF-0,5%,1/16W,CHIP,CA',
 WATTAGE='1/16W',
 TOLERANCE='5%',
 MATERIAL='CHIP',
 VALUE='0',
 PRIM_FILE='./archive_libs/logical/q_res/chips/chips.prt';

PART_NAME
 PR1325 'Q_RES_0402LF-0,5%,1/16W,CHIP,CA':;

SECTION_NUMBER 1
 '@S9S_MB_2U_LIB.S9S_MB_2U(SCH_1):PAGE258_I38@PURE_QUANTA.Q_RES(CHIPS)':
 C_PATH='@s9s_mb_2u_lib.s9s_mb_2u(sch_1):page258_i38@pure_quanta.q_res(chips)',
 P_PATH='@s9s_mb_2u_lib.s9s_mb_2u(sch_1):page272_i38@pure_quanta.q_res(chips)',
 PATH='I38',
 DRAWING='@S9S_MB_2U_LIB.S9S_MB_2U(SCH_1):PAGE258',
 PHYS_PAGE='272',
 XY='(-6475,1850)',
 ROT='0',
 VER='1',
 PACK_TYPE='0402LF',
 LOCATION='PR1325',
 CDS_LIB='pure_quanta',
 CDS_PART_NAME='Q_RES_0402LF-0,5%,1/16W,CHIP,CA',
 WATTAGE='1/16W',
 TOLERANCE='5%',
 MATERIAL='CHIP',
 VALUE='0',
 PRIM_FILE='./archive_libs/logical/q_res/chips/chips.prt';

PART_NAME
 PR1326 'Q_RES_0402LF-0,5%,1/16W,CHIP,CA':;

SECTION_NUMBER 1
 '@S9S_MB_2U_LIB.S9S_MB_2U(SCH_1):PAGE248_I3@PURE_QUANTA.Q_RES(CHIPS)':
 C_PATH='@s9s_mb_2u_lib.s9s_mb_2u(sch_1):page248_i3@pure_quanta.q_res(chips)',
 P_PATH='@s9s_mb_2u_lib.s9s_mb_2u(sch_1):page262_i3@pure_quanta.q_res(chips)',
 PATH='I3',
 DRAWING='@S9S_MB_2U_LIB.S9S_MB_2U(SCH_1):PAGE248',
 PHYS_PAGE='262',
 XY='(-3150,-1000)',
 ROT='0',
 VER='2',
 PACK_TYPE='0402LF',
 LOCATION='PR1326',
 CDS_LIB='pure_quanta',
 CDS_PART_NAME='Q_RES_0402LF-0,5%,1/16W,CHIP,CA',
 WATTAGE='1/16W',
 TOLERANCE='5%',
 MATERIAL='CHIP',
 VALUE='0',
 PRIM_FILE='./archive_libs/logical/q_res/chips/chips.prt';

PART_NAME
 PR1327 'Q_RES_0402LF-8.45K,1%,1/16W,CHA':;

SECTION_NUMBER 1
 '@S9S_MB_2U_LIB.S9S_MB_2U(SCH_1):PAGE248_I6@PURE_QUANTA.Q_RES(CHIPS)':
 C_PATH='@s9s_mb_2u_lib.s9s_mb_2u(sch_1):page248_i6@pure_quanta.q_res(chips)',
 P_PATH='@s9s_mb_2u_lib.s9s_mb_2u(sch_1):page262_i6@pure_quanta.q_res(chips)',
 PATH='I6',
 DRAWING='@S9S_MB_2U_LIB.S9S_MB_2U(SCH_1):PAGE248',
 PHYS_PAGE='262',
 XY='(-2100,-1450)',
 ROT='0',
 VER='2',
 PACK_TYPE='0402LF',
 LOCATION='PR1327',
 CDS_LIB='pure_quanta',
 CDS_PART_NAME='Q_RES_0402LF-8.45K,1%,1/16W,CHA',
 WATTAGE='1/16W',
 TOLERANCE='1%',
 MATERIAL='CHIP',
 VALUE='8.45K',
 PRIM_FILE='./archive_libs/logical/q_res/chips/chips.prt';

PART_NAME
 PR1328 'Q_RES_0402LF-7.32K,0.1%,1/16W,A':;

SECTION_NUMBER 1
 '@S9S_MB_2U_LIB.S9S_MB_2U(SCH_1):PAGE248_I36@PURE_QUANTA.Q_RES(CHIPS)':
 C_PATH='@s9s_mb_2u_lib.s9s_mb_2u(sch_1):page248_i36@pure_quanta.q_res(chips)',
 P_PATH='@s9s_mb_2u_lib.s9s_mb_2u(sch_1):page262_i36@pure_quanta.q_res(chips)',
 PATH='I36',
 DRAWING='@S9S_MB_2U_LIB.S9S_MB_2U(SCH_1):PAGE248',
 PHYS_PAGE='262',
 XY='(1650,-1050)',
 ROT='0',
 VER='1',
 PACK_TYPE='0402LF',
 LOCATION='PR1328',
 CDS_LIB='pure_quanta',
 CDS_PART_NAME='Q_RES_0402LF-7.32K,0.1%,1/16W,A',
 WATTAGE='1/16W',
 TOLERANCE='0.1%',
 MATERIAL='CHIP',
 VALUE='7.32K',
 PRIM_FILE='./archive_libs/logical/q_res/chips/chips.prt';

PART_NAME
 PR1329 'Q_RES_0402LF-5.1,5%,1/16W,CHIPA':;

SECTION_NUMBER 1
 '@S9S_MB_2U_LIB.S9S_MB_2U(SCH_1):PAGE249_I5@PURE_QUANTA.Q_RES(CHIPS)':
 C_PATH='@s9s_mb_2u_lib.s9s_mb_2u(sch_1):page249_i5@pure_quanta.q_res(chips)',
 P_PATH='@s9s_mb_2u_lib.s9s_mb_2u(sch_1):page263_i5@pure_quanta.q_res(chips)',
 PATH='I5',
 DRAWING='@S9S_MB_2U_LIB.S9S_MB_2U(SCH_1):PAGE249',
 PHYS_PAGE='263',
 XY='(-5750,5600)',
 ROT='0',
 VER='2',
 PACK_TYPE='0402LF',
 LOCATION='PR1329',
 CDS_LIB='pure_quanta',
 CDS_PART_NAME='Q_RES_0402LF-5.1,5%,1/16W,CHIPA',
 WATTAGE='1/16W',
 TOLERANCE='5%',
 MATERIAL='CHIP',
 VALUE='5.1',
 PRIM_FILE='./archive_libs/logical/q_res/chips/chips.prt';

PART_NAME
 PR1330 'Q_RES_0402LF-150K,1%,1/16W,CHIA':;

SECTION_NUMBER 1
 '@S9S_MB_2U_LIB.S9S_MB_2U(SCH_1):PAGE249_I24@PURE_QUANTA.Q_RES(CHIPS)':
 C_PATH='@s9s_mb_2u_lib.s9s_mb_2u(sch_1):page249_i24@pure_quanta.q_res(chips)',
 P_PATH='@s9s_mb_2u_lib.s9s_mb_2u(sch_1):page263_i24@pure_quanta.q_res(chips)',
 PATH='I24',
 DRAWING='@S9S_MB_2U_LIB.S9S_MB_2U(SCH_1):PAGE249',
 PHYS_PAGE='263',
 XY='(-4325,5150)',
 ROT='0',
 VER='2',
 PACK_TYPE='0402LF',
 LOCATION='PR1330',
 CDS_LIB='pure_quanta',
 CDS_PART_NAME='Q_RES_0402LF-150K,1%,1/16W,CHIA',
 WATTAGE='1/16W',
 TOLERANCE='1%',
 MATERIAL='CHIP',
 VALUE='150K',
 PRIM_FILE='./archive_libs/logical/q_res/chips/chips.prt';

PART_NAME
 PR1331 'Q_RES_0402LF-0,5%,1/16W,CHIP,CA':;

SECTION_NUMBER 1
 '@S9S_MB_2U_LIB.S9S_MB_2U(SCH_1):PAGE275_I53@PURE_QUANTA.Q_RES(CHIPS)':
 C_PATH='@s9s_mb_2u_lib.s9s_mb_2u(sch_1):page275_i53@pure_quanta.q_res(chips)',
 P_PATH='@s9s_mb_2u_lib.s9s_mb_2u(sch_1):page289_i53@pure_quanta.q_res(chips)',
 PATH='I53',
 DRAWING='@S9S_MB_2U_LIB.S9S_MB_2U(SCH_1):PAGE275',
 PHYS_PAGE='289',
 XY='(-6025,4425)',
 ROT='0',
 VER='1',
 PACK_TYPE='0402LF',
 LOCATION='PR1331',
 CDS_LIB='pure_quanta',
 CDS_PART_NAME='Q_RES_0402LF-0,5%,1/16W,CHIP,CA',
 WATTAGE='1/16W',
 TOLERANCE='5%',
 MATERIAL='CHIP',
 VALUE='0',
 PRIM_FILE='./archive_libs/logical/q_res/chips/chips.prt';

PART_NAME
 PR1332 'Q_RES_0402LF-0,5%,1/16W,CHIP,CA':;

SECTION_NUMBER 1
 '@S9S_MB_2U_LIB.S9S_MB_2U(SCH_1):PAGE275_I41@PURE_QUANTA.Q_RES(CHIPS)':
 C_PATH='@s9s_mb_2u_lib.s9s_mb_2u(sch_1):page275_i41@pure_quanta.q_res(chips)',
 P_PATH='@s9s_mb_2u_lib.s9s_mb_2u(sch_1):page289_i41@pure_quanta.q_res(chips)',
 PATH='I41',
 DRAWING='@S9S_MB_2U_LIB.S9S_MB_2U(SCH_1):PAGE275',
 PHYS_PAGE='289',
 XY='(-6025,1625)',
 ROT='0',
 VER='1',
 PACK_TYPE='0402LF',
 LOCATION='PR1332',
 CDS_LIB='pure_quanta',
 CDS_PART_NAME='Q_RES_0402LF-0,5%,1/16W,CHIP,CA',
 WATTAGE='1/16W',
 TOLERANCE='5%',
 MATERIAL='CHIP',
 VALUE='0',
 PRIM_FILE='./archive_libs/logical/q_res/chips/chips.prt';

PART_NAME
 PR1333 'Q_RES_0402LF-0,5%,1/16W,CHIP,CA':;

SECTION_NUMBER 1
 '@S9S_MB_2U_LIB.S9S_MB_2U(SCH_1):PAGE276_I54@PURE_QUANTA.Q_RES(CHIPS)':
 C_PATH='@s9s_mb_2u_lib.s9s_mb_2u(sch_1):page276_i54@pure_quanta.q_res(chips)',
 P_PATH='@s9s_mb_2u_lib.s9s_mb_2u(sch_1):page290_i54@pure_quanta.q_res(chips)',
 PATH='I54',
 DRAWING='@S9S_MB_2U_LIB.S9S_MB_2U(SCH_1):PAGE276',
 PHYS_PAGE='290',
 XY='(-3100,6375)',
 ROT='0',
 VER='1',
 PACK_TYPE='0402LF',
 LOCATION='PR1333',
 CDS_LIB='pure_quanta',
 CDS_PART_NAME='Q_RES_0402LF-0,5%,1/16W,CHIP,CA',
 WATTAGE='1/16W',
 TOLERANCE='5%',
 MATERIAL='CHIP',
 VALUE='0',
 PRIM_FILE='./archive_libs/logical/q_res/chips/chips.prt';

PART_NAME
 PR1334 'Q_RES_0402LF-0,5%,1/16W,CHIP,CA':;

SECTION_NUMBER 1
 '@S9S_MB_2U_LIB.S9S_MB_2U(SCH_1):PAGE276_I43@PURE_QUANTA.Q_RES(CHIPS)':
 C_PATH='@s9s_mb_2u_lib.s9s_mb_2u(sch_1):page276_i43@pure_quanta.q_res(chips)',
 P_PATH='@s9s_mb_2u_lib.s9s_mb_2u(sch_1):page290_i43@pure_quanta.q_res(chips)',
 PATH='I43',
 DRAWING='@S9S_MB_2U_LIB.S9S_MB_2U(SCH_1):PAGE276',
 PHYS_PAGE='290',
 XY='(-3100,3575)',
 ROT='0',
 VER='1',
 PACK_TYPE='0402LF',
 LOCATION='PR1334',
 CDS_LIB='pure_quanta',
 CDS_PART_NAME='Q_RES_0402LF-0,5%,1/16W,CHIP,CA',
 WATTAGE='1/16W',
 TOLERANCE='5%',
 MATERIAL='CHIP',
 VALUE='0',
 PRIM_FILE='./archive_libs/logical/q_res/chips/chips.prt';

PART_NAME
 PR1335 'Q_RES_0402LF-0,5%,1/16W,CHIP,CA':;

SECTION_NUMBER 1
 '@S9S_MB_2U_LIB.S9S_MB_2U(SCH_1):PAGE267_I5@PURE_QUANTA.Q_RES(CHIPS)':
 C_PATH='@s9s_mb_2u_lib.s9s_mb_2u(sch_1):page267_i5@pure_quanta.q_res(chips)',
 P_PATH='@s9s_mb_2u_lib.s9s_mb_2u(sch_1):page281_i5@pure_quanta.q_res(chips)',
 PATH='I5',
 DRAWING='@S9S_MB_2U_LIB.S9S_MB_2U(SCH_1):PAGE267',
 PHYS_PAGE='281',
 XY='(-10850,2975)',
 ROT='0',
 VER='2',
 PACK_TYPE='0402LF',
 LOCATION='PR1335',
 CDS_LIB='pure_quanta',
 CDS_PART_NAME='Q_RES_0402LF-0,5%,1/16W,CHIP,CA',
 WATTAGE='1/16W',
 TOLERANCE='5%',
 MATERIAL='CHIP',
 VALUE='0',
 PRIM_FILE='./archive_libs/logical/q_res/chips/chips.prt';

PART_NAME
 PR1336 'Q_RES_0402LF-9.76K,1%,1/16W,CHA':;

SECTION_NUMBER 1
 '@S9S_MB_2U_LIB.S9S_MB_2U(SCH_1):PAGE267_I15@PURE_QUANTA.Q_RES(CHIPS)':
 C_PATH='@s9s_mb_2u_lib.s9s_mb_2u(sch_1):page267_i15@pure_quanta.q_res(chips)',
 P_PATH='@s9s_mb_2u_lib.s9s_mb_2u(sch_1):page281_i15@pure_quanta.q_res(chips)',
 PATH='I15',
 DRAWING='@S9S_MB_2U_LIB.S9S_MB_2U(SCH_1):PAGE267',
 PHYS_PAGE='281',
 XY='(-9775,2525)',
 ROT='0',
 VER='2',
 PACK_TYPE='0402LF',
 LOCATION='PR1336',
 CDS_LIB='pure_quanta',
 CDS_PART_NAME='Q_RES_0402LF-9.76K,1%,1/16W,CHA',
 WATTAGE='1/16W',
 TOLERANCE='1%',
 MATERIAL='CHIP',
 VALUE='9.76K',
 PRIM_FILE='./archive_libs/logical/q_res/chips/chips.prt';

PART_NAME
 PR1337 'Q_RES_0402LF-38.3K,0.1%,1/16W,A':;

SECTION_NUMBER 1
 '@S9S_MB_2U_LIB.S9S_MB_2U(SCH_1):PAGE267_I36@PURE_QUANTA.Q_RES(CHIPS)':
 C_PATH='@s9s_mb_2u_lib.s9s_mb_2u(sch_1):page267_i36@pure_quanta.q_res(chips)',
 P_PATH='@s9s_mb_2u_lib.s9s_mb_2u(sch_1):page281_i36@pure_quanta.q_res(chips)',
 PATH='I36',
 DRAWING='@S9S_MB_2U_LIB.S9S_MB_2U(SCH_1):PAGE267',
 PHYS_PAGE='281',
 XY='(-6400,2950)',
 ROT='0',
 VER='1',
 PACK_TYPE='0402LF',
 LOCATION='PR1337',
 CDS_LIB='pure_quanta',
 CDS_PART_NAME='Q_RES_0402LF-38.3K,0.1%,1/16W,A',
 WATTAGE='1/16W',
 TOLERANCE='0.1%',
 MATERIAL='CHIP',
 VALUE='38.3K',
 PRIM_FILE='./archive_libs/logical/q_res/chips/chips.prt';

PART_NAME
 PR1338 'Q_RES_0402LF-0,5%,1/16W,CHIP,CA':;

SECTION_NUMBER 1
 '@S9S_MB_2U_LIB.S9S_MB_2U(SCH_1):PAGE285_I3@PURE_QUANTA.Q_RES(CHIPS)':
 C_PATH='@s9s_mb_2u_lib.s9s_mb_2u(sch_1):page285_i3@pure_quanta.q_res(chips)',
 P_PATH='@s9s_mb_2u_lib.s9s_mb_2u(sch_1):page299_i3@pure_quanta.q_res(chips)',
 PATH='I3',
 DRAWING='@S9S_MB_2U_LIB.S9S_MB_2U(SCH_1):PAGE285',
 PHYS_PAGE='299',
 XY='(-10525,2650)',
 ROT='0',
 VER='2',
 PACK_TYPE='0402LF',
 LOCATION='PR1338',
 CDS_LIB='pure_quanta',
 CDS_PART_NAME='Q_RES_0402LF-0,5%,1/16W,CHIP,CA',
 WATTAGE='1/16W',
 TOLERANCE='5%',
 MATERIAL='CHIP',
 VALUE='0',
 PRIM_FILE='./archive_libs/logical/q_res/chips/chips.prt';

PART_NAME
 PR1339 'Q_RES_0402LF-9.76K,1%,1/16W,CHA':;

SECTION_NUMBER 1
 '@S9S_MB_2U_LIB.S9S_MB_2U(SCH_1):PAGE285_I10@PURE_QUANTA.Q_RES(CHIPS)':
 C_PATH='@s9s_mb_2u_lib.s9s_mb_2u(sch_1):page285_i10@pure_quanta.q_res(chips)',
 P_PATH='@s9s_mb_2u_lib.s9s_mb_2u(sch_1):page299_i10@pure_quanta.q_res(chips)',
 PATH='I10',
 DRAWING='@S9S_MB_2U_LIB.S9S_MB_2U(SCH_1):PAGE285',
 PHYS_PAGE='299',
 XY='(-9175,2075)',
 ROT='0',
 VER='2',
 PACK_TYPE='0402LF',
 LOCATION='PR1339',
 CDS_LIB='pure_quanta',
 CDS_PART_NAME='Q_RES_0402LF-9.76K,1%,1/16W,CHA',
 WATTAGE='1/16W',
 TOLERANCE='1%',
 MATERIAL='CHIP',
 VALUE='9.76K',
 PRIM_FILE='./archive_libs/logical/q_res/chips/chips.prt';

PART_NAME
 PR1340 'Q_RES_0402LF-38.3K,0.1%,1/16W,A':;

SECTION_NUMBER 1
 '@S9S_MB_2U_LIB.S9S_MB_2U(SCH_1):PAGE285_I34@PURE_QUANTA.Q_RES(CHIPS)':
 C_PATH='@s9s_mb_2u_lib.s9s_mb_2u(sch_1):page285_i34@pure_quanta.q_res(chips)',
 P_PATH='@s9s_mb_2u_lib.s9s_mb_2u(sch_1):page299_i34@pure_quanta.q_res(chips)',
 PATH='I34',
 DRAWING='@S9S_MB_2U_LIB.S9S_MB_2U(SCH_1):PAGE285',
 PHYS_PAGE='299',
 XY='(-5700,2425)',
 ROT='0',
 VER='1',
 PACK_TYPE='0402LF',
 LOCATION='PR1340',
 CDS_LIB='pure_quanta',
 CDS_PART_NAME='Q_RES_0402LF-38.3K,0.1%,1/16W,A',
 WATTAGE='1/16W',
 TOLERANCE='0.1%',
 MATERIAL='CHIP',
 VALUE='38.3K',
 PRIM_FILE='./archive_libs/logical/q_res/chips/chips.prt';

PART_NAME
 PR1380 'Q_RES_0402LF-49.9,1%,1/16W,CHIA':;

SECTION_NUMBER 1
 '@S9S_MB_2U_LIB.S9S_MB_2U(SCH_1):PAGE264_I11@PURE_QUANTA.Q_RES(CHIPS)':
 C_PATH='@s9s_mb_2u_lib.s9s_mb_2u(sch_1):page264_i11@pure_quanta.q_res(chips)',
 P_PATH='@s9s_mb_2u_lib.s9s_mb_2u(sch_1):page278_i11@pure_quanta.q_res(chips)',
 PATH='I11',
 DRAWING='@S9S_MB_2U_LIB.S9S_MB_2U(SCH_1):PAGE264',
 PHYS_PAGE='278',
 XY='(-9775,3600)',
 ROT='0',
 VER='1',
 PACK_TYPE='0402LF',
 LOCATION='PR1380',
 CDS_LIB='pure_quanta',
 CDS_PART_NAME='Q_RES_0402LF-49.9,1%,1/16W,CHIA',
 WATTAGE='1/16W',
 TOLERANCE='1%',
 MATERIAL='CHIP',
 VALUE='49.9',
 PRIM_FILE='./archive_libs/logical/q_res/chips/chips.prt';

PART_NAME
 PR1390 'Q_RES_0402LF-49.9,1%,1/16W,CHIA':;

SECTION_NUMBER 1
 '@S9S_MB_2U_LIB.S9S_MB_2U(SCH_1):PAGE264_I10@PURE_QUANTA.Q_RES(CHIPS)':
 C_PATH='@s9s_mb_2u_lib.s9s_mb_2u(sch_1):page264_i10@pure_quanta.q_res(chips)',
 P_PATH='@s9s_mb_2u_lib.s9s_mb_2u(sch_1):page278_i10@pure_quanta.q_res(chips)',
 PATH='I10',
 DRAWING='@S9S_MB_2U_LIB.S9S_MB_2U(SCH_1):PAGE264',
 PHYS_PAGE='278',
 XY='(-9775,3500)',
 ROT='0',
 VER='1',
 PACK_TYPE='0402LF',
 LOCATION='PR1390',
 CDS_LIB='pure_quanta',
 CDS_PART_NAME='Q_RES_0402LF-49.9,1%,1/16W,CHIA',
 WATTAGE='1/16W',
 TOLERANCE='1%',
 MATERIAL='CHIP',
 VALUE='49.9',
 PRIM_FILE='./archive_libs/logical/q_res/chips/chips.prt';

PART_NAME
 PR1400 'Q_RES_0402LF-49.9,1%,1/16W,CHIA':;

SECTION_NUMBER 1
 '@S9S_MB_2U_LIB.S9S_MB_2U(SCH_1):PAGE282_I9@PURE_QUANTA.Q_RES(CHIPS)':
 C_PATH='@s9s_mb_2u_lib.s9s_mb_2u(sch_1):page282_i9@pure_quanta.q_res(chips)',
 P_PATH='@s9s_mb_2u_lib.s9s_mb_2u(sch_1):page296_i9@pure_quanta.q_res(chips)',
 PATH='I9',
 DRAWING='@S9S_MB_2U_LIB.S9S_MB_2U(SCH_1):PAGE282',
 PHYS_PAGE='296',
 XY='(-5400,100)',
 ROT='0',
 VER='1',
 PACK_TYPE='0402LF',
 LOCATION='PR1400',
 CDS_LIB='pure_quanta',
 CDS_PART_NAME='Q_RES_0402LF-49.9,1%,1/16W,CHIA',
 WATTAGE='1/16W',
 TOLERANCE='1%',
 MATERIAL='CHIP',
 VALUE='49.9',
 PRIM_FILE='./archive_libs/logical/q_res/chips/chips.prt';

PART_NAME
 PR1410 'Q_RES_0402LF-49.9,1%,1/16W,CHIA':;

SECTION_NUMBER 1
 '@S9S_MB_2U_LIB.S9S_MB_2U(SCH_1):PAGE282_I10@PURE_QUANTA.Q_RES(CHIPS)':
 C_PATH='@s9s_mb_2u_lib.s9s_mb_2u(sch_1):page282_i10@pure_quanta.q_res(chips)',
 P_PATH='@s9s_mb_2u_lib.s9s_mb_2u(sch_1):page296_i10@pure_quanta.q_res(chips)',
 PATH='I10',
 DRAWING='@S9S_MB_2U_LIB.S9S_MB_2U(SCH_1):PAGE282',
 PHYS_PAGE='296',
 XY='(-5400,0)',
 ROT='0',
 VER='1',
 PACK_TYPE='0402LF',
 LOCATION='PR1410',
 CDS_LIB='pure_quanta',
 CDS_PART_NAME='Q_RES_0402LF-49.9,1%,1/16W,CHIA',
 WATTAGE='1/16W',
 TOLERANCE='1%',
 MATERIAL='CHIP',
 VALUE='49.9',
 PRIM_FILE='./archive_libs/logical/q_res/chips/chips.prt';

PART_NAME
 PR1647 'Q_RES_0402LF-10K,1%,1/16W,EMPTA':;

SECTION_NUMBER 1
 '@S9S_MB_2U_LIB.S9S_MB_2U(SCH_1):PAGE248_I26@PURE_QUANTA.Q_RES(CHIPS)':
 C_PATH='@s9s_mb_2u_lib.s9s_mb_2u(sch_1):page248_i26@pure_quanta.q_res(chips)',
 P_PATH='@s9s_mb_2u_lib.s9s_mb_2u(sch_1):page262_i26@pure_quanta.q_res(chips)',
 PATH='I26',
 DRAWING='@S9S_MB_2U_LIB.S9S_MB_2U(SCH_1):PAGE248',
 PHYS_PAGE='262',
 XY='(-2950,-75)',
 ROT='0',
 VER='1',
 PACK_TYPE='0402LF',
 LOCATION='PR1647',
 CDS_LIB='pure_quanta',
 CDS_PART_NAME='Q_RES_0402LF-10K,1%,1/16W,EMPTA',
 WATTAGE='1/16W',
 TOLERANCE='1%',
 MATERIAL='EMPTY',
 VALUE='10K',
 PRIM_FILE='./archive_libs/logical/q_res/chips/chips.prt';

PART_NAME
 PR1649 'Q_RES_0402LF-2K,1%,1/16W,CHIP,A':;

SECTION_NUMBER 1
 '@S9S_MB_2U_LIB.S9S_MB_2U(SCH_1):PAGE248_I9@PURE_QUANTA.Q_RES(CHIPS)':
 C_PATH='@s9s_mb_2u_lib.s9s_mb_2u(sch_1):page248_i9@pure_quanta.q_res(chips)',
 P_PATH='@s9s_mb_2u_lib.s9s_mb_2u(sch_1):page262_i9@pure_quanta.q_res(chips)',
 PATH='I9',
 DRAWING='@S9S_MB_2U_LIB.S9S_MB_2U(SCH_1):PAGE248',
 PHYS_PAGE='262',
 XY='(-2350,-575)',
 ROT='0',
 VER='2',
 PACK_TYPE='0402LF',
 LOCATION='PR1649',
 CDS_LIB='pure_quanta',
 CDS_PART_NAME='Q_RES_0402LF-2K,1%,1/16W,CHIP,A',
 WATTAGE='1/16W',
 TOLERANCE='1%',
 MATERIAL='CHIP',
 VALUE='2K',
 PRIM_FILE='./archive_libs/logical/q_res/chips/chips.prt';

PART_NAME
 PR1653 'Q_RES_0402LF-470,1%,1/16W,CHIPA':;

SECTION_NUMBER 1
 '@S9S_MB_2U_LIB.S9S_MB_2U(SCH_1):PAGE249_I42@PURE_QUANTA.Q_RES(CHIPS)':
 C_PATH='@s9s_mb_2u_lib.s9s_mb_2u(sch_1):page249_i42@pure_quanta.q_res(chips)',
 P_PATH='@s9s_mb_2u_lib.s9s_mb_2u(sch_1):page263_i42@pure_quanta.q_res(chips)',
 PATH='I42',
 DRAWING='@S9S_MB_2U_LIB.S9S_MB_2U(SCH_1):PAGE249',
 PHYS_PAGE='263',
 XY='(1375,6025)',
 ROT='0',
 VER='2',
 PACK_TYPE='0402LF',
 LOCATION='PR1653',
 CDS_LIB='pure_quanta',
 CDS_PART_NAME='Q_RES_0402LF-470,1%,1/16W,CHIPA',
 WATTAGE='1/16W',
 TOLERANCE='1%',
 MATERIAL='CHIP',
 VALUE='470',
 PRIM_FILE='./archive_libs/logical/q_res/chips/chips.prt';

PART_NAME
 PR1707 'Q_RES_0402LF-8.87K,1%,1/16W,EMA':;

SECTION_NUMBER 1
 '@S9S_MB_2U_LIB.S9S_MB_2U(SCH_1):PAGE261_I2@PURE_QUANTA.Q_RES(CHIPS)':
 C_PATH='@s9s_mb_2u_lib.s9s_mb_2u(sch_1):page261_i2@pure_quanta.q_res(chips)',
 P_PATH='@s9s_mb_2u_lib.s9s_mb_2u(sch_1):page275_i2@pure_quanta.q_res(chips)',
 PATH='I2',
 DRAWING='@S9S_MB_2U_LIB.S9S_MB_2U(SCH_1):PAGE261',
 PHYS_PAGE='275',
 XY='(-10900,1400)',
 ROT='2',
 VER='2',
 PACK_TYPE='0402LF',
 LOCATION='PR1707',
 CDS_LIB='pure_quanta',
 CDS_PART_NAME='Q_RES_0402LF-8.87K,1%,1/16W,EMA',
 WATTAGE='1/16W',
 TOLERANCE='1%',
 MATERIAL='EMPTY',
 VALUE='8.87K',
 PRIM_FILE='./archive_libs/logical/q_res/chips/chips.prt';

PART_NAME
 PR1708 'Q_RES_0402LF-8.87K,1%,1/16W,EMA':;

SECTION_NUMBER 1
 '@S9S_MB_2U_LIB.S9S_MB_2U(SCH_1):PAGE261_I5@PURE_QUANTA.Q_RES(CHIPS)':
 C_PATH='@s9s_mb_2u_lib.s9s_mb_2u(sch_1):page261_i5@pure_quanta.q_res(chips)',
 P_PATH='@s9s_mb_2u_lib.s9s_mb_2u(sch_1):page275_i5@pure_quanta.q_res(chips)',
 PATH='I5',
 DRAWING='@S9S_MB_2U_LIB.S9S_MB_2U(SCH_1):PAGE261',
 PHYS_PAGE='275',
 XY='(-10875,4200)',
 ROT='2',
 VER='2',
 PACK_TYPE='0402LF',
 LOCATION='PR1708',
 CDS_LIB='pure_quanta',
 CDS_PART_NAME='Q_RES_0402LF-8.87K,1%,1/16W,EMA',
 WATTAGE='1/16W',
 TOLERANCE='1%',
 MATERIAL='EMPTY',
 VALUE='8.87K',
 PRIM_FILE='./archive_libs/logical/q_res/chips/chips.prt';

PART_NAME
 PR1709 'Q_RES_0402LF-8.87K,1%,1/16W,EMA':;

SECTION_NUMBER 1
 '@S9S_MB_2U_LIB.S9S_MB_2U(SCH_1):PAGE262_I2@PURE_QUANTA.Q_RES(CHIPS)':
 C_PATH='@s9s_mb_2u_lib.s9s_mb_2u(sch_1):page262_i2@pure_quanta.q_res(chips)',
 P_PATH='@s9s_mb_2u_lib.s9s_mb_2u(sch_1):page276_i2@pure_quanta.q_res(chips)',
 PATH='I2',
 DRAWING='@S9S_MB_2U_LIB.S9S_MB_2U(SCH_1):PAGE262',
 PHYS_PAGE='276',
 XY='(-10275,2975)',
 ROT='2',
 VER='2',
 PACK_TYPE='0402LF',
 LOCATION='PR1709',
 CDS_LIB='pure_quanta',
 CDS_PART_NAME='Q_RES_0402LF-8.87K,1%,1/16W,EMA',
 WATTAGE='1/16W',
 TOLERANCE='1%',
 MATERIAL='EMPTY',
 VALUE='8.87K',
 PRIM_FILE='./archive_libs/logical/q_res/chips/chips.prt';

PART_NAME
 PR1726 'Q_RES_0402LF-8.87K,1%,1/16W,EMA':;

SECTION_NUMBER 1
 '@S9S_MB_2U_LIB.S9S_MB_2U(SCH_1):PAGE279_I16@PURE_QUANTA.Q_RES(CHIPS)':
 C_PATH='@s9s_mb_2u_lib.s9s_mb_2u(sch_1):page279_i16@pure_quanta.q_res(chips)',
 P_PATH='@s9s_mb_2u_lib.s9s_mb_2u(sch_1):page293_i16@pure_quanta.q_res(chips)',
 PATH='I16',
 DRAWING='@S9S_MB_2U_LIB.S9S_MB_2U(SCH_1):PAGE279',
 PHYS_PAGE='293',
 XY='(-9000,10650)',
 ROT='2',
 VER='2',
 PACK_TYPE='0402LF',
 LOCATION='PR1726',
 CDS_LIB='pure_quanta',
 CDS_PART_NAME='Q_RES_0402LF-8.87K,1%,1/16W,EMA',
 WATTAGE='1/16W',
 TOLERANCE='1%',
 MATERIAL='EMPTY',
 VALUE='8.87K',
 PRIM_FILE='./archive_libs/logical/q_res/chips/chips.prt';

PART_NAME
 PR1727 'Q_RES_0402LF-8.87K,1%,1/16W,EMA':;

SECTION_NUMBER 1
 '@S9S_MB_2U_LIB.S9S_MB_2U(SCH_1):PAGE279_I3@PURE_QUANTA.Q_RES(CHIPS)':
 C_PATH='@s9s_mb_2u_lib.s9s_mb_2u(sch_1):page279_i3@pure_quanta.q_res(chips)',
 P_PATH='@s9s_mb_2u_lib.s9s_mb_2u(sch_1):page293_i3@pure_quanta.q_res(chips)',
 PATH='I3',
 DRAWING='@S9S_MB_2U_LIB.S9S_MB_2U(SCH_1):PAGE279',
 PHYS_PAGE='293',
 XY='(-9000,7850)',
 ROT='2',
 VER='2',
 PACK_TYPE='0402LF',
 LOCATION='PR1727',
 CDS_LIB='pure_quanta',
 CDS_PART_NAME='Q_RES_0402LF-8.87K,1%,1/16W,EMA',
 WATTAGE='1/16W',
 TOLERANCE='1%',
 MATERIAL='EMPTY',
 VALUE='8.87K',
 PRIM_FILE='./archive_libs/logical/q_res/chips/chips.prt';

PART_NAME
 PR1728 'Q_RES_0402LF-8.87K,1%,1/16W,EMA':;

SECTION_NUMBER 1
 '@S9S_MB_2U_LIB.S9S_MB_2U(SCH_1):PAGE280_I1@PURE_QUANTA.Q_RES(CHIPS)':
 C_PATH='@s9s_mb_2u_lib.s9s_mb_2u(sch_1):page280_i1@pure_quanta.q_res(chips)',
 P_PATH='@s9s_mb_2u_lib.s9s_mb_2u(sch_1):page294_i1@pure_quanta.q_res(chips)',
 PATH='I1',
 DRAWING='@S9S_MB_2U_LIB.S9S_MB_2U(SCH_1):PAGE280',
 PHYS_PAGE='294',
 XY='(-6775,8600)',
 ROT='2',
 VER='2',
 PACK_TYPE='0402LF',
 LOCATION='PR1728',
 CDS_LIB='pure_quanta',
 CDS_PART_NAME='Q_RES_0402LF-8.87K,1%,1/16W,EMA',
 WATTAGE='1/16W',
 TOLERANCE='1%',
 MATERIAL='EMPTY',
 VALUE='8.87K',
 PRIM_FILE='./archive_libs/logical/q_res/chips/chips.prt';

PART_NAME
 PR1746 'Q_RES_0402LF-8.87K,1%,1/16W,EMA':;

SECTION_NUMBER 1
 '@S9S_MB_2U_LIB.S9S_MB_2U(SCH_1):PAGE283_I3@PURE_QUANTA.Q_RES(CHIPS)':
 C_PATH='@s9s_mb_2u_lib.s9s_mb_2u(sch_1):page283_i3@pure_quanta.q_res(chips)',
 P_PATH='@s9s_mb_2u_lib.s9s_mb_2u(sch_1):page297_i3@pure_quanta.q_res(chips)',
 PATH='I3',
 DRAWING='@S9S_MB_2U_LIB.S9S_MB_2U(SCH_1):PAGE283',
 PHYS_PAGE='297',
 XY='(-8650,3050)',
 ROT='2',
 VER='2',
 PACK_TYPE='0402LF',
 LOCATION='PR1746',
 CDS_LIB='pure_quanta',
 CDS_PART_NAME='Q_RES_0402LF-8.87K,1%,1/16W,EMA',
 WATTAGE='1/16W',
 TOLERANCE='1%',
 MATERIAL='EMPTY',
 VALUE='8.87K',
 PRIM_FILE='./archive_libs/logical/q_res/chips/chips.prt';

PART_NAME
 PR1766 'Q_RES_0402LF-3.3,1%,1/16W,CHIPA':;

SECTION_NUMBER 1
 '@S9S_MB_2U_LIB.S9S_MB_2U(SCH_1):PAGE271_I20@PURE_QUANTA.Q_RES(CHIPS)':
 C_PATH='@s9s_mb_2u_lib.s9s_mb_2u(sch_1):page271_i20@pure_quanta.q_res(chips)',
 P_PATH='@s9s_mb_2u_lib.s9s_mb_2u(sch_1):page285_i20@pure_quanta.q_res(chips)',
 PATH='I20',
 DRAWING='@S9S_MB_2U_LIB.S9S_MB_2U(SCH_1):PAGE271',
 PHYS_PAGE='285',
 XY='(-875,-1250)',
 ROT='0',
 VER='1',
 PACK_TYPE='0402LF',
 LOCATION='PR1766',
 CDS_LIB='pure_quanta',
 CDS_PART_NAME='Q_RES_0402LF-3.3,1%,1/16W,CHIPA',
 WATTAGE='1/16W',
 TOLERANCE='1%',
 MATERIAL='CHIP',
 VALUE='3.3',
 PRIM_FILE='./archive_libs/logical/q_res/chips/chips.prt';

PART_NAME
 PR1767 'Q_RES_0402LF-3.3,1%,1/16W,CHIPA':;

SECTION_NUMBER 1
 '@S9S_MB_2U_LIB.S9S_MB_2U(SCH_1):PAGE271_I46@PURE_QUANTA.Q_RES(CHIPS)':
 C_PATH='@s9s_mb_2u_lib.s9s_mb_2u(sch_1):page271_i46@pure_quanta.q_res(chips)',
 P_PATH='@s9s_mb_2u_lib.s9s_mb_2u(sch_1):page285_i46@pure_quanta.q_res(chips)',
 PATH='I46',
 DRAWING='@S9S_MB_2U_LIB.S9S_MB_2U(SCH_1):PAGE271',
 PHYS_PAGE='285',
 XY='(-850,1575)',
 ROT='0',
 VER='1',
 PACK_TYPE='0402LF',
 LOCATION='PR1767',
 CDS_LIB='pure_quanta',
 CDS_PART_NAME='Q_RES_0402LF-3.3,1%,1/16W,CHIPA',
 WATTAGE='1/16W',
 TOLERANCE='1%',
 MATERIAL='CHIP',
 VALUE='3.3',
 PRIM_FILE='./archive_libs/logical/q_res/chips/chips.prt';

PART_NAME
 PR1768 'Q_RES_0402LF-3.3,1%,1/16W,CHIPA':;

SECTION_NUMBER 1
 '@S9S_MB_2U_LIB.S9S_MB_2U(SCH_1):PAGE254_I36@PURE_QUANTA.Q_RES(CHIPS)':
 C_PATH='@s9s_mb_2u_lib.s9s_mb_2u(sch_1):page254_i36@pure_quanta.q_res(chips)',
 P_PATH='@s9s_mb_2u_lib.s9s_mb_2u(sch_1):page268_i36@pure_quanta.q_res(chips)',
 PATH='I36',
 DRAWING='@S9S_MB_2U_LIB.S9S_MB_2U(SCH_1):PAGE254',
 PHYS_PAGE='268',
 XY='(5775,1950)',
 ROT='0',
 VER='1',
 PACK_TYPE='0402LF',
 LOCATION='PR1768',
 CDS_LIB='pure_quanta',
 CDS_PART_NAME='Q_RES_0402LF-3.3,1%,1/16W,CHIPA',
 WATTAGE='1/16W',
 TOLERANCE='1%',
 MATERIAL='CHIP',
 VALUE='3.3',
 PRIM_FILE='./archive_libs/logical/q_res/chips/chips.prt';

PART_NAME
 PR1769 'Q_RES_0402LF-3.3,1%,1/16W,CHIPA':;

SECTION_NUMBER 1
 '@S9S_MB_2U_LIB.S9S_MB_2U(SCH_1):PAGE254_I49@PURE_QUANTA.Q_RES(CHIPS)':
 C_PATH='@s9s_mb_2u_lib.s9s_mb_2u(sch_1):page254_i49@pure_quanta.q_res(chips)',
 P_PATH='@s9s_mb_2u_lib.s9s_mb_2u(sch_1):page268_i49@pure_quanta.q_res(chips)',
 PATH='I49',
 DRAWING='@S9S_MB_2U_LIB.S9S_MB_2U(SCH_1):PAGE254',
 PHYS_PAGE='268',
 XY='(5800,4775)',
 ROT='0',
 VER='1',
 PACK_TYPE='0402LF',
 LOCATION='PR1769',
 CDS_LIB='pure_quanta',
 CDS_PART_NAME='Q_RES_0402LF-3.3,1%,1/16W,CHIPA',
 WATTAGE='1/16W',
 TOLERANCE='1%',
 MATERIAL='CHIP',
 VALUE='3.3',
 PRIM_FILE='./archive_libs/logical/q_res/chips/chips.prt';

PART_NAME
 PR1770 'Q_RES_0402LF-3.3,1%,1/16W,CHIPA':;

SECTION_NUMBER 1
 '@S9S_MB_2U_LIB.S9S_MB_2U(SCH_1):PAGE255_I35@PURE_QUANTA.Q_RES(CHIPS)':
 C_PATH='@s9s_mb_2u_lib.s9s_mb_2u(sch_1):page255_i35@pure_quanta.q_res(chips)',
 P_PATH='@s9s_mb_2u_lib.s9s_mb_2u(sch_1):page269_i35@pure_quanta.q_res(chips)',
 PATH='I35',
 DRAWING='@S9S_MB_2U_LIB.S9S_MB_2U(SCH_1):PAGE255',
 PHYS_PAGE='269',
 XY='(4850,2350)',
 ROT='0',
 VER='1',
 PACK_TYPE='0402LF',
 LOCATION='PR1770',
 CDS_LIB='pure_quanta',
 CDS_PART_NAME='Q_RES_0402LF-3.3,1%,1/16W,CHIPA',
 WATTAGE='1/16W',
 TOLERANCE='1%',
 MATERIAL='CHIP',
 VALUE='3.3',
 PRIM_FILE='./archive_libs/logical/q_res/chips/chips.prt';

PART_NAME
 PR1771 'Q_RES_0402LF-3.3,1%,1/16W,CHIPA':;

SECTION_NUMBER 1
 '@S9S_MB_2U_LIB.S9S_MB_2U(SCH_1):PAGE255_I49@PURE_QUANTA.Q_RES(CHIPS)':
 C_PATH='@s9s_mb_2u_lib.s9s_mb_2u(sch_1):page255_i49@pure_quanta.q_res(chips)',
 P_PATH='@s9s_mb_2u_lib.s9s_mb_2u(sch_1):page269_i49@pure_quanta.q_res(chips)',
 PATH='I49',
 DRAWING='@S9S_MB_2U_LIB.S9S_MB_2U(SCH_1):PAGE255',
 PHYS_PAGE='269',
 XY='(4875,5175)',
 ROT='0',
 VER='1',
 PACK_TYPE='0402LF',
 LOCATION='PR1771',
 CDS_LIB='pure_quanta',
 CDS_PART_NAME='Q_RES_0402LF-3.3,1%,1/16W,CHIPA',
 WATTAGE='1/16W',
 TOLERANCE='1%',
 MATERIAL='CHIP',
 VALUE='3.3',
 PRIM_FILE='./archive_libs/logical/q_res/chips/chips.prt';

PART_NAME
 PR1772 'Q_RES_0402LF-3.3,1%,1/16W,CHIPA':;

SECTION_NUMBER 1
 '@S9S_MB_2U_LIB.S9S_MB_2U(SCH_1):PAGE256_I19@PURE_QUANTA.Q_RES(CHIPS)':
 C_PATH='@s9s_mb_2u_lib.s9s_mb_2u(sch_1):page256_i19@pure_quanta.q_res(chips)',
 P_PATH='@s9s_mb_2u_lib.s9s_mb_2u(sch_1):page270_i19@pure_quanta.q_res(chips)',
 PATH='I19',
 DRAWING='@S9S_MB_2U_LIB.S9S_MB_2U(SCH_1):PAGE256',
 PHYS_PAGE='270',
 XY='(-4375,-4950)',
 ROT='0',
 VER='1',
 PACK_TYPE='0402LF',
 LOCATION='PR1772',
 CDS_LIB='pure_quanta',
 CDS_PART_NAME='Q_RES_0402LF-3.3,1%,1/16W,CHIPA',
 WATTAGE='1/16W',
 TOLERANCE='1%',
 MATERIAL='CHIP',
 VALUE='3.3',
 PRIM_FILE='./archive_libs/logical/q_res/chips/chips.prt';

PART_NAME
 PR1773 'Q_RES_0402LF-3.3,1%,1/16W,CHIPA':;

SECTION_NUMBER 1
 '@S9S_MB_2U_LIB.S9S_MB_2U(SCH_1):PAGE256_I40@PURE_QUANTA.Q_RES(CHIPS)':
 C_PATH='@s9s_mb_2u_lib.s9s_mb_2u(sch_1):page256_i40@pure_quanta.q_res(chips)',
 P_PATH='@s9s_mb_2u_lib.s9s_mb_2u(sch_1):page270_i40@pure_quanta.q_res(chips)',
 PATH='I40',
 DRAWING='@S9S_MB_2U_LIB.S9S_MB_2U(SCH_1):PAGE256',
 PHYS_PAGE='270',
 XY='(-4350,-2125)',
 ROT='0',
 VER='1',
 PACK_TYPE='0402LF',
 LOCATION='PR1773',
 CDS_LIB='pure_quanta',
 CDS_PART_NAME='Q_RES_0402LF-3.3,1%,1/16W,CHIPA',
 WATTAGE='1/16W',
 TOLERANCE='1%',
 MATERIAL='CHIP',
 VALUE='3.3',
 PRIM_FILE='./archive_libs/logical/q_res/chips/chips.prt';

PART_NAME
 PR1774 'Q_RES_0402LF-3.3,1%,1/16W,CHIPA':;

SECTION_NUMBER 1
 '@S9S_MB_2U_LIB.S9S_MB_2U(SCH_1):PAGE261_I47@PURE_QUANTA.Q_RES(CHIPS)':
 C_PATH='@s9s_mb_2u_lib.s9s_mb_2u(sch_1):page261_i47@pure_quanta.q_res(chips)',
 P_PATH='@s9s_mb_2u_lib.s9s_mb_2u(sch_1):page275_i47@pure_quanta.q_res(chips)',
 PATH='I47',
 DRAWING='@S9S_MB_2U_LIB.S9S_MB_2U(SCH_1):PAGE261',
 PHYS_PAGE='275',
 XY='(-7525,5225)',
 ROT='0',
 VER='1',
 PACK_TYPE='0402LF',
 LOCATION='PR1774',
 CDS_LIB='pure_quanta',
 CDS_PART_NAME='Q_RES_0402LF-3.3,1%,1/16W,CHIPA',
 WATTAGE='1/16W',
 TOLERANCE='1%',
 MATERIAL='CHIP',
 VALUE='3.3',
 PRIM_FILE='./archive_libs/logical/q_res/chips/chips.prt';

PART_NAME
 PR1775 'Q_RES_0402LF-3.3,1%,1/16W,CHIPA':;

SECTION_NUMBER 1
 '@S9S_MB_2U_LIB.S9S_MB_2U(SCH_1):PAGE261_I34@PURE_QUANTA.Q_RES(CHIPS)':
 C_PATH='@s9s_mb_2u_lib.s9s_mb_2u(sch_1):page261_i34@pure_quanta.q_res(chips)',
 P_PATH='@s9s_mb_2u_lib.s9s_mb_2u(sch_1):page275_i34@pure_quanta.q_res(chips)',
 PATH='I34',
 DRAWING='@S9S_MB_2U_LIB.S9S_MB_2U(SCH_1):PAGE261',
 PHYS_PAGE='275',
 XY='(-7525,2425)',
 ROT='0',
 VER='1',
 PACK_TYPE='0402LF',
 LOCATION='PR1775',
 CDS_LIB='pure_quanta',
 CDS_PART_NAME='Q_RES_0402LF-3.3,1%,1/16W,CHIPA',
 WATTAGE='1/16W',
 TOLERANCE='1%',
 MATERIAL='CHIP',
 VALUE='3.3',
 PRIM_FILE='./archive_libs/logical/q_res/chips/chips.prt';

PART_NAME
 PR1776 'Q_RES_0402LF-0,5%,1/16W,CHIP,CA':;

SECTION_NUMBER 1
 '@S9S_MB_2U_LIB.S9S_MB_2U(SCH_1):PAGE261_I46@PURE_QUANTA.Q_RES(CHIPS)':
 C_PATH='@s9s_mb_2u_lib.s9s_mb_2u(sch_1):page261_i46@pure_quanta.q_res(chips)',
 P_PATH='@s9s_mb_2u_lib.s9s_mb_2u(sch_1):page275_i46@pure_quanta.q_res(chips)',
 PATH='I46',
 DRAWING='@S9S_MB_2U_LIB.S9S_MB_2U(SCH_1):PAGE261',
 PHYS_PAGE='275',
 XY='(-7325,4525)',
 ROT='0',
 VER='1',
 PACK_TYPE='0402LF',
 LOCATION='PR1776',
 CDS_LIB='pure_quanta',
 CDS_PART_NAME='Q_RES_0402LF-0,5%,1/16W,CHIP,CA',
 WATTAGE='1/16W',
 TOLERANCE='5%',
 MATERIAL='CHIP',
 VALUE='0',
 PRIM_FILE='./archive_libs/logical/q_res/chips/chips.prt';

PART_NAME
 PR1777 'Q_RES_0402LF-0,5%,1/16W,CHIP,CA':;

SECTION_NUMBER 1
 '@S9S_MB_2U_LIB.S9S_MB_2U(SCH_1):PAGE261_I31@PURE_QUANTA.Q_RES(CHIPS)':
 C_PATH='@s9s_mb_2u_lib.s9s_mb_2u(sch_1):page261_i31@pure_quanta.q_res(chips)',
 P_PATH='@s9s_mb_2u_lib.s9s_mb_2u(sch_1):page275_i31@pure_quanta.q_res(chips)',
 PATH='I31',
 DRAWING='@S9S_MB_2U_LIB.S9S_MB_2U(SCH_1):PAGE261',
 PHYS_PAGE='275',
 XY='(-7300,1725)',
 ROT='0',
 VER='1',
 PACK_TYPE='0402LF',
 LOCATION='PR1777',
 CDS_LIB='pure_quanta',
 CDS_PART_NAME='Q_RES_0402LF-0,5%,1/16W,CHIP,CA',
 WATTAGE='1/16W',
 TOLERANCE='5%',
 MATERIAL='CHIP',
 VALUE='0',
 PRIM_FILE='./archive_libs/logical/q_res/chips/chips.prt';

PART_NAME
 PR1778 'Q_RES_0402LF-3.3,1%,1/16W,CHIPA':;

SECTION_NUMBER 1
 '@S9S_MB_2U_LIB.S9S_MB_2U(SCH_1):PAGE262_I17@PURE_QUANTA.Q_RES(CHIPS)':
 C_PATH='@s9s_mb_2u_lib.s9s_mb_2u(sch_1):page262_i17@pure_quanta.q_res(chips)',
 P_PATH='@s9s_mb_2u_lib.s9s_mb_2u(sch_1):page276_i17@pure_quanta.q_res(chips)',
 PATH='I17',
 DRAWING='@S9S_MB_2U_LIB.S9S_MB_2U(SCH_1):PAGE262',
 PHYS_PAGE='276',
 XY='(-6750,4000)',
 ROT='0',
 VER='1',
 PACK_TYPE='0402LF',
 LOCATION='PR1778',
 CDS_LIB='pure_quanta',
 CDS_PART_NAME='Q_RES_0402LF-3.3,1%,1/16W,CHIPA',
 WATTAGE='1/16W',
 TOLERANCE='1%',
 MATERIAL='CHIP',
 VALUE='3.3',
 PRIM_FILE='./archive_libs/logical/q_res/chips/chips.prt';

PART_NAME
 PR1779 'Q_RES_0402LF-0,5%,1/16W,CHIP,CA':;

SECTION_NUMBER 1
 '@S9S_MB_2U_LIB.S9S_MB_2U(SCH_1):PAGE262_I16@PURE_QUANTA.Q_RES(CHIPS)':
 C_PATH='@s9s_mb_2u_lib.s9s_mb_2u(sch_1):page262_i16@pure_quanta.q_res(chips)',
 P_PATH='@s9s_mb_2u_lib.s9s_mb_2u(sch_1):page276_i16@pure_quanta.q_res(chips)',
 PATH='I16',
 DRAWING='@S9S_MB_2U_LIB.S9S_MB_2U(SCH_1):PAGE262',
 PHYS_PAGE='276',
 XY='(-6525,3250)',
 ROT='0',
 VER='1',
 PACK_TYPE='0402LF',
 LOCATION='PR1779',
 CDS_LIB='pure_quanta',
 CDS_PART_NAME='Q_RES_0402LF-0,5%,1/16W,CHIP,CA',
 WATTAGE='1/16W',
 TOLERANCE='5%',
 MATERIAL='CHIP',
 VALUE='0',
 PRIM_FILE='./archive_libs/logical/q_res/chips/chips.prt';

PART_NAME
 PR1780 'Q_RES_0402LF-3.3,1%,1/16W,CHIPA':;

SECTION_NUMBER 1
 '@S9S_MB_2U_LIB.S9S_MB_2U(SCH_1):PAGE257_I46@PURE_QUANTA.Q_RES(CHIPS)':
 C_PATH='@s9s_mb_2u_lib.s9s_mb_2u(sch_1):page257_i46@pure_quanta.q_res(chips)',
 P_PATH='@s9s_mb_2u_lib.s9s_mb_2u(sch_1):page271_i46@pure_quanta.q_res(chips)',
 PATH='I46',
 DRAWING='@S9S_MB_2U_LIB.S9S_MB_2U(SCH_1):PAGE257',
 PHYS_PAGE='271',
 XY='(-1225,5650)',
 ROT='0',
 VER='1',
 PACK_TYPE='0402LF',
 LOCATION='PR1780',
 CDS_LIB='pure_quanta',
 CDS_PART_NAME='Q_RES_0402LF-3.3,1%,1/16W,CHIPA',
 WATTAGE='1/16W',
 TOLERANCE='1%',
 MATERIAL='CHIP',
 VALUE='3.3',
 PRIM_FILE='./archive_libs/logical/q_res/chips/chips.prt';

PART_NAME
 PR1781 'Q_RES_0402LF-3.3,1%,1/16W,CHIPA':;

SECTION_NUMBER 1
 '@S9S_MB_2U_LIB.S9S_MB_2U(SCH_1):PAGE257_I30@PURE_QUANTA.Q_RES(CHIPS)':
 C_PATH='@s9s_mb_2u_lib.s9s_mb_2u(sch_1):page257_i30@pure_quanta.q_res(chips)',
 P_PATH='@s9s_mb_2u_lib.s9s_mb_2u(sch_1):page271_i30@pure_quanta.q_res(chips)',
 PATH='I30',
 DRAWING='@S9S_MB_2U_LIB.S9S_MB_2U(SCH_1):PAGE257',
 PHYS_PAGE='271',
 XY='(-1225,2850)',
 ROT='0',
 VER='1',
 PACK_TYPE='0402LF',
 LOCATION='PR1781',
 CDS_LIB='pure_quanta',
 CDS_PART_NAME='Q_RES_0402LF-3.3,1%,1/16W,CHIPA',
 WATTAGE='1/16W',
 TOLERANCE='1%',
 MATERIAL='CHIP',
 VALUE='3.3',
 PRIM_FILE='./archive_libs/logical/q_res/chips/chips.prt';

PART_NAME
 PR1782 'Q_RES_0402LF-3.3,1%,1/16W,CHIPA':;

SECTION_NUMBER 1
 '@S9S_MB_2U_LIB.S9S_MB_2U(SCH_1):PAGE258_I45@PURE_QUANTA.Q_RES(CHIPS)':
 C_PATH='@s9s_mb_2u_lib.s9s_mb_2u(sch_1):page258_i45@pure_quanta.q_res(chips)',
 P_PATH='@s9s_mb_2u_lib.s9s_mb_2u(sch_1):page272_i45@pure_quanta.q_res(chips)',
 PATH='I45',
 DRAWING='@S9S_MB_2U_LIB.S9S_MB_2U(SCH_1):PAGE258',
 PHYS_PAGE='272',
 XY='(-7675,5350)',
 ROT='0',
 VER='1',
 PACK_TYPE='0402LF',
 LOCATION='PR1782',
 CDS_LIB='pure_quanta',
 CDS_PART_NAME='Q_RES_0402LF-3.3,1%,1/16W,CHIPA',
 WATTAGE='1/16W',
 TOLERANCE='1%',
 MATERIAL='CHIP',
 VALUE='3.3',
 PRIM_FILE='./archive_libs/logical/q_res/chips/chips.prt';

PART_NAME
 PR1783 'Q_RES_0402LF-3.3,1%,1/16W,CHIPA':;

SECTION_NUMBER 1
 '@S9S_MB_2U_LIB.S9S_MB_2U(SCH_1):PAGE258_I33@PURE_QUANTA.Q_RES(CHIPS)':
 C_PATH='@s9s_mb_2u_lib.s9s_mb_2u(sch_1):page258_i33@pure_quanta.q_res(chips)',
 P_PATH='@s9s_mb_2u_lib.s9s_mb_2u(sch_1):page272_i33@pure_quanta.q_res(chips)',
 PATH='I33',
 DRAWING='@S9S_MB_2U_LIB.S9S_MB_2U(SCH_1):PAGE258',
 PHYS_PAGE='272',
 XY='(-7675,2550)',
 ROT='0',
 VER='1',
 PACK_TYPE='0402LF',
 LOCATION='PR1783',
 CDS_LIB='pure_quanta',
 CDS_PART_NAME='Q_RES_0402LF-3.3,1%,1/16W,CHIPA',
 WATTAGE='1/16W',
 TOLERANCE='1%',
 MATERIAL='CHIP',
 VALUE='3.3',
 PRIM_FILE='./archive_libs/logical/q_res/chips/chips.prt';

PART_NAME
 PR1784 'Q_RES_0402LF-3.3,1%,1/16W,CHIPA':;

SECTION_NUMBER 1
 '@S9S_MB_2U_LIB.S9S_MB_2U(SCH_1):PAGE265_I19@PURE_QUANTA.Q_RES(CHIPS)':
 C_PATH='@s9s_mb_2u_lib.s9s_mb_2u(sch_1):page265_i19@pure_quanta.q_res(chips)',
 P_PATH='@s9s_mb_2u_lib.s9s_mb_2u(sch_1):page279_i19@pure_quanta.q_res(chips)',
 PATH='I19',
 DRAWING='@S9S_MB_2U_LIB.S9S_MB_2U(SCH_1):PAGE265',
 PHYS_PAGE='279',
 XY='(-5450,2375)',
 ROT='0',
 VER='1',
 PACK_TYPE='0402LF',
 LOCATION='PR1784',
 CDS_LIB='pure_quanta',
 CDS_PART_NAME='Q_RES_0402LF-3.3,1%,1/16W,CHIPA',
 WATTAGE='1/16W',
 TOLERANCE='1%',
 MATERIAL='CHIP',
 VALUE='3.3',
 PRIM_FILE='./archive_libs/logical/q_res/chips/chips.prt';

PART_NAME
 PR1785 'Q_RES_0402LF-0,5%,1/16W,CHIP,CA':;

SECTION_NUMBER 1
 '@S9S_MB_2U_LIB.S9S_MB_2U(SCH_1):PAGE265_I17@PURE_QUANTA.Q_RES(CHIPS)':
 C_PATH='@s9s_mb_2u_lib.s9s_mb_2u(sch_1):page265_i17@pure_quanta.q_res(chips)',
 P_PATH='@s9s_mb_2u_lib.s9s_mb_2u(sch_1):page279_i17@pure_quanta.q_res(chips)',
 PATH='I17',
 DRAWING='@S9S_MB_2U_LIB.S9S_MB_2U(SCH_1):PAGE265',
 PHYS_PAGE='279',
 XY='(-5150,1675)',
 ROT='0',
 VER='1',
 PACK_TYPE='0402LF',
 LOCATION='PR1785',
 CDS_LIB='pure_quanta',
 CDS_PART_NAME='Q_RES_0402LF-0,5%,1/16W,CHIP,CA',
 WATTAGE='1/16W',
 TOLERANCE='5%',
 MATERIAL='CHIP',
 VALUE='0',
 PRIM_FILE='./archive_libs/logical/q_res/chips/chips.prt';

PART_NAME
 PR1786 'Q_RES_0402LF-3.3,1%,1/16W,CHIPA':;

SECTION_NUMBER 1
 '@S9S_MB_2U_LIB.S9S_MB_2U(SCH_1):PAGE253_I18@PURE_QUANTA.Q_RES(CHIPS)':
 C_PATH='@s9s_mb_2u_lib.s9s_mb_2u(sch_1):page253_i18@pure_quanta.q_res(chips)',
 P_PATH='@s9s_mb_2u_lib.s9s_mb_2u(sch_1):page267_i18@pure_quanta.q_res(chips)',
 PATH='I18',
 DRAWING='@S9S_MB_2U_LIB.S9S_MB_2U(SCH_1):PAGE253',
 PHYS_PAGE='267',
 XY='(-1025,-1675)',
 ROT='0',
 VER='1',
 PACK_TYPE='0402LF',
 LOCATION='PR1786',
 CDS_LIB='pure_quanta',
 CDS_PART_NAME='Q_RES_0402LF-3.3,1%,1/16W,CHIPA',
 WATTAGE='1/16W',
 TOLERANCE='1%',
 MATERIAL='CHIP',
 VALUE='3.3',
 PRIM_FILE='./archive_libs/logical/q_res/chips/chips.prt';

PART_NAME
 PR1787 'Q_RES_0402LF-3.3,1%,1/16W,CHIPA':;

SECTION_NUMBER 1
 '@S9S_MB_2U_LIB.S9S_MB_2U(SCH_1):PAGE253_I97@PURE_QUANTA.Q_RES(CHIPS)':
 C_PATH='@s9s_mb_2u_lib.s9s_mb_2u(sch_1):page253_i97@pure_quanta.q_res(chips)',
 P_PATH='@s9s_mb_2u_lib.s9s_mb_2u(sch_1):page267_i97@pure_quanta.q_res(chips)',
 PATH='I97',
 DRAWING='@S9S_MB_2U_LIB.S9S_MB_2U(SCH_1):PAGE253',
 PHYS_PAGE='267',
 XY='(-1000,1150)',
 ROT='0',
 VER='1',
 PACK_TYPE='0402LF',
 LOCATION='PR1787',
 CDS_LIB='pure_quanta',
 CDS_PART_NAME='Q_RES_0402LF-3.3,1%,1/16W,CHIPA',
 WATTAGE='1/16W',
 TOLERANCE='1%',
 MATERIAL='CHIP',
 VALUE='3.3',
 PRIM_FILE='./archive_libs/logical/q_res/chips/chips.prt';

PART_NAME
 PR1788 'Q_RES_0402LF-3.3,1%,1/16W,CHIPA':;

SECTION_NUMBER 1
 '@S9S_MB_2U_LIB.S9S_MB_2U(SCH_1):PAGE272_I34@PURE_QUANTA.Q_RES(CHIPS)':
 C_PATH='@s9s_mb_2u_lib.s9s_mb_2u(sch_1):page272_i34@pure_quanta.q_res(chips)',
 P_PATH='@s9s_mb_2u_lib.s9s_mb_2u(sch_1):page286_i34@pure_quanta.q_res(chips)',
 PATH='I34',
 DRAWING='@S9S_MB_2U_LIB.S9S_MB_2U(SCH_1):PAGE272',
 PHYS_PAGE='286',
 XY='(400,-1100)',
 ROT='0',
 VER='1',
 PACK_TYPE='0402LF',
 LOCATION='PR1788',
 CDS_LIB='pure_quanta',
 CDS_PART_NAME='Q_RES_0402LF-3.3,1%,1/16W,CHIPA',
 WATTAGE='1/16W',
 TOLERANCE='1%',
 MATERIAL='CHIP',
 VALUE='3.3',
 PRIM_FILE='./archive_libs/logical/q_res/chips/chips.prt';

PART_NAME
 PR1789 'Q_RES_0402LF-3.3,1%,1/16W,CHIPA':;

SECTION_NUMBER 1
 '@S9S_MB_2U_LIB.S9S_MB_2U(SCH_1):PAGE272_I46@PURE_QUANTA.Q_RES(CHIPS)':
 C_PATH='@s9s_mb_2u_lib.s9s_mb_2u(sch_1):page272_i46@pure_quanta.q_res(chips)',
 P_PATH='@s9s_mb_2u_lib.s9s_mb_2u(sch_1):page286_i46@pure_quanta.q_res(chips)',
 PATH='I46',
 DRAWING='@S9S_MB_2U_LIB.S9S_MB_2U(SCH_1):PAGE272',
 PHYS_PAGE='286',
 XY='(425,1725)',
 ROT='0',
 VER='1',
 PACK_TYPE='0402LF',
 LOCATION='PR1789',
 CDS_LIB='pure_quanta',
 CDS_PART_NAME='Q_RES_0402LF-3.3,1%,1/16W,CHIPA',
 WATTAGE='1/16W',
 TOLERANCE='1%',
 MATERIAL='CHIP',
 VALUE='3.3',
 PRIM_FILE='./archive_libs/logical/q_res/chips/chips.prt';

PART_NAME
 PR1790 'Q_RES_0402LF-3.3,1%,1/16W,CHIPA':;

SECTION_NUMBER 1
 '@S9S_MB_2U_LIB.S9S_MB_2U(SCH_1):PAGE273_I30@PURE_QUANTA.Q_RES(CHIPS)':
 C_PATH='@s9s_mb_2u_lib.s9s_mb_2u(sch_1):page273_i30@pure_quanta.q_res(chips)',
 P_PATH='@s9s_mb_2u_lib.s9s_mb_2u(sch_1):page287_i30@pure_quanta.q_res(chips)',
 PATH='I30',
 DRAWING='@S9S_MB_2U_LIB.S9S_MB_2U(SCH_1):PAGE273',
 PHYS_PAGE='287',
 XY='(6550,125)',
 ROT='0',
 VER='1',
 PACK_TYPE='0402LF',
 LOCATION='PR1790',
 CDS_LIB='pure_quanta',
 CDS_PART_NAME='Q_RES_0402LF-3.3,1%,1/16W,CHIPA',
 WATTAGE='1/16W',
 TOLERANCE='1%',
 MATERIAL='CHIP',
 VALUE='3.3',
 PRIM_FILE='./archive_libs/logical/q_res/chips/chips.prt';

PART_NAME
 PR1791 'Q_RES_0402LF-3.3,1%,1/16W,CHIPA':;

SECTION_NUMBER 1
 '@S9S_MB_2U_LIB.S9S_MB_2U(SCH_1):PAGE273_I44@PURE_QUANTA.Q_RES(CHIPS)':
 C_PATH='@s9s_mb_2u_lib.s9s_mb_2u(sch_1):page273_i44@pure_quanta.q_res(chips)',
 P_PATH='@s9s_mb_2u_lib.s9s_mb_2u(sch_1):page287_i44@pure_quanta.q_res(chips)',
 PATH='I44',
 DRAWING='@S9S_MB_2U_LIB.S9S_MB_2U(SCH_1):PAGE273',
 PHYS_PAGE='287',
 XY='(6575,2950)',
 ROT='0',
 VER='1',
 PACK_TYPE='0402LF',
 LOCATION='PR1791',
 CDS_LIB='pure_quanta',
 CDS_PART_NAME='Q_RES_0402LF-3.3,1%,1/16W,CHIPA',
 WATTAGE='1/16W',
 TOLERANCE='1%',
 MATERIAL='CHIP',
 VALUE='3.3',
 PRIM_FILE='./archive_libs/logical/q_res/chips/chips.prt';

PART_NAME
 PR1792 'Q_RES_0402LF-3.3,1%,1/16W,CHIPA':;

SECTION_NUMBER 1
 '@S9S_MB_2U_LIB.S9S_MB_2U(SCH_1):PAGE274_I26@PURE_QUANTA.Q_RES(CHIPS)':
 C_PATH='@s9s_mb_2u_lib.s9s_mb_2u(sch_1):page274_i26@pure_quanta.q_res(chips)',
 P_PATH='@s9s_mb_2u_lib.s9s_mb_2u(sch_1):page288_i26@pure_quanta.q_res(chips)',
 PATH='I26',
 DRAWING='@S9S_MB_2U_LIB.S9S_MB_2U(SCH_1):PAGE274',
 PHYS_PAGE='288',
 XY='(-4775,2150)',
 ROT='0',
 VER='1',
 PACK_TYPE='0402LF',
 LOCATION='PR1792',
 CDS_LIB='pure_quanta',
 CDS_PART_NAME='Q_RES_0402LF-3.3,1%,1/16W,CHIPA',
 WATTAGE='1/16W',
 TOLERANCE='1%',
 MATERIAL='CHIP',
 VALUE='3.3',
 PRIM_FILE='./archive_libs/logical/q_res/chips/chips.prt';

PART_NAME
 PR1793 'Q_RES_0402LF-3.3,1%,1/16W,CHIPA':;

SECTION_NUMBER 1
 '@S9S_MB_2U_LIB.S9S_MB_2U(SCH_1):PAGE274_I39@PURE_QUANTA.Q_RES(CHIPS)':
 C_PATH='@s9s_mb_2u_lib.s9s_mb_2u(sch_1):page274_i39@pure_quanta.q_res(chips)',
 P_PATH='@s9s_mb_2u_lib.s9s_mb_2u(sch_1):page288_i39@pure_quanta.q_res(chips)',
 PATH='I39',
 DRAWING='@S9S_MB_2U_LIB.S9S_MB_2U(SCH_1):PAGE274',
 PHYS_PAGE='288',
 XY='(-4750,4975)',
 ROT='0',
 VER='1',
 PACK_TYPE='0402LF',
 LOCATION='PR1793',
 CDS_LIB='pure_quanta',
 CDS_PART_NAME='Q_RES_0402LF-3.3,1%,1/16W,CHIPA',
 WATTAGE='1/16W',
 TOLERANCE='1%',
 MATERIAL='CHIP',
 VALUE='3.3',
 PRIM_FILE='./archive_libs/logical/q_res/chips/chips.prt';

PART_NAME
 PR1794 'Q_RES_0402LF-3.3,1%,1/16W,CHIPA':;

SECTION_NUMBER 1
 '@S9S_MB_2U_LIB.S9S_MB_2U(SCH_1):PAGE279_I50@PURE_QUANTA.Q_RES(CHIPS)':
 C_PATH='@s9s_mb_2u_lib.s9s_mb_2u(sch_1):page279_i50@pure_quanta.q_res(chips)',
 P_PATH='@s9s_mb_2u_lib.s9s_mb_2u(sch_1):page293_i50@pure_quanta.q_res(chips)',
 PATH='I50',
 DRAWING='@S9S_MB_2U_LIB.S9S_MB_2U(SCH_1):PAGE279',
 PHYS_PAGE='293',
 XY='(-5625,11675)',
 ROT='0',
 VER='1',
 PACK_TYPE='0402LF',
 LOCATION='PR1794',
 CDS_LIB='pure_quanta',
 CDS_PART_NAME='Q_RES_0402LF-3.3,1%,1/16W,CHIPA',
 WATTAGE='1/16W',
 TOLERANCE='1%',
 MATERIAL='CHIP',
 VALUE='3.3',
 PRIM_FILE='./archive_libs/logical/q_res/chips/chips.prt';

PART_NAME
 PR1795 'Q_RES_0402LF-3.3,1%,1/16W,CHIPA':;

SECTION_NUMBER 1
 '@S9S_MB_2U_LIB.S9S_MB_2U(SCH_1):PAGE279_I42@PURE_QUANTA.Q_RES(CHIPS)':
 C_PATH='@s9s_mb_2u_lib.s9s_mb_2u(sch_1):page279_i42@pure_quanta.q_res(chips)',
 P_PATH='@s9s_mb_2u_lib.s9s_mb_2u(sch_1):page293_i42@pure_quanta.q_res(chips)',
 PATH='I42',
 DRAWING='@S9S_MB_2U_LIB.S9S_MB_2U(SCH_1):PAGE279',
 PHYS_PAGE='293',
 XY='(-5625,8875)',
 ROT='0',
 VER='1',
 PACK_TYPE='0402LF',
 LOCATION='PR1795',
 CDS_LIB='pure_quanta',
 CDS_PART_NAME='Q_RES_0402LF-3.3,1%,1/16W,CHIPA',
 WATTAGE='1/16W',
 TOLERANCE='1%',
 MATERIAL='CHIP',
 VALUE='3.3',
 PRIM_FILE='./archive_libs/logical/q_res/chips/chips.prt';

PART_NAME
 PR1796 'Q_RES_0402LF-0,5%,1/16W,CHIP,CA':;

SECTION_NUMBER 1
 '@S9S_MB_2U_LIB.S9S_MB_2U(SCH_1):PAGE279_I49@PURE_QUANTA.Q_RES(CHIPS)':
 C_PATH='@s9s_mb_2u_lib.s9s_mb_2u(sch_1):page279_i49@pure_quanta.q_res(chips)',
 P_PATH='@s9s_mb_2u_lib.s9s_mb_2u(sch_1):page293_i49@pure_quanta.q_res(chips)',
 PATH='I49',
 DRAWING='@S9S_MB_2U_LIB.S9S_MB_2U(SCH_1):PAGE279',
 PHYS_PAGE='293',
 XY='(-5250,10975)',
 ROT='0',
 VER='1',
 PACK_TYPE='0402LF',
 LOCATION='PR1796',
 CDS_LIB='pure_quanta',
 CDS_PART_NAME='Q_RES_0402LF-0,5%,1/16W,CHIP,CA',
 WATTAGE='1/16W',
 TOLERANCE='5%',
 MATERIAL='CHIP',
 VALUE='0',
 PRIM_FILE='./archive_libs/logical/q_res/chips/chips.prt';

PART_NAME
 PR1797 'Q_RES_0402LF-0,5%,1/16W,CHIP,CA':;

SECTION_NUMBER 1
 '@S9S_MB_2U_LIB.S9S_MB_2U(SCH_1):PAGE279_I31@PURE_QUANTA.Q_RES(CHIPS)':
 C_PATH='@s9s_mb_2u_lib.s9s_mb_2u(sch_1):page279_i31@pure_quanta.q_res(chips)',
 P_PATH='@s9s_mb_2u_lib.s9s_mb_2u(sch_1):page293_i31@pure_quanta.q_res(chips)',
 PATH='I31',
 DRAWING='@S9S_MB_2U_LIB.S9S_MB_2U(SCH_1):PAGE279',
 PHYS_PAGE='293',
 XY='(-5275,8175)',
 ROT='0',
 VER='1',
 PACK_TYPE='0402LF',
 LOCATION='PR1797',
 CDS_LIB='pure_quanta',
 CDS_PART_NAME='Q_RES_0402LF-0,5%,1/16W,CHIP,CA',
 WATTAGE='1/16W',
 TOLERANCE='5%',
 MATERIAL='CHIP',
 VALUE='0',
 PRIM_FILE='./archive_libs/logical/q_res/chips/chips.prt';

PART_NAME
 PR1798 'Q_RES_0402LF-3.3,1%,1/16W,CHIPA':;

SECTION_NUMBER 1
 '@S9S_MB_2U_LIB.S9S_MB_2U(SCH_1):PAGE280_I25@PURE_QUANTA.Q_RES(CHIPS)':
 C_PATH='@s9s_mb_2u_lib.s9s_mb_2u(sch_1):page280_i25@pure_quanta.q_res(chips)',
 P_PATH='@s9s_mb_2u_lib.s9s_mb_2u(sch_1):page294_i25@pure_quanta.q_res(chips)',
 PATH='I25',
 DRAWING='@S9S_MB_2U_LIB.S9S_MB_2U(SCH_1):PAGE280',
 PHYS_PAGE='294',
 XY='(-3250,9650)',
 ROT='0',
 VER='1',
 PACK_TYPE='0402LF',
 LOCATION='PR1798',
 CDS_LIB='pure_quanta',
 CDS_PART_NAME='Q_RES_0402LF-3.3,1%,1/16W,CHIPA',
 WATTAGE='1/16W',
 TOLERANCE='1%',
 MATERIAL='CHIP',
 VALUE='3.3',
 PRIM_FILE='./archive_libs/logical/q_res/chips/chips.prt';

PART_NAME
 PR1799 'Q_RES_0402LF-0,5%,1/16W,CHIP,CA':;

SECTION_NUMBER 1
 '@S9S_MB_2U_LIB.S9S_MB_2U(SCH_1):PAGE280_I20@PURE_QUANTA.Q_RES(CHIPS)':
 C_PATH='@s9s_mb_2u_lib.s9s_mb_2u(sch_1):page280_i20@pure_quanta.q_res(chips)',
 P_PATH='@s9s_mb_2u_lib.s9s_mb_2u(sch_1):page294_i20@pure_quanta.q_res(chips)',
 PATH='I20',
 DRAWING='@S9S_MB_2U_LIB.S9S_MB_2U(SCH_1):PAGE280',
 PHYS_PAGE='294',
 XY='(-3025,8900)',
 ROT='0',
 VER='1',
 PACK_TYPE='0402LF',
 LOCATION='PR1799',
 CDS_LIB='pure_quanta',
 CDS_PART_NAME='Q_RES_0402LF-0,5%,1/16W,CHIP,CA',
 WATTAGE='1/16W',
 TOLERANCE='5%',
 MATERIAL='CHIP',
 VALUE='0',
 PRIM_FILE='./archive_libs/logical/q_res/chips/chips.prt';

PART_NAME
 PR1800 'Q_RES_0402LF-3.3,1%,1/16W,CHIPA':;

SECTION_NUMBER 1
 '@S9S_MB_2U_LIB.S9S_MB_2U(SCH_1):PAGE275_I50@PURE_QUANTA.Q_RES(CHIPS)':
 C_PATH='@s9s_mb_2u_lib.s9s_mb_2u(sch_1):page275_i50@pure_quanta.q_res(chips)',
 P_PATH='@s9s_mb_2u_lib.s9s_mb_2u(sch_1):page289_i50@pure_quanta.q_res(chips)',
 PATH='I50',
 DRAWING='@S9S_MB_2U_LIB.S9S_MB_2U(SCH_1):PAGE275',
 PHYS_PAGE='289',
 XY='(-7225,5125)',
 ROT='0',
 VER='1',
 PACK_TYPE='0402LF',
 LOCATION='PR1800',
 CDS_LIB='pure_quanta',
 CDS_PART_NAME='Q_RES_0402LF-3.3,1%,1/16W,CHIPA',
 WATTAGE='1/16W',
 TOLERANCE='1%',
 MATERIAL='CHIP',
 VALUE='3.3',
 PRIM_FILE='./archive_libs/logical/q_res/chips/chips.prt';

PART_NAME
 PR1801 'Q_RES_0402LF-3.3,1%,1/16W,CHIPA':;

SECTION_NUMBER 1
 '@S9S_MB_2U_LIB.S9S_MB_2U(SCH_1):PAGE275_I38@PURE_QUANTA.Q_RES(CHIPS)':
 C_PATH='@s9s_mb_2u_lib.s9s_mb_2u(sch_1):page275_i38@pure_quanta.q_res(chips)',
 P_PATH='@s9s_mb_2u_lib.s9s_mb_2u(sch_1):page289_i38@pure_quanta.q_res(chips)',
 PATH='I38',
 DRAWING='@S9S_MB_2U_LIB.S9S_MB_2U(SCH_1):PAGE275',
 PHYS_PAGE='289',
 XY='(-7225,2325)',
 ROT='0',
 VER='1',
 PACK_TYPE='0402LF',
 LOCATION='PR1801',
 CDS_LIB='pure_quanta',
 CDS_PART_NAME='Q_RES_0402LF-3.3,1%,1/16W,CHIPA',
 WATTAGE='1/16W',
 TOLERANCE='1%',
 MATERIAL='CHIP',
 VALUE='3.3',
 PRIM_FILE='./archive_libs/logical/q_res/chips/chips.prt';

PART_NAME
 PR1802 'Q_RES_0402LF-3.3,1%,1/16W,CHIPA':;

SECTION_NUMBER 1
 '@S9S_MB_2U_LIB.S9S_MB_2U(SCH_1):PAGE276_I40@PURE_QUANTA.Q_RES(CHIPS)':
 C_PATH='@s9s_mb_2u_lib.s9s_mb_2u(sch_1):page276_i40@pure_quanta.q_res(chips)',
 P_PATH='@s9s_mb_2u_lib.s9s_mb_2u(sch_1):page290_i40@pure_quanta.q_res(chips)',
 PATH='I40',
 DRAWING='@S9S_MB_2U_LIB.S9S_MB_2U(SCH_1):PAGE276',
 PHYS_PAGE='290',
 XY='(-4300,7075)',
 ROT='0',
 VER='1',
 PACK_TYPE='0402LF',
 LOCATION='PR1802',
 CDS_LIB='pure_quanta',
 CDS_PART_NAME='Q_RES_0402LF-3.3,1%,1/16W,CHIPA',
 WATTAGE='1/16W',
 TOLERANCE='1%',
 MATERIAL='CHIP',
 VALUE='3.3',
 PRIM_FILE='./archive_libs/logical/q_res/chips/chips.prt';

PART_NAME
 PR1803 'Q_RES_0402LF-3.3,1%,1/16W,CHIPA':;

SECTION_NUMBER 1
 '@S9S_MB_2U_LIB.S9S_MB_2U(SCH_1):PAGE276_I17@PURE_QUANTA.Q_RES(CHIPS)':
 C_PATH='@s9s_mb_2u_lib.s9s_mb_2u(sch_1):page276_i17@pure_quanta.q_res(chips)',
 P_PATH='@s9s_mb_2u_lib.s9s_mb_2u(sch_1):page290_i17@pure_quanta.q_res(chips)',
 PATH='I17',
 DRAWING='@S9S_MB_2U_LIB.S9S_MB_2U(SCH_1):PAGE276',
 PHYS_PAGE='290',
 XY='(-4300,4275)',
 ROT='0',
 VER='1',
 PACK_TYPE='0402LF',
 LOCATION='PR1803',
 CDS_LIB='pure_quanta',
 CDS_PART_NAME='Q_RES_0402LF-3.3,1%,1/16W,CHIPA',
 WATTAGE='1/16W',
 TOLERANCE='1%',
 MATERIAL='CHIP',
 VALUE='3.3',
 PRIM_FILE='./archive_libs/logical/q_res/chips/chips.prt';

PART_NAME
 PR1804 'Q_RES_0402LF-3.3,1%,1/16W,CHIPA':;

SECTION_NUMBER 1
 '@S9S_MB_2U_LIB.S9S_MB_2U(SCH_1):PAGE283_I21@PURE_QUANTA.Q_RES(CHIPS)':
 C_PATH='@s9s_mb_2u_lib.s9s_mb_2u(sch_1):page283_i21@pure_quanta.q_res(chips)',
 P_PATH='@s9s_mb_2u_lib.s9s_mb_2u(sch_1):page297_i21@pure_quanta.q_res(chips)',
 PATH='I21',
 DRAWING='@S9S_MB_2U_LIB.S9S_MB_2U(SCH_1):PAGE283',
 PHYS_PAGE='297',
 XY='(-5225,4075)',
 ROT='0',
 VER='1',
 PACK_TYPE='0402LF',
 LOCATION='PR1804',
 CDS_LIB='pure_quanta',
 CDS_PART_NAME='Q_RES_0402LF-3.3,1%,1/16W,CHIPA',
 WATTAGE='1/16W',
 TOLERANCE='1%',
 MATERIAL='CHIP',
 VALUE='3.3',
 PRIM_FILE='./archive_libs/logical/q_res/chips/chips.prt';

PART_NAME
 PR1805 'Q_RES_0402LF-0,5%,1/16W,CHIP,CA':;

SECTION_NUMBER 1
 '@S9S_MB_2U_LIB.S9S_MB_2U(SCH_1):PAGE283_I12@PURE_QUANTA.Q_RES(CHIPS)':
 C_PATH='@s9s_mb_2u_lib.s9s_mb_2u(sch_1):page283_i12@pure_quanta.q_res(chips)',
 P_PATH='@s9s_mb_2u_lib.s9s_mb_2u(sch_1):page297_i12@pure_quanta.q_res(chips)',
 PATH='I12',
 DRAWING='@S9S_MB_2U_LIB.S9S_MB_2U(SCH_1):PAGE283',
 PHYS_PAGE='297',
 XY='(-4950,3375)',
 ROT='0',
 VER='1',
 PACK_TYPE='0402LF',
 LOCATION='PR1805',
 CDS_LIB='pure_quanta',
 CDS_PART_NAME='Q_RES_0402LF-0,5%,1/16W,CHIP,CA',
 WATTAGE='1/16W',
 TOLERANCE='5%',
 MATERIAL='CHIP',
 VALUE='0',
 PRIM_FILE='./archive_libs/logical/q_res/chips/chips.prt';

PART_NAME
 PR1850 'Q_RES_0402LF-1K,1%,1/16W,EMPTYA':;

SECTION_NUMBER 1
 '@S9S_MB_2U_LIB.S9S_MB_2U(SCH_1):PAGE249_I11@PURE_QUANTA.Q_RES(CHIPS)':
 C_PATH='@s9s_mb_2u_lib.s9s_mb_2u(sch_1):page249_i11@pure_quanta.q_res(chips)',
 P_PATH='@s9s_mb_2u_lib.s9s_mb_2u(sch_1):page263_i11@pure_quanta.q_res(chips)',
 PATH='I11',
 DRAWING='@S9S_MB_2U_LIB.S9S_MB_2U(SCH_1):PAGE249',
 PHYS_PAGE='263',
 XY='(-4500,5950)',
 ROT='0',
 VER='1',
 PACK_TYPE='0402LF',
 LOCATION='PR1850',
 CDS_LIB='pure_quanta',
 CDS_PART_NAME='Q_RES_0402LF-1K,1%,1/16W,EMPTYA',
 WATTAGE='1/16W',
 TOLERANCE='1%',
 MATERIAL='EMPTY',
 VALUE='1K',
 PRIM_FILE='./archive_libs/logical/q_res/chips/chips.prt';

PART_NAME
 PR2106 'Q_RES_0402LF-10K,1%,1/16W,CHIPA':
 ROOM='HSC1_BOM1';

SECTION_NUMBER 1
 '@S9S_MB_2U_LIB.S9S_MB_2U(SCH_1):PAGE303_I43@PURE_QUANTA.Q_RES(CHIPS)':
 C_PATH='@s9s_mb_2u_lib.s9s_mb_2u(sch_1):page303_i43@pure_quanta.q_res(chips)',
 P_PATH='@s9s_mb_2u_lib.s9s_mb_2u(sch_1):page301_i43@pure_quanta.q_res(chips)',
 PATH='I43',
 DRAWING='@S9S_MB_2U_LIB.S9S_MB_2U(SCH_1):PAGE303',
 PHYS_PAGE='301',
 XY='(-14825,3475)',
 ROT='0',
 VER='1',
 PACK_TYPE='0402LF',
 CDS_LIB='pure_quanta',
 CDS_PART_NAME='Q_RES_0402LF-10K,1%,1/16W,CHIPA',
 WATTAGE='1/16W',
 TOLERANCE='1%',
 MATERIAL='CHIP',
 ROOM='HSC1_BOM1',
 VALUE='10K',
 PRIM_FILE='./archive_libs/logical/q_res/chips/chips.prt';

PART_NAME
 PR2149 'Q_RES_0402LF-0,5%,1/16W,CHIP,CA':
 ROOM='HSC1_BOM1';

SECTION_NUMBER 1
 '@S9S_MB_2U_LIB.S9S_MB_2U(SCH_1):PAGE303_I24@PURE_QUANTA.Q_RES(CHIPS)':
 C_PATH='@s9s_mb_2u_lib.s9s_mb_2u(sch_1):page303_i24@pure_quanta.q_res(chips)',
 P_PATH='@s9s_mb_2u_lib.s9s_mb_2u(sch_1):page301_i24@pure_quanta.q_res(chips)',
 PATH='I24',
 DRAWING='@S9S_MB_2U_LIB.S9S_MB_2U(SCH_1):PAGE303',
 PHYS_PAGE='301',
 XY='(-16950,4750)',
 ROT='1',
 VER='1',
 PACK_TYPE='0402LF',
 LOCATION='PR2149',
 CDS_LIB='pure_quanta',
 CDS_PART_NAME='Q_RES_0402LF-0,5%,1/16W,CHIP,CA',
 WATTAGE='1/16W',
 TOLERANCE='5%',
 MATERIAL='CHIP',
 ROOM='HSC1_BOM1',
 VALUE='0',
 PRIM_FILE='./archive_libs/logical/q_res/chips/chips.prt';

PART_NAME
 PR2220 'Q_RES_0402LF-60.4K,1%,1/16W,CHA':;

SECTION_NUMBER 1
 '@S9S_MB_2U_LIB.S9S_MB_2U(SCH_1):PAGE286_I12@PURE_QUANTA.Q_RES(CHIPS)':
 C_PATH='@s9s_mb_2u_lib.s9s_mb_2u(sch_1):page286_i12@pure_quanta.q_res(chips)',
 P_PATH='@s9s_mb_2u_lib.s9s_mb_2u(sch_1):page300_i12@pure_quanta.q_res(chips)',
 PATH='I12',
 DRAWING='@S9S_MB_2U_LIB.S9S_MB_2U(SCH_1):PAGE286',
 PHYS_PAGE='300',
 XY='(3200,6650)',
 ROT='0',
 VER='2',
 PACK_TYPE='0402LF',
 LOCATION='PR2220',
 CDS_LIB='pure_quanta',
 CDS_PART_NAME='Q_RES_0402LF-60.4K,1%,1/16W,CHA',
 WATTAGE='1/16W',
 TOLERANCE='1%',
 MATERIAL='CHIP',
 VALUE='60.4K',
 PRIM_FILE='./archive_libs/logical/q_res/chips/chips.prt';

PART_NAME
 PR2222 'Q_RES_0402LF-34.8K,1%,1/16W,CHA':;

SECTION_NUMBER 1
 '@S9S_MB_2U_LIB.S9S_MB_2U(SCH_1):PAGE286_I19@PURE_QUANTA.Q_RES(CHIPS)':
 C_PATH='@s9s_mb_2u_lib.s9s_mb_2u(sch_1):page286_i19@pure_quanta.q_res(chips)',
 P_PATH='@s9s_mb_2u_lib.s9s_mb_2u(sch_1):page300_i19@pure_quanta.q_res(chips)',
 PATH='I19',
 DRAWING='@S9S_MB_2U_LIB.S9S_MB_2U(SCH_1):PAGE286',
 PHYS_PAGE='300',
 XY='(4075,6050)',
 ROT='0',
 VER='2',
 PACK_TYPE='0402LF',
 LOCATION='PR2222',
 CDS_LIB='pure_quanta',
 CDS_PART_NAME='Q_RES_0402LF-34.8K,1%,1/16W,CHA',
 WATTAGE='1/16W',
 TOLERANCE='1%',
 MATERIAL='CHIP',
 VALUE='34.8K',
 PRIM_FILE='./archive_libs/logical/q_res/chips/chips.prt';

PART_NAME
 PR2336 'Q_RES_0402LF-26.1K,0.1%,1/16W,A':;

SECTION_NUMBER 1
 '@S9S_MB_2U_LIB.S9S_MB_2U(SCH_1):PAGE267_I34@PURE_QUANTA.Q_RES(CHIPS)':
 C_PATH='@s9s_mb_2u_lib.s9s_mb_2u(sch_1):page267_i34@pure_quanta.q_res(chips)',
 P_PATH='@s9s_mb_2u_lib.s9s_mb_2u(sch_1):page281_i34@pure_quanta.q_res(chips)',
 PATH='I34',
 DRAWING='@S9S_MB_2U_LIB.S9S_MB_2U(SCH_1):PAGE267',
 PHYS_PAGE='281',
 XY='(-6350,2475)',
 ROT='0',
 VER='1',
 PACK_TYPE='0402LF',
 LOCATION='PR2336',
 CDS_LIB='pure_quanta',
 CDS_PART_NAME='Q_RES_0402LF-26.1K,0.1%,1/16W,A',
 WATTAGE='1/16W',
 TOLERANCE='0.1%',
 MATERIAL='EMPTY',
 VALUE='26.1K',
 PRIM_FILE='./archive_libs/logical/q_res/chips/chips.prt';

PART_NAME
 PR2381 'Q_RES_0402LF-26.1K,0.1%,1/16W,A':;

SECTION_NUMBER 1
 '@S9S_MB_2U_LIB.S9S_MB_2U(SCH_1):PAGE285_I30@PURE_QUANTA.Q_RES(CHIPS)':
 C_PATH='@s9s_mb_2u_lib.s9s_mb_2u(sch_1):page285_i30@pure_quanta.q_res(chips)',
 P_PATH='@s9s_mb_2u_lib.s9s_mb_2u(sch_1):page299_i30@pure_quanta.q_res(chips)',
 PATH='I30',
 DRAWING='@S9S_MB_2U_LIB.S9S_MB_2U(SCH_1):PAGE285',
 PHYS_PAGE='299',
 XY='(-5700,2025)',
 ROT='0',
 VER='1',
 PACK_TYPE='0402LF',
 LOCATION='PR2381',
 CDS_LIB='pure_quanta',
 CDS_PART_NAME='Q_RES_0402LF-26.1K,0.1%,1/16W,A',
 WATTAGE='1/16W',
 TOLERANCE='0.1%',
 MATERIAL='EMPTY',
 VALUE='26.1K',
 PRIM_FILE='./archive_libs/logical/q_res/chips/chips.prt';

PART_NAME
 PR2510 'Q_RES_0402LF-1,1%,1/16W,EMPTY,A':
 ROOM='HSC1_BOM2';

SECTION_NUMBER 1
 '@S9S_MB_2U_LIB.S9S_MB_2U(SCH_1):PAGE328_I98@PURE_QUANTA.Q_RES(CHIPS)':
 C_PATH='@s9s_mb_2u_lib.s9s_mb_2u(sch_1):page328_i98@pure_quanta.q_res(chips)',
 P_PATH='@s9s_mb_2u_lib.s9s_mb_2u(sch_1):page304_i98@pure_quanta.q_res(chips)',
 PATH='I98',
 DRAWING='@S9S_MB_2U_LIB.S9S_MB_2U(SCH_1):PAGE328',
 PHYS_PAGE='304',
 XY='(-2625,4050)',
 ROT='0',
 VER='1',
 PACK_TYPE='0402LF',
 LOCATION='PR2510',
 CDS_LIB='pure_quanta',
 CDS_PART_NAME='Q_RES_0402LF-1,1%,1/16W,EMPTY,A',
 WATTAGE='1/16W',
 TOLERANCE='1%',
 MATERIAL='EMPTY',
 ROOM='HSC1_BOM2',
 VALUE='1',
 PRIM_FILE='./archive_libs/logical/q_res/chips/chips.prt';

PART_NAME
 PR2511 'Q_RES_0402LF-1,1%,1/16W,EMPTY,A':
 ROOM='HSC1_BOM2';

SECTION_NUMBER 1
 '@S9S_MB_2U_LIB.S9S_MB_2U(SCH_1):PAGE328_I99@PURE_QUANTA.Q_RES(CHIPS)':
 C_PATH='@s9s_mb_2u_lib.s9s_mb_2u(sch_1):page328_i99@pure_quanta.q_res(chips)',
 P_PATH='@s9s_mb_2u_lib.s9s_mb_2u(sch_1):page304_i99@pure_quanta.q_res(chips)',
 PATH='I99',
 DRAWING='@S9S_MB_2U_LIB.S9S_MB_2U(SCH_1):PAGE328',
 PHYS_PAGE='304',
 XY='(-2625,3950)',
 ROT='0',
 VER='1',
 PACK_TYPE='0402LF',
 LOCATION='PR2511',
 CDS_LIB='pure_quanta',
 CDS_PART_NAME='Q_RES_0402LF-1,1%,1/16W,EMPTY,A',
 WATTAGE='1/16W',
 TOLERANCE='1%',
 MATERIAL='EMPTY',
 ROOM='HSC1_BOM2',
 VALUE='1',
 PRIM_FILE='./archive_libs/logical/q_res/chips/chips.prt';

PART_NAME
 PR2512 'Q_RES_0402LF-1,1%,1/16W,EMPTY,A':
 ROOM='HSC1_BOM2';

SECTION_NUMBER 1
 '@S9S_MB_2U_LIB.S9S_MB_2U(SCH_1):PAGE328_I96@PURE_QUANTA.Q_RES(CHIPS)':
 C_PATH='@s9s_mb_2u_lib.s9s_mb_2u(sch_1):page328_i96@pure_quanta.q_res(chips)',
 P_PATH='@s9s_mb_2u_lib.s9s_mb_2u(sch_1):page304_i96@pure_quanta.q_res(chips)',
 PATH='I96',
 DRAWING='@S9S_MB_2U_LIB.S9S_MB_2U(SCH_1):PAGE328',
 PHYS_PAGE='304',
 XY='(-2625,3850)',
 ROT='0',
 VER='1',
 PACK_TYPE='0402LF',
 LOCATION='PR2512',
 CDS_LIB='pure_quanta',
 CDS_PART_NAME='Q_RES_0402LF-1,1%,1/16W,EMPTY,A',
 WATTAGE='1/16W',
 TOLERANCE='1%',
 MATERIAL='EMPTY',
 ROOM='HSC1_BOM2',
 VALUE='1',
 PRIM_FILE='./archive_libs/logical/q_res/chips/chips.prt';

PART_NAME
 PR2513 'Q_RES_0402LF-1,1%,1/16W,EMPTY,A':
 ROOM='HSC1_BOM2';

SECTION_NUMBER 1
 '@S9S_MB_2U_LIB.S9S_MB_2U(SCH_1):PAGE328_I95@PURE_QUANTA.Q_RES(CHIPS)':
 C_PATH='@s9s_mb_2u_lib.s9s_mb_2u(sch_1):page328_i95@pure_quanta.q_res(chips)',
 P_PATH='@s9s_mb_2u_lib.s9s_mb_2u(sch_1):page304_i95@pure_quanta.q_res(chips)',
 PATH='I95',
 DRAWING='@S9S_MB_2U_LIB.S9S_MB_2U(SCH_1):PAGE328',
 PHYS_PAGE='304',
 XY='(-2625,3750)',
 ROT='0',
 VER='1',
 PACK_TYPE='0402LF',
 LOCATION='PR2513',
 CDS_LIB='pure_quanta',
 CDS_PART_NAME='Q_RES_0402LF-1,1%,1/16W,EMPTY,A',
 WATTAGE='1/16W',
 TOLERANCE='1%',
 MATERIAL='EMPTY',
 ROOM='HSC1_BOM2',
 VALUE='1',
 PRIM_FILE='./archive_libs/logical/q_res/chips/chips.prt';

PART_NAME
 PR2514 'Q_RES_0402LF-10,1%,1/16W,EMPTYA':
 ROOM='HSC1_BOM2';

SECTION_NUMBER 1
 '@S9S_MB_2U_LIB.S9S_MB_2U(SCH_1):PAGE328_I97@PURE_QUANTA.Q_RES(CHIPS)':
 C_PATH='@s9s_mb_2u_lib.s9s_mb_2u(sch_1):page328_i97@pure_quanta.q_res(chips)',
 P_PATH='@s9s_mb_2u_lib.s9s_mb_2u(sch_1):page304_i97@pure_quanta.q_res(chips)',
 PATH='I97',
 DRAWING='@S9S_MB_2U_LIB.S9S_MB_2U(SCH_1):PAGE328',
 PHYS_PAGE='304',
 XY='(-2625,3650)',
 ROT='0',
 VER='1',
 PACK_TYPE='0402LF',
 LOCATION='PR2514',
 CDS_LIB='pure_quanta',
 CDS_PART_NAME='Q_RES_0402LF-10,1%,1/16W,EMPTYA',
 WATTAGE='1/16W',
 TOLERANCE='1%',
 MATERIAL='EMPTY',
 ROOM='HSC1_BOM2',
 VALUE='10',
 PRIM_FILE='./archive_libs/logical/q_res/chips/chips.prt';

PART_NAME
 PR2515 'Q_RES_0402LF-10,1%,1/16W,EMPTYA':
 ROOM='HSC1_BOM2';

SECTION_NUMBER 1
 '@S9S_MB_2U_LIB.S9S_MB_2U(SCH_1):PAGE328_I93@PURE_QUANTA.Q_RES(CHIPS)':
 C_PATH='@s9s_mb_2u_lib.s9s_mb_2u(sch_1):page328_i93@pure_quanta.q_res(chips)',
 P_PATH='@s9s_mb_2u_lib.s9s_mb_2u(sch_1):page304_i93@pure_quanta.q_res(chips)',
 PATH='I93',
 DRAWING='@S9S_MB_2U_LIB.S9S_MB_2U(SCH_1):PAGE328',
 PHYS_PAGE='304',
 XY='(-2600,3300)',
 ROT='0',
 VER='1',
 PACK_TYPE='0402LF',
 LOCATION='PR2515',
 CDS_LIB='pure_quanta',
 CDS_PART_NAME='Q_RES_0402LF-10,1%,1/16W,EMPTYA',
 WATTAGE='1/16W',
 TOLERANCE='1%',
 MATERIAL='EMPTY',
 ROOM='HSC1_BOM2',
 VALUE='10',
 PRIM_FILE='./archive_libs/logical/q_res/chips/chips.prt';

PART_NAME
 PR2516 'Q_RES_0402LF-10,1%,1/16W,EMPTYA':
 ROOM='HSC1_BOM2';

SECTION_NUMBER 1
 '@S9S_MB_2U_LIB.S9S_MB_2U(SCH_1):PAGE328_I94@PURE_QUANTA.Q_RES(CHIPS)':
 C_PATH='@s9s_mb_2u_lib.s9s_mb_2u(sch_1):page328_i94@pure_quanta.q_res(chips)',
 P_PATH='@s9s_mb_2u_lib.s9s_mb_2u(sch_1):page304_i94@pure_quanta.q_res(chips)',
 PATH='I94',
 DRAWING='@S9S_MB_2U_LIB.S9S_MB_2U(SCH_1):PAGE328',
 PHYS_PAGE='304',
 XY='(-2600,3200)',
 ROT='0',
 VER='1',
 PACK_TYPE='0402LF',
 LOCATION='PR2516',
 CDS_LIB='pure_quanta',
 CDS_PART_NAME='Q_RES_0402LF-10,1%,1/16W,EMPTYA',
 WATTAGE='1/16W',
 TOLERANCE='1%',
 MATERIAL='EMPTY',
 ROOM='HSC1_BOM2',
 VALUE='10',
 PRIM_FILE='./archive_libs/logical/q_res/chips/chips.prt';

PART_NAME
 PR2517 'Q_RES_0402LF-10,1%,1/16W,EMPTYA':
 ROOM='HSC1_BOM2';

SECTION_NUMBER 1
 '@S9S_MB_2U_LIB.S9S_MB_2U(SCH_1):PAGE328_I90@PURE_QUANTA.Q_RES(CHIPS)':
 C_PATH='@s9s_mb_2u_lib.s9s_mb_2u(sch_1):page328_i90@pure_quanta.q_res(chips)',
 P_PATH='@s9s_mb_2u_lib.s9s_mb_2u(sch_1):page304_i90@pure_quanta.q_res(chips)',
 PATH='I90',
 DRAWING='@S9S_MB_2U_LIB.S9S_MB_2U(SCH_1):PAGE328',
 PHYS_PAGE='304',
 XY='(-2600,3100)',
 ROT='0',
 VER='1',
 PACK_TYPE='0402LF',
 LOCATION='PR2517',
 CDS_LIB='pure_quanta',
 CDS_PART_NAME='Q_RES_0402LF-10,1%,1/16W,EMPTYA',
 WATTAGE='1/16W',
 TOLERANCE='1%',
 MATERIAL='EMPTY',
 ROOM='HSC1_BOM2',
 VALUE='10',
 PRIM_FILE='./archive_libs/logical/q_res/chips/chips.prt';

PART_NAME
 PR2518 'Q_RES_0402LF-10,1%,1/16W,EMPTYA':
 ROOM='HSC1_BOM2';

SECTION_NUMBER 1
 '@S9S_MB_2U_LIB.S9S_MB_2U(SCH_1):PAGE328_I91@PURE_QUANTA.Q_RES(CHIPS)':
 C_PATH='@s9s_mb_2u_lib.s9s_mb_2u(sch_1):page328_i91@pure_quanta.q_res(chips)',
 P_PATH='@s9s_mb_2u_lib.s9s_mb_2u(sch_1):page304_i91@pure_quanta.q_res(chips)',
 PATH='I91',
 DRAWING='@S9S_MB_2U_LIB.S9S_MB_2U(SCH_1):PAGE328',
 PHYS_PAGE='304',
 XY='(-2600,3000)',
 ROT='0',
 VER='1',
 PACK_TYPE='0402LF',
 LOCATION='PR2518',
 CDS_LIB='pure_quanta',
 CDS_PART_NAME='Q_RES_0402LF-10,1%,1/16W,EMPTYA',
 WATTAGE='1/16W',
 TOLERANCE='1%',
 MATERIAL='EMPTY',
 ROOM='HSC1_BOM2',
 VALUE='10',
 PRIM_FILE='./archive_libs/logical/q_res/chips/chips.prt';

PART_NAME
 PR2519 'Q_RES_0402LF-100,1%,1/16W,EMPTA':
 ROOM='HSC1_BOM2';

SECTION_NUMBER 1
 '@S9S_MB_2U_LIB.S9S_MB_2U(SCH_1):PAGE328_I92@PURE_QUANTA.Q_RES(CHIPS)':
 C_PATH='@s9s_mb_2u_lib.s9s_mb_2u(sch_1):page328_i92@pure_quanta.q_res(chips)',
 P_PATH='@s9s_mb_2u_lib.s9s_mb_2u(sch_1):page304_i92@pure_quanta.q_res(chips)',
 PATH='I92',
 DRAWING='@S9S_MB_2U_LIB.S9S_MB_2U(SCH_1):PAGE328',
 PHYS_PAGE='304',
 XY='(-2600,2900)',
 ROT='0',
 VER='1',
 PACK_TYPE='0402LF',
 LOCATION='PR2519',
 CDS_LIB='pure_quanta',
 CDS_PART_NAME='Q_RES_0402LF-100,1%,1/16W,EMPTA',
 WATTAGE='1/16W',
 TOLERANCE='1%',
 MATERIAL='EMPTY',
 ROOM='HSC1_BOM2',
 VALUE='100',
 PRIM_FILE='./archive_libs/logical/q_res/chips/chips.prt';

PART_NAME
 PR2520 'Q_RES_0402LF-1,1%,1/16W,EMPTY,A':
 ROOM='HSC1_BOM2';

SECTION_NUMBER 1
 '@S9S_MB_2U_LIB.S9S_MB_2U(SCH_1):PAGE328_I89@PURE_QUANTA.Q_RES(CHIPS)':
 C_PATH='@s9s_mb_2u_lib.s9s_mb_2u(sch_1):page328_i89@pure_quanta.q_res(chips)',
 P_PATH='@s9s_mb_2u_lib.s9s_mb_2u(sch_1):page304_i89@pure_quanta.q_res(chips)',
 PATH='I89',
 DRAWING='@S9S_MB_2U_LIB.S9S_MB_2U(SCH_1):PAGE328',
 PHYS_PAGE='304',
 XY='(-2600,2525)',
 ROT='0',
 VER='1',
 PACK_TYPE='0402LF',
 LOCATION='PR2520',
 CDS_LIB='pure_quanta',
 CDS_PART_NAME='Q_RES_0402LF-1,1%,1/16W,EMPTY,A',
 WATTAGE='1/16W',
 TOLERANCE='1%',
 MATERIAL='EMPTY',
 ROOM='HSC1_BOM2',
 VALUE='1',
 PRIM_FILE='./archive_libs/logical/q_res/chips/chips.prt';

PART_NAME
 PR2521 'Q_RES_0402LF-1,1%,1/16W,EMPTY,A':
 ROOM='HSC1_BOM2';

SECTION_NUMBER 1
 '@S9S_MB_2U_LIB.S9S_MB_2U(SCH_1):PAGE328_I88@PURE_QUANTA.Q_RES(CHIPS)':
 C_PATH='@s9s_mb_2u_lib.s9s_mb_2u(sch_1):page328_i88@pure_quanta.q_res(chips)',
 P_PATH='@s9s_mb_2u_lib.s9s_mb_2u(sch_1):page304_i88@pure_quanta.q_res(chips)',
 PATH='I88',
 DRAWING='@S9S_MB_2U_LIB.S9S_MB_2U(SCH_1):PAGE328',
 PHYS_PAGE='304',
 XY='(-2600,2425)',
 ROT='0',
 VER='1',
 PACK_TYPE='0402LF',
 LOCATION='PR2521',
 CDS_LIB='pure_quanta',
 CDS_PART_NAME='Q_RES_0402LF-1,1%,1/16W,EMPTY,A',
 WATTAGE='1/16W',
 TOLERANCE='1%',
 MATERIAL='EMPTY',
 ROOM='HSC1_BOM2',
 VALUE='1',
 PRIM_FILE='./archive_libs/logical/q_res/chips/chips.prt';

PART_NAME
 PR2522 'Q_RES_0402LF-1,1%,1/16W,EMPTY,A':
 ROOM='HSC1_BOM2';

SECTION_NUMBER 1
 '@S9S_MB_2U_LIB.S9S_MB_2U(SCH_1):PAGE328_I86@PURE_QUANTA.Q_RES(CHIPS)':
 C_PATH='@s9s_mb_2u_lib.s9s_mb_2u(sch_1):page328_i86@pure_quanta.q_res(chips)',
 P_PATH='@s9s_mb_2u_lib.s9s_mb_2u(sch_1):page304_i86@pure_quanta.q_res(chips)',
 PATH='I86',
 DRAWING='@S9S_MB_2U_LIB.S9S_MB_2U(SCH_1):PAGE328',
 PHYS_PAGE='304',
 XY='(-2600,2325)',
 ROT='0',
 VER='1',
 PACK_TYPE='0402LF',
 LOCATION='PR2522',
 CDS_LIB='pure_quanta',
 CDS_PART_NAME='Q_RES_0402LF-1,1%,1/16W,EMPTY,A',
 WATTAGE='1/16W',
 TOLERANCE='1%',
 MATERIAL='EMPTY',
 ROOM='HSC1_BOM2',
 VALUE='1',
 PRIM_FILE='./archive_libs/logical/q_res/chips/chips.prt';

PART_NAME
 PR2523 'Q_RES_0402LF-1,1%,1/16W,EMPTY,A':
 ROOM='HSC1_BOM2';

SECTION_NUMBER 1
 '@S9S_MB_2U_LIB.S9S_MB_2U(SCH_1):PAGE328_I87@PURE_QUANTA.Q_RES(CHIPS)':
 C_PATH='@s9s_mb_2u_lib.s9s_mb_2u(sch_1):page328_i87@pure_quanta.q_res(chips)',
 P_PATH='@s9s_mb_2u_lib.s9s_mb_2u(sch_1):page304_i87@pure_quanta.q_res(chips)',
 PATH='I87',
 DRAWING='@S9S_MB_2U_LIB.S9S_MB_2U(SCH_1):PAGE328',
 PHYS_PAGE='304',
 XY='(-2600,2225)',
 ROT='0',
 VER='1',
 PACK_TYPE='0402LF',
 LOCATION='PR2523',
 CDS_LIB='pure_quanta',
 CDS_PART_NAME='Q_RES_0402LF-1,1%,1/16W,EMPTY,A',
 WATTAGE='1/16W',
 TOLERANCE='1%',
 MATERIAL='EMPTY',
 ROOM='HSC1_BOM2',
 VALUE='1',
 PRIM_FILE='./archive_libs/logical/q_res/chips/chips.prt';

PART_NAME
 PR2524 'Q_RES_0402LF-10,1%,1/16W,EMPTYA':
 ROOM='HSC1_BOM2';

SECTION_NUMBER 1
 '@S9S_MB_2U_LIB.S9S_MB_2U(SCH_1):PAGE328_I119@PURE_QUANTA.Q_RES(CHIPS)':
 C_PATH='@s9s_mb_2u_lib.s9s_mb_2u(sch_1):page328_i119@pure_quanta.q_res(chips)',
 P_PATH='@s9s_mb_2u_lib.s9s_mb_2u(sch_1):page304_i119@pure_quanta.q_res(chips)',
 PATH='I119',
 DRAWING='@S9S_MB_2U_LIB.S9S_MB_2U(SCH_1):PAGE328',
 PHYS_PAGE='304',
 XY='(-2575,1875)',
 ROT='0',
 VER='1',
 PACK_TYPE='0402LF',
 LOCATION='PR2524',
 CDS_LIB='pure_quanta',
 CDS_PART_NAME='Q_RES_0402LF-10,1%,1/16W,EMPTYA',
 WATTAGE='1/16W',
 TOLERANCE='1%',
 MATERIAL='EMPTY',
 ROOM='HSC1_BOM2',
 VALUE='10',
 PRIM_FILE='./archive_libs/logical/q_res/chips/chips.prt';

PART_NAME
 PR2525 'Q_RES_0402LF-10,1%,1/16W,EMPTYA':
 ROOM='HSC1_BOM2';

SECTION_NUMBER 1
 '@S9S_MB_2U_LIB.S9S_MB_2U(SCH_1):PAGE328_I120@PURE_QUANTA.Q_RES(CHIPS)':
 C_PATH='@s9s_mb_2u_lib.s9s_mb_2u(sch_1):page328_i120@pure_quanta.q_res(chips)',
 P_PATH='@s9s_mb_2u_lib.s9s_mb_2u(sch_1):page304_i120@pure_quanta.q_res(chips)',
 PATH='I120',
 DRAWING='@S9S_MB_2U_LIB.S9S_MB_2U(SCH_1):PAGE328',
 PHYS_PAGE='304',
 XY='(-2575,1775)',
 ROT='0',
 VER='1',
 PACK_TYPE='0402LF',
 LOCATION='PR2525',
 CDS_LIB='pure_quanta',
 CDS_PART_NAME='Q_RES_0402LF-10,1%,1/16W,EMPTYA',
 WATTAGE='1/16W',
 TOLERANCE='1%',
 MATERIAL='EMPTY',
 ROOM='HSC1_BOM2',
 VALUE='10',
 PRIM_FILE='./archive_libs/logical/q_res/chips/chips.prt';

PART_NAME
 PR2526 'Q_RES_0402LF-10,1%,1/16W,EMPTYA':
 ROOM='HSC1_BOM2';

SECTION_NUMBER 1
 '@S9S_MB_2U_LIB.S9S_MB_2U(SCH_1):PAGE328_I118@PURE_QUANTA.Q_RES(CHIPS)':
 C_PATH='@s9s_mb_2u_lib.s9s_mb_2u(sch_1):page328_i118@pure_quanta.q_res(chips)',
 P_PATH='@s9s_mb_2u_lib.s9s_mb_2u(sch_1):page304_i118@pure_quanta.q_res(chips)',
 PATH='I118',
 DRAWING='@S9S_MB_2U_LIB.S9S_MB_2U(SCH_1):PAGE328',
 PHYS_PAGE='304',
 XY='(-2575,1675)',
 ROT='0',
 VER='1',
 PACK_TYPE='0402LF',
 LOCATION='PR2526',
 CDS_LIB='pure_quanta',
 CDS_PART_NAME='Q_RES_0402LF-10,1%,1/16W,EMPTYA',
 WATTAGE='1/16W',
 TOLERANCE='1%',
 MATERIAL='EMPTY',
 ROOM='HSC1_BOM2',
 VALUE='10',
 PRIM_FILE='./archive_libs/logical/q_res/chips/chips.prt';

PART_NAME
 PR2527 'Q_RES_0402LF-10,1%,1/16W,EMPTYA':
 ROOM='HSC1_BOM2';

SECTION_NUMBER 1
 '@S9S_MB_2U_LIB.S9S_MB_2U(SCH_1):PAGE328_I117@PURE_QUANTA.Q_RES(CHIPS)':
 C_PATH='@s9s_mb_2u_lib.s9s_mb_2u(sch_1):page328_i117@pure_quanta.q_res(chips)',
 P_PATH='@s9s_mb_2u_lib.s9s_mb_2u(sch_1):page304_i117@pure_quanta.q_res(chips)',
 PATH='I117',
 DRAWING='@S9S_MB_2U_LIB.S9S_MB_2U(SCH_1):PAGE328',
 PHYS_PAGE='304',
 XY='(-2575,1575)',
 ROT='0',
 VER='1',
 PACK_TYPE='0402LF',
 LOCATION='PR2527',
 CDS_LIB='pure_quanta',
 CDS_PART_NAME='Q_RES_0402LF-10,1%,1/16W,EMPTYA',
 WATTAGE='1/16W',
 TOLERANCE='1%',
 MATERIAL='EMPTY',
 ROOM='HSC1_BOM2',
 VALUE='10',
 PRIM_FILE='./archive_libs/logical/q_res/chips/chips.prt';

PART_NAME
 PR2528 'Q_RES_0402LF-10,1%,1/16W,EMPTYA':
 ROOM='HSC1_BOM2';

SECTION_NUMBER 1
 '@S9S_MB_2U_LIB.S9S_MB_2U(SCH_1):PAGE328_I16@PURE_QUANTA.Q_RES(CHIPS)':
 C_PATH='@s9s_mb_2u_lib.s9s_mb_2u(sch_1):page328_i16@pure_quanta.q_res(chips)',
 P_PATH='@s9s_mb_2u_lib.s9s_mb_2u(sch_1):page304_i16@pure_quanta.q_res(chips)',
 PATH='I16',
 DRAWING='@S9S_MB_2U_LIB.S9S_MB_2U(SCH_1):PAGE328',
 PHYS_PAGE='304',
 XY='(-875,675)',
 ROT='0',
 VER='2',
 PACK_TYPE='0402LF',
 LOCATION='PR2528',
 CDS_LIB='pure_quanta',
 CDS_PART_NAME='Q_RES_0402LF-10,1%,1/16W,EMPTYA',
 WATTAGE='1/16W',
 TOLERANCE='1%',
 MATERIAL='EMPTY',
 ROOM='HSC1_BOM2',
 VALUE='10',
 PRIM_FILE='./archive_libs/logical/q_res/chips/chips.prt';

PART_NAME
 PR2529 'Q_RES_0402LF-10,1%,1/16W,EMPTYA':
 ROOM='HSC1_BOM2';

SECTION_NUMBER 1
 '@S9S_MB_2U_LIB.S9S_MB_2U(SCH_1):PAGE328_I38@PURE_QUANTA.Q_RES(CHIPS)':
 C_PATH='@s9s_mb_2u_lib.s9s_mb_2u(sch_1):page328_i38@pure_quanta.q_res(chips)',
 P_PATH='@s9s_mb_2u_lib.s9s_mb_2u(sch_1):page304_i38@pure_quanta.q_res(chips)',
 PATH='I38',
 DRAWING='@S9S_MB_2U_LIB.S9S_MB_2U(SCH_1):PAGE328',
 PHYS_PAGE='304',
 XY='(0,675)',
 ROT='0',
 VER='2',
 PACK_TYPE='0402LF',
 LOCATION='PR2529',
 CDS_LIB='pure_quanta',
 CDS_PART_NAME='Q_RES_0402LF-10,1%,1/16W,EMPTYA',
 WATTAGE='1/16W',
 TOLERANCE='1%',
 MATERIAL='EMPTY',
 ROOM='HSC1_BOM2',
 VALUE='10',
 PRIM_FILE='./archive_libs/logical/q_res/chips/chips.prt';

PART_NAME
 PR2530 'Q_RES_0402LF-10,1%,1/16W,EMPTYA':
 ROOM='HSC1_BOM2';

SECTION_NUMBER 1
 '@S9S_MB_2U_LIB.S9S_MB_2U(SCH_1):PAGE328_I39@PURE_QUANTA.Q_RES(CHIPS)':
 C_PATH='@s9s_mb_2u_lib.s9s_mb_2u(sch_1):page328_i39@pure_quanta.q_res(chips)',
 P_PATH='@s9s_mb_2u_lib.s9s_mb_2u(sch_1):page304_i39@pure_quanta.q_res(chips)',
 PATH='I39',
 DRAWING='@S9S_MB_2U_LIB.S9S_MB_2U(SCH_1):PAGE328',
 PHYS_PAGE='304',
 XY='(850,675)',
 ROT='0',
 VER='2',
 PACK_TYPE='0402LF',
 LOCATION='PR2530',
 CDS_LIB='pure_quanta',
 CDS_PART_NAME='Q_RES_0402LF-10,1%,1/16W,EMPTYA',
 WATTAGE='1/16W',
 TOLERANCE='1%',
 MATERIAL='EMPTY',
 ROOM='HSC1_BOM2',
 VALUE='10',
 PRIM_FILE='./archive_libs/logical/q_res/chips/chips.prt';

PART_NAME
 PR2531 'Q_RES_0402LF-10,1%,1/16W,EMPTYA':
 ROOM='HSC1_BOM2';

SECTION_NUMBER 1
 '@S9S_MB_2U_LIB.S9S_MB_2U(SCH_1):PAGE328_I59@PURE_QUANTA.Q_RES(CHIPS)':
 C_PATH='@s9s_mb_2u_lib.s9s_mb_2u(sch_1):page328_i59@pure_quanta.q_res(chips)',
 P_PATH='@s9s_mb_2u_lib.s9s_mb_2u(sch_1):page304_i59@pure_quanta.q_res(chips)',
 PATH='I59',
 DRAWING='@S9S_MB_2U_LIB.S9S_MB_2U(SCH_1):PAGE328',
 PHYS_PAGE='304',
 XY='(1700,675)',
 ROT='0',
 VER='2',
 PACK_TYPE='0402LF',
 LOCATION='PR2531',
 CDS_LIB='pure_quanta',
 CDS_PART_NAME='Q_RES_0402LF-10,1%,1/16W,EMPTYA',
 WATTAGE='1/16W',
 TOLERANCE='1%',
 MATERIAL='EMPTY',
 ROOM='HSC1_BOM2',
 VALUE='10',
 PRIM_FILE='./archive_libs/logical/q_res/chips/chips.prt';

PART_NAME
 PR2532 'Q_SP_RES4P-0.0003,1%,4W,SMLF,EA':
 ROOM='HSC1_BOM2';

SECTION_NUMBER 1
 '@S9S_MB_2U_LIB.S9S_MB_2U(SCH_1):PAGE328_I78@PURE_QUANTA.Q_SP_RES4P(CHIPS)':
 C_PATH='@s9s_mb_2u_lib.s9s_mb_2u(sch_1):page328_i78@pure_quanta.q_sp_res4p(chip~
s)',
 P_PATH='@s9s_mb_2u_lib.s9s_mb_2u(sch_1):page304_i78@pure_quanta.q_sp_res4p(chip~
s)',
 PATH='I78',
 DRAWING='@S9S_MB_2U_LIB.S9S_MB_2U(SCH_1):PAGE328',
 PHYS_PAGE='304',
 XY='(2150,3500)',
 ROT='0',
 VER='1',
 LOCATION='PR2532',
 CDS_LIB='pure_quanta',
 CDS_PART_NAME='Q_SP_RES4P-0.0003,1%,4W,SMLF,EA',
 PART_TYPE='SMLF',
 WATTAGE='4W',
 TOLERANCE='1%',
 MATERIAL='EMPTY',
 ROOM='HSC1_BOM2',
 VALUE='0.0003',
 PRIM_FILE='./archive_libs/logical/q_sp_res4p/chips/chips.prt';

PART_NAME
 PR2533 'Q_SP_RES4P-0.0003,1%,4W,SMLF,EA':
 ROOM='HSC1_BOM2';

SECTION_NUMBER 1
 '@S9S_MB_2U_LIB.S9S_MB_2U(SCH_1):PAGE328_I64@PURE_QUANTA.Q_SP_RES4P(CHIPS)':
 C_PATH='@s9s_mb_2u_lib.s9s_mb_2u(sch_1):page328_i64@pure_quanta.q_sp_res4p(chip~
s)',
 P_PATH='@s9s_mb_2u_lib.s9s_mb_2u(sch_1):page304_i64@pure_quanta.q_sp_res4p(chip~
s)',
 PATH='I64',
 DRAWING='@S9S_MB_2U_LIB.S9S_MB_2U(SCH_1):PAGE328',
 PHYS_PAGE='304',
 XY='(2150,2925)',
 ROT='0',
 VER='1',
 LOCATION='PR2533',
 CDS_LIB='pure_quanta',
 CDS_PART_NAME='Q_SP_RES4P-0.0003,1%,4W,SMLF,EA',
 PART_TYPE='SMLF',
 WATTAGE='4W',
 TOLERANCE='1%',
 MATERIAL='EMPTY',
 ROOM='HSC1_BOM2',
 VALUE='0.0003',
 PRIM_FILE='./archive_libs/logical/q_sp_res4p/chips/chips.prt';

PART_NAME
 PR2534 'Q_SP_RES4P-0.0003,1%,4W,SMLF,EA':
 ROOM='HSC1_BOM2';

SECTION_NUMBER 1
 '@S9S_MB_2U_LIB.S9S_MB_2U(SCH_1):PAGE328_I63@PURE_QUANTA.Q_SP_RES4P(CHIPS)':
 C_PATH='@s9s_mb_2u_lib.s9s_mb_2u(sch_1):page328_i63@pure_quanta.q_sp_res4p(chip~
s)',
 P_PATH='@s9s_mb_2u_lib.s9s_mb_2u(sch_1):page304_i63@pure_quanta.q_sp_res4p(chip~
s)',
 PATH='I63',
 DRAWING='@S9S_MB_2U_LIB.S9S_MB_2U(SCH_1):PAGE328',
 PHYS_PAGE='304',
 XY='(2150,2325)',
 ROT='0',
 VER='1',
 LOCATION='PR2534',
 CDS_LIB='pure_quanta',
 CDS_PART_NAME='Q_SP_RES4P-0.0003,1%,4W,SMLF,EA',
 PART_TYPE='SMLF',
 WATTAGE='4W',
 TOLERANCE='1%',
 MATERIAL='EMPTY',
 ROOM='HSC1_BOM2',
 VALUE='0.0003',
 PRIM_FILE='./archive_libs/logical/q_sp_res4p/chips/chips.prt';

PART_NAME
 PR2535 'Q_RES_0402LF-10,1%,1/16W,EMPTYA':
 ROOM='HSC1_BOM2';

SECTION_NUMBER 1
 '@S9S_MB_2U_LIB.S9S_MB_2U(SCH_1):PAGE328_I60@PURE_QUANTA.Q_RES(CHIPS)':
 C_PATH='@s9s_mb_2u_lib.s9s_mb_2u(sch_1):page328_i60@pure_quanta.q_res(chips)',
 P_PATH='@s9s_mb_2u_lib.s9s_mb_2u(sch_1):page304_i60@pure_quanta.q_res(chips)',
 PATH='I60',
 DRAWING='@S9S_MB_2U_LIB.S9S_MB_2U(SCH_1):PAGE328',
 PHYS_PAGE='304',
 XY='(2550,675)',
 ROT='0',
 VER='2',
 PACK_TYPE='0402LF',
 LOCATION='PR2535',
 CDS_LIB='pure_quanta',
 CDS_PART_NAME='Q_RES_0402LF-10,1%,1/16W,EMPTYA',
 WATTAGE='1/16W',
 TOLERANCE='1%',
 MATERIAL='EMPTY',
 ROOM='HSC1_BOM2',
 VALUE='10',
 PRIM_FILE='./archive_libs/logical/q_res/chips/chips.prt';

PART_NAME
 PR2536 'Q_RES_0402LF-10,1%,1/16W,EMPTYA':
 ROOM='HSC1_BOM2';

SECTION_NUMBER 1
 '@S9S_MB_2U_LIB.S9S_MB_2U(SCH_1):PAGE328_I61@PURE_QUANTA.Q_RES(CHIPS)':
 C_PATH='@s9s_mb_2u_lib.s9s_mb_2u(sch_1):page328_i61@pure_quanta.q_res(chips)',
 P_PATH='@s9s_mb_2u_lib.s9s_mb_2u(sch_1):page304_i61@pure_quanta.q_res(chips)',
 PATH='I61',
 DRAWING='@S9S_MB_2U_LIB.S9S_MB_2U(SCH_1):PAGE328',
 PHYS_PAGE='304',
 XY='(3425,675)',
 ROT='0',
 VER='2',
 PACK_TYPE='0402LF',
 LOCATION='PR2536',
 CDS_LIB='pure_quanta',
 CDS_PART_NAME='Q_RES_0402LF-10,1%,1/16W,EMPTYA',
 WATTAGE='1/16W',
 TOLERANCE='1%',
 MATERIAL='EMPTY',
 ROOM='HSC1_BOM2',
 VALUE='10',
 PRIM_FILE='./archive_libs/logical/q_res/chips/chips.prt';

PART_NAME
 PR2537 'Q_RES_0402LF-10,1%,1/16W,EMPTYA':;

SECTION_NUMBER 1
 '@S9S_MB_2U_LIB.S9S_MB_2U(SCH_1):PAGE328_I70@PURE_QUANTA.Q_RES(CHIPS)':
 C_PATH='@s9s_mb_2u_lib.s9s_mb_2u(sch_1):page328_i70@pure_quanta.q_res(chips)',
 P_PATH='@s9s_mb_2u_lib.s9s_mb_2u(sch_1):page304_i70@pure_quanta.q_res(chips)',
 PATH='I70',
 DRAWING='@S9S_MB_2U_LIB.S9S_MB_2U(SCH_1):PAGE328',
 PHYS_PAGE='304',
 XY='(4500,700)',
 ROT='0',
 VER='2',
 PACK_TYPE='0402LF',
 LOCATION='PR2537',
 CDS_LIB='pure_quanta',
 CDS_PART_NAME='Q_RES_0402LF-10,1%,1/16W,EMPTYA',
 WATTAGE='1/16W',
 TOLERANCE='1%',
 MATERIAL='EMPTY',
 VALUE='10',
 PRIM_FILE='./archive_libs/logical/q_res/chips/chips.prt';

PART_NAME
 PR2538 'Q_RES_0402LF-10,1%,1/16W,EMPTYA':
 ROOM='HSC1_BOM2';

SECTION_NUMBER 1
 '@S9S_MB_2U_LIB.S9S_MB_2U(SCH_1):PAGE328_I76@PURE_QUANTA.Q_RES(CHIPS)':
 C_PATH='@s9s_mb_2u_lib.s9s_mb_2u(sch_1):page328_i76@pure_quanta.q_res(chips)',
 P_PATH='@s9s_mb_2u_lib.s9s_mb_2u(sch_1):page304_i76@pure_quanta.q_res(chips)',
 PATH='I76',
 DRAWING='@S9S_MB_2U_LIB.S9S_MB_2U(SCH_1):PAGE328',
 PHYS_PAGE='304',
 XY='(4800,2125)',
 ROT='0',
 VER='2',
 PACK_TYPE='0402LF',
 LOCATION='PR2538',
 CDS_LIB='pure_quanta',
 CDS_PART_NAME='Q_RES_0402LF-10,1%,1/16W,EMPTYA',
 WATTAGE='1/16W',
 TOLERANCE='1%',
 MATERIAL='EMPTY',
 ROOM='HSC1_BOM2',
 VALUE='10',
 PRIM_FILE='./archive_libs/logical/q_res/chips/chips.prt';

PART_NAME
 PR2554 'Q_RES_2512LF-0.03,0.1%,1W,EMPTA':;

SECTION_NUMBER 1
 '@S9S_MB_2U_LIB.S9S_MB_2U(SCH_1):PAGE253_I81@PURE_QUANTA.Q_RES(CHIPS)':
 C_PATH='@s9s_mb_2u_lib.s9s_mb_2u(sch_1):page253_i81@pure_quanta.q_res(chips)',
 P_PATH='@s9s_mb_2u_lib.s9s_mb_2u(sch_1):page267_i81@pure_quanta.q_res(chips)',
 PATH='I81',
 DRAWING='@S9S_MB_2U_LIB.S9S_MB_2U(SCH_1):PAGE253',
 PHYS_PAGE='267',
 XY='(1875,1900)',
 ROT='0',
 VER='1',
 PACK_TYPE='2512LF',
 LOCATION='PR2554',
 CDS_LIB='pure_quanta',
 CDS_PART_NAME='Q_RES_2512LF-0.03,0.1%,1W,EMPTA',
 WATTAGE='1W',
 TOLERANCE='0.1%',
 MATERIAL='EMPTY',
 VALUE='0.03',
 PRIM_FILE='./archive_libs/logical/q_res/chips/chips.prt';

PART_NAME
 PR2556 'Q_RES_2512LF-0.03,0.1%,1W,EMPTA':;

SECTION_NUMBER 1
 '@S9S_MB_2U_LIB.S9S_MB_2U(SCH_1):PAGE271_I82@PURE_QUANTA.Q_RES(CHIPS)':
 C_PATH='@s9s_mb_2u_lib.s9s_mb_2u(sch_1):page271_i82@pure_quanta.q_res(chips)',
 P_PATH='@s9s_mb_2u_lib.s9s_mb_2u(sch_1):page285_i82@pure_quanta.q_res(chips)',
 PATH='I82',
 DRAWING='@S9S_MB_2U_LIB.S9S_MB_2U(SCH_1):PAGE271',
 PHYS_PAGE='285',
 XY='(1925,2325)',
 ROT='0',
 VER='1',
 PACK_TYPE='2512LF',
 LOCATION='PR2556',
 CDS_LIB='pure_quanta',
 CDS_PART_NAME='Q_RES_2512LF-0.03,0.1%,1W,EMPTA',
 WATTAGE='1W',
 TOLERANCE='0.1%',
 MATERIAL='EMPTY',
 VALUE='0.03',
 PRIM_FILE='./archive_libs/logical/q_res/chips/chips.prt';

PART_NAME
 PR2718 'Q_RES_0402LF-8.87K,1%,1/16W,EMA':;

SECTION_NUMBER 1
 '@S9S_MB_2U_LIB.S9S_MB_2U(SCH_1):PAGE265_I3@PURE_QUANTA.Q_RES(CHIPS)':
 C_PATH='@s9s_mb_2u_lib.s9s_mb_2u(sch_1):page265_i3@pure_quanta.q_res(chips)',
 P_PATH='@s9s_mb_2u_lib.s9s_mb_2u(sch_1):page279_i3@pure_quanta.q_res(chips)',
 PATH='I3',
 DRAWING='@S9S_MB_2U_LIB.S9S_MB_2U(SCH_1):PAGE265',
 PHYS_PAGE='279',
 XY='(-8775,1325)',
 ROT='2',
 VER='2',
 PACK_TYPE='0402LF',
 LOCATION='PR2718',
 CDS_LIB='pure_quanta',
 CDS_PART_NAME='Q_RES_0402LF-8.87K,1%,1/16W,EMA',
 WATTAGE='1/16W',
 TOLERANCE='1%',
 MATERIAL='EMPTY',
 VALUE='8.87K',
 PRIM_FILE='./archive_libs/logical/q_res/chips/chips.prt';

PART_NAME
 PR3002 'Q_RES_0402LF-0,5%,1/16W,CHIP,CA':;

SECTION_NUMBER 1
 '@S9S_MB_2U_LIB.S9S_MB_2U(SCH_1):PAGE303_I54@PURE_QUANTA.Q_RES(CHIPS)':
 C_PATH='@s9s_mb_2u_lib.s9s_mb_2u(sch_1):page303_i54@pure_quanta.q_res(chips)',
 P_PATH='@s9s_mb_2u_lib.s9s_mb_2u(sch_1):page301_i54@pure_quanta.q_res(chips)',
 PATH='I54',
 DRAWING='@S9S_MB_2U_LIB.S9S_MB_2U(SCH_1):PAGE303',
 PHYS_PAGE='301',
 XY='(-13175,1725)',
 ROT='0',
 VER='1',
 PACK_TYPE='0402LF',
 LOCATION='PR3002',
 CDS_LIB='pure_quanta',
 CDS_PART_NAME='Q_RES_0402LF-0,5%,1/16W,CHIP,CA',
 WATTAGE='1/16W',
 TOLERANCE='5%',
 MATERIAL='CHIP',
 VALUE='0',
 PRIM_FILE='./archive_libs/logical/q_res/chips/chips.prt';

PART_NAME
 PR3335 'Q_RES_0402LF-30.1K,1%,1/16W,CHA':;

SECTION_NUMBER 1
 '@S9S_MB_2U_LIB.S9S_MB_2U(SCH_1):PAGE267_I18@PURE_QUANTA.Q_RES(CHIPS)':
 C_PATH='@s9s_mb_2u_lib.s9s_mb_2u(sch_1):page267_i18@pure_quanta.q_res(chips)',
 P_PATH='@s9s_mb_2u_lib.s9s_mb_2u(sch_1):page281_i18@pure_quanta.q_res(chips)',
 PATH='I18',
 DRAWING='@S9S_MB_2U_LIB.S9S_MB_2U(SCH_1):PAGE267',
 PHYS_PAGE='281',
 XY='(-9650,3350)',
 ROT='0',
 VER='1',
 PACK_TYPE='0402LF',
 LOCATION='PR3335',
 CDS_LIB='pure_quanta',
 CDS_PART_NAME='Q_RES_0402LF-30.1K,1%,1/16W,CHA',
 WATTAGE='1/16W',
 TOLERANCE='1%',
 MATERIAL='CHIP',
 VALUE='30.1K',
 PRIM_FILE='./archive_libs/logical/q_res/chips/chips.prt';

PART_NAME
 PR3336 'Q_RES_0402LF-30.1K,1%,1/16W,CHA':;

SECTION_NUMBER 1
 '@S9S_MB_2U_LIB.S9S_MB_2U(SCH_1):PAGE285_I18@PURE_QUANTA.Q_RES(CHIPS)':
 C_PATH='@s9s_mb_2u_lib.s9s_mb_2u(sch_1):page285_i18@pure_quanta.q_res(chips)',
 P_PATH='@s9s_mb_2u_lib.s9s_mb_2u(sch_1):page299_i18@pure_quanta.q_res(chips)',
 PATH='I18',
 DRAWING='@S9S_MB_2U_LIB.S9S_MB_2U(SCH_1):PAGE285',
 PHYS_PAGE='299',
 XY='(-8950,2900)',
 ROT='0',
 VER='1',
 PACK_TYPE='0402LF',
 LOCATION='PR3336',
 CDS_LIB='pure_quanta',
 CDS_PART_NAME='Q_RES_0402LF-30.1K,1%,1/16W,CHA',
 WATTAGE='1/16W',
 TOLERANCE='1%',
 MATERIAL='CHIP',
 VALUE='30.1K',
 PRIM_FILE='./archive_libs/logical/q_res/chips/chips.prt';

PART_NAME
 PR3337 'Q_RES_0402LF-0,5%,1/16W,CHIP,CA':;

SECTION_NUMBER 1
 '@S9S_MB_2U_LIB.S9S_MB_2U(SCH_1):PAGE244_I10@PURE_QUANTA.Q_RES(CHIPS)':
 C_PATH='@s9s_mb_2u_lib.s9s_mb_2u(sch_1):page244_i10@pure_quanta.q_res(chips)',
 P_PATH='@s9s_mb_2u_lib.s9s_mb_2u(sch_1):page258_i10@pure_quanta.q_res(chips)',
 PATH='I10',
 DRAWING='@S9S_MB_2U_LIB.S9S_MB_2U(SCH_1):PAGE244',
 PHYS_PAGE='258',
 XY='(-5550,5900)',
 ROT='0',
 VER='1',
 PACK_TYPE='0402LF',
 LOCATION='PR3337',
 CDS_LIB='pure_quanta',
 CDS_PART_NAME='Q_RES_0402LF-0,5%,1/16W,CHIP,CA',
 WATTAGE='1/16W',
 TOLERANCE='5%',
 MATERIAL='CHIP',
 VALUE='0',
 PRIM_FILE='./archive_libs/logical/q_res/chips/chips.prt';

PART_NAME
 PR3338 'Q_RES_0402LF-0,5%,1/16W,CHIP,CA':;

SECTION_NUMBER 1
 '@S9S_MB_2U_LIB.S9S_MB_2U(SCH_1):PAGE286_I13@PURE_QUANTA.Q_RES(CHIPS)':
 C_PATH='@s9s_mb_2u_lib.s9s_mb_2u(sch_1):page286_i13@pure_quanta.q_res(chips)',
 P_PATH='@s9s_mb_2u_lib.s9s_mb_2u(sch_1):page300_i13@pure_quanta.q_res(chips)',
 PATH='I13',
 DRAWING='@S9S_MB_2U_LIB.S9S_MB_2U(SCH_1):PAGE286',
 PHYS_PAGE='300',
 XY='(3625,6725)',
 ROT='0',
 VER='2',
 PACK_TYPE='0402LF',
 LOCATION='PR3338',
 CDS_LIB='pure_quanta',
 CDS_PART_NAME='Q_RES_0402LF-0,5%,1/16W,CHIP,CA',
 WATTAGE='1/16W',
 TOLERANCE='5%',
 MATERIAL='CHIP',
 VALUE='0',
 PRIM_FILE='./archive_libs/logical/q_res/chips/chips.prt';

PART_NAME
 PR3339 'Q_RES_0402LF-0,5%,1/16W,CHIP,CA':;

SECTION_NUMBER 1
 '@S9S_MB_2U_LIB.S9S_MB_2U(SCH_1):PAGE268_I10@PURE_QUANTA.Q_RES(CHIPS)':
 C_PATH='@s9s_mb_2u_lib.s9s_mb_2u(sch_1):page268_i10@pure_quanta.q_res(chips)',
 P_PATH='@s9s_mb_2u_lib.s9s_mb_2u(sch_1):page282_i10@pure_quanta.q_res(chips)',
 PATH='I10',
 DRAWING='@S9S_MB_2U_LIB.S9S_MB_2U(SCH_1):PAGE268',
 PHYS_PAGE='282',
 XY='(-8225,9350)',
 ROT='0',
 VER='2',
 PACK_TYPE='0402LF',
 LOCATION='PR3339',
 CDS_LIB='pure_quanta',
 CDS_PART_NAME='Q_RES_0402LF-0,5%,1/16W,CHIP,CA',
 WATTAGE='1/16W',
 TOLERANCE='5%',
 MATERIAL='CHIP',
 VALUE='0',
 PRIM_FILE='./archive_libs/logical/q_res/chips/chips.prt';

PART_NAME
 PR3780 'Q_RES_0402LF-5.36K,1%,1/16W,CHA':
 ROOM='NIC1_P3V3_BOM1';

SECTION_NUMBER 1
 '@S9S_MB_2U_LIB.S9S_MB_2U(SCH_1):PAGE153_I60@PURE_QUANTA.Q_RES(CHIPS)':
 C_PATH='@s9s_mb_2u_lib.s9s_mb_2u(sch_1):page153_i60@pure_quanta.q_res(chips)',
 P_PATH='@s9s_mb_2u_lib.s9s_mb_2u(sch_1):page156_i60@pure_quanta.q_res(chips)',
 PATH='I60',
 DRAWING='@S9S_MB_2U_LIB.S9S_MB_2U(SCH_1):PAGE153',
 PHYS_PAGE='156',
 XY='(7000,12300)',
 ROT='0',
 VER='2',
 PACK_TYPE='0402LF',
 LOCATION='PR3780',
 CDS_LIB='pure_quanta',
 CDS_PART_NAME='Q_RES_0402LF-5.36K,1%,1/16W,CHA',
 WATTAGE='1/16W',
 TOLERANCE='1%',
 MATERIAL='CHIP',
 ROOM='NIC1_P3V3_BOM1',
 VALUE='5.36K',
 PRIM_FILE='./archive_libs/logical/q_res/chips/chips.prt';

PART_NAME
 PR3781 'Q_RES_0402LF-845,1%,1/16W,EMPTA':
 ROOM='NIC1_P12V_MAM_MAM_BOM1';

SECTION_NUMBER 1
 '@S9S_MB_2U_LIB.S9S_MB_2U(SCH_1):PAGE153_I80@PURE_QUANTA.Q_RES(CHIPS)':
 C_PATH='@s9s_mb_2u_lib.s9s_mb_2u(sch_1):page153_i80@pure_quanta.q_res(chips)',
 P_PATH='@s9s_mb_2u_lib.s9s_mb_2u(sch_1):page156_i80@pure_quanta.q_res(chips)',
 PATH='I80',
 DRAWING='@S9S_MB_2U_LIB.S9S_MB_2U(SCH_1):PAGE153',
 ROOM1='NIC1_P12V_MAM_TIC_BOM2',
 PHYS_PAGE='156',
 XY='(8375,10300)',
 ROT='0',
 VER='2',
 PACK_TYPE='0402LF',
 LOCATION='PR3781',
 CDS_LIB='pure_quanta',
 CDS_PART_NAME='Q_RES_0402LF-845,1%,1/16W,EMPTA',
 WATTAGE='1/16W',
 TOLERANCE='1%',
 MATERIAL='EMPTY',
 ROOM='NIC1_P12V_MAM_MAM_BOM1',
 VALUE='845',
 PRIM_FILE='./archive_libs/logical/q_res/chips/chips.prt';

PART_NAME
 PR3782 'Q_RES_0402LF-10,1%,1/16W,CHIP,A':
 ROOM='NIC1_P3V3_BOM1';

SECTION_NUMBER 1
 '@S9S_MB_2U_LIB.S9S_MB_2U(SCH_1):PAGE131_I92@PURE_QUANTA.Q_RES(CHIPS)':
 C_PATH='@s9s_mb_2u_lib.s9s_mb_2u(sch_1):page131_i92@pure_quanta.q_res(chips)',
 P_PATH='@s9s_mb_2u_lib.s9s_mb_2u(sch_1):page162_i92@pure_quanta.q_res(chips)',
 PATH='I92',
 DRAWING='@S9S_MB_2U_LIB.S9S_MB_2U(SCH_1):PAGE131',
 PHYS_PAGE='162',
 XY='(275,2525)',
 ROT='0',
 VER='2',
 PACK_TYPE='0402LF',
 LOCATION='PR3782',
 CDS_LIB='pure_quanta',
 CDS_PART_NAME='Q_RES_0402LF-10,1%,1/16W,CHIP,A',
 WATTAGE='1/16W',
 TOLERANCE='1%',
 MATERIAL='CHIP',
 ROOM='NIC1_P3V3_BOM1',
 VALUE='10',
 PRIM_FILE='./archive_libs/logical/q_res/chips/chips.prt';

PART_NAME
 PR3786 'Q_RES_0402LF-160K,1%,1/16W,EMPA':
 ROOM='NIC1_P12V_MAM_MAM_BOM1';

SECTION_NUMBER 1
 '@S9S_MB_2U_LIB.S9S_MB_2U(SCH_1):PAGE153_I42@PURE_QUANTA.Q_RES(CHIPS)':
 C_PATH='@s9s_mb_2u_lib.s9s_mb_2u(sch_1):page153_i42@pure_quanta.q_res(chips)',
 P_PATH='@s9s_mb_2u_lib.s9s_mb_2u(sch_1):page156_i42@pure_quanta.q_res(chips)',
 PATH='I42',
 DRAWING='@S9S_MB_2U_LIB.S9S_MB_2U(SCH_1):PAGE153',
 ROOM1='NIC1_P12V_MAM_TIC_BOM2',
 PHYS_PAGE='156',
 XY='(5925,11125)',
 ROT='0',
 VER='2',
 PACK_TYPE='0402LF',
 LOCATION='PR3786',
 CDS_LIB='pure_quanta',
 CDS_PART_NAME='Q_RES_0402LF-160K,1%,1/16W,EMPA',
 WATTAGE='1/16W',
 TOLERANCE='1%',
 MATERIAL='EMPTY',
 ROOM='NIC1_P12V_MAM_MAM_BOM1',
 VALUE='160K',
 PRIM_FILE='./archive_libs/logical/q_res/chips/chips.prt';

PART_NAME
 PR3787 'Q_RES_0402LF-6.8K,1%,1/16W,EMPA':
 ROOM='NIC1_P12V_MAM_MAM_BOM1';

SECTION_NUMBER 1
 '@S9S_MB_2U_LIB.S9S_MB_2U(SCH_1):PAGE153_I41@PURE_QUANTA.Q_RES(CHIPS)':
 C_PATH='@s9s_mb_2u_lib.s9s_mb_2u(sch_1):page153_i41@pure_quanta.q_res(chips)',
 P_PATH='@s9s_mb_2u_lib.s9s_mb_2u(sch_1):page156_i41@pure_quanta.q_res(chips)',
 PATH='I41',
 DRAWING='@S9S_MB_2U_LIB.S9S_MB_2U(SCH_1):PAGE153',
 ROOM1='NIC1_P12V_MAM_TIC_BOM2',
 PHYS_PAGE='156',
 XY='(5925,10450)',
 ROT='0',
 VER='2',
 PACK_TYPE='0402LF',
 LOCATION='PR3787',
 CDS_LIB='pure_quanta',
 CDS_PART_NAME='Q_RES_0402LF-6.8K,1%,1/16W,EMPA',
 WATTAGE='1/16W',
 TOLERANCE='1%',
 MATERIAL='EMPTY',
 ROOM='NIC1_P12V_MAM_MAM_BOM1',
 VALUE='6.8K',
 PRIM_FILE='./archive_libs/logical/q_res/chips/chips.prt';

PART_NAME
 PR3788 'Q_RES_0402LF-15K,1%,1/16W,EMPTA':
 ROOM='NIC1_P12V_MAM_MAM_BOM1';

SECTION_NUMBER 1
 '@S9S_MB_2U_LIB.S9S_MB_2U(SCH_1):PAGE153_I33@PURE_QUANTA.Q_RES(CHIPS)':
 C_PATH='@s9s_mb_2u_lib.s9s_mb_2u(sch_1):page153_i33@pure_quanta.q_res(chips)',
 P_PATH='@s9s_mb_2u_lib.s9s_mb_2u(sch_1):page156_i33@pure_quanta.q_res(chips)',
 PATH='I33',
 DRAWING='@S9S_MB_2U_LIB.S9S_MB_2U(SCH_1):PAGE153',
 ROOM1='NIC1_P12V_MAM_TIC_BOM2',
 PHYS_PAGE='156',
 XY='(5925,10175)',
 ROT='0',
 VER='2',
 PACK_TYPE='0402LF',
 LOCATION='PR3788',
 CDS_LIB='pure_quanta',
 CDS_PART_NAME='Q_RES_0402LF-15K,1%,1/16W,EMPTA',
 WATTAGE='1/16W',
 TOLERANCE='1%',
 MATERIAL='EMPTY',
 ROOM='NIC1_P12V_MAM_MAM_BOM1',
 VALUE='15K',
 PRIM_FILE='./archive_libs/logical/q_res/chips/chips.prt';

PART_NAME
 PR3789 'Q_RES_0402LF-25.5K,1%,1/16W,CHA':
 ROOM='NIC1_P3V3_BOM1';

SECTION_NUMBER 1
 '@S9S_MB_2U_LIB.S9S_MB_2U(SCH_1):PAGE153_I70@PURE_QUANTA.Q_RES(CHIPS)':
 C_PATH='@s9s_mb_2u_lib.s9s_mb_2u(sch_1):page153_i70@pure_quanta.q_res(chips)',
 P_PATH='@s9s_mb_2u_lib.s9s_mb_2u(sch_1):page156_i70@pure_quanta.q_res(chips)',
 PATH='I70',
 DRAWING='@S9S_MB_2U_LIB.S9S_MB_2U(SCH_1):PAGE153',
 PHYS_PAGE='156',
 XY='(6150,13275)',
 ROT='0',
 VER='2',
 PACK_TYPE='0402LF',
 LOCATION='PR3789',
 CDS_LIB='pure_quanta',
 CDS_PART_NAME='Q_RES_0402LF-25.5K,1%,1/16W,CHA',
 WATTAGE='1/16W',
 TOLERANCE='1%',
 MATERIAL='CHIP',
 ROOM='NIC1_P3V3_BOM1',
 VALUE='25.5K',
 PRIM_FILE='./archive_libs/logical/q_res/chips/chips.prt';

PART_NAME
 PR3790 'Q_RES_0402LF-7.15K,1%,1/16W,CHA':
 ROOM='NIC1_P3V3_BOM1';

SECTION_NUMBER 1
 '@S9S_MB_2U_LIB.S9S_MB_2U(SCH_1):PAGE153_I68@PURE_QUANTA.Q_RES(CHIPS)':
 C_PATH='@s9s_mb_2u_lib.s9s_mb_2u(sch_1):page153_i68@pure_quanta.q_res(chips)',
 P_PATH='@s9s_mb_2u_lib.s9s_mb_2u(sch_1):page156_i68@pure_quanta.q_res(chips)',
 PATH='I68',
 DRAWING='@S9S_MB_2U_LIB.S9S_MB_2U(SCH_1):PAGE153',
 PHYS_PAGE='156',
 XY='(6150,12550)',
 ROT='0',
 VER='2',
 PACK_TYPE='0402LF',
 LOCATION='PR3790',
 CDS_LIB='pure_quanta',
 CDS_PART_NAME='Q_RES_0402LF-7.15K,1%,1/16W,CHA',
 WATTAGE='1/16W',
 TOLERANCE='1%',
 MATERIAL='CHIP',
 ROOM='NIC1_P3V3_BOM1',
 VALUE='7.15K',
 PRIM_FILE='./archive_libs/logical/q_res/chips/chips.prt';

PART_NAME
 PR3791 'Q_RES_0402LF-15K,1%,1/16W,CHIPA':
 ROOM='NIC1_P3V3_BOM1';

SECTION_NUMBER 1
 '@S9S_MB_2U_LIB.S9S_MB_2U(SCH_1):PAGE153_I58@PURE_QUANTA.Q_RES(CHIPS)':
 C_PATH='@s9s_mb_2u_lib.s9s_mb_2u(sch_1):page153_i58@pure_quanta.q_res(chips)',
 P_PATH='@s9s_mb_2u_lib.s9s_mb_2u(sch_1):page156_i58@pure_quanta.q_res(chips)',
 PATH='I58',
 DRAWING='@S9S_MB_2U_LIB.S9S_MB_2U(SCH_1):PAGE153',
 PHYS_PAGE='156',
 XY='(6150,12275)',
 ROT='0',
 VER='2',
 PACK_TYPE='0402LF',
 LOCATION='PR3791',
 CDS_LIB='pure_quanta',
 CDS_PART_NAME='Q_RES_0402LF-15K,1%,1/16W,CHIPA',
 WATTAGE='1/16W',
 TOLERANCE='1%',
 MATERIAL='CHIP',
 ROOM='NIC1_P3V3_BOM1',
 VALUE='15K',
 PRIM_FILE='./archive_libs/logical/q_res/chips/chips.prt';

PART_NAME
 PR3792 'Q_RES_0402LF-10,1%,1/16W,EMPTYA':
 ROOM='NIC1_P12V_MAM_MAM_BOM1';

SECTION_NUMBER 1
 '@S9S_MB_2U_LIB.S9S_MB_2U(SCH_1):PAGE153_I56@PURE_QUANTA.Q_RES(CHIPS)':
 C_PATH='@s9s_mb_2u_lib.s9s_mb_2u(sch_1):page153_i56@pure_quanta.q_res(chips)',
 P_PATH='@s9s_mb_2u_lib.s9s_mb_2u(sch_1):page156_i56@pure_quanta.q_res(chips)',
 PATH='I56',
 DRAWING='@S9S_MB_2U_LIB.S9S_MB_2U(SCH_1):PAGE153',
 ROOM1='NIC1_P12V_MAM_TIC_BOM2',
 PHYS_PAGE='156',
 XY='(6250,11425)',
 ROT='0',
 VER='2',
 PACK_TYPE='0402LF',
 LOCATION='PR3792',
 CDS_LIB='pure_quanta',
 CDS_PART_NAME='Q_RES_0402LF-10,1%,1/16W,EMPTYA',
 WATTAGE='1/16W',
 TOLERANCE='1%',
 MATERIAL='EMPTY',
 ROOM='NIC1_P12V_MAM_MAM_BOM1',
 VALUE='10',
 PRIM_FILE='./archive_libs/logical/q_res/chips/chips.prt';

PART_NAME
 PR3795 'Q_RES_0402LF-25.5K,1%,1/16W,CHA':
 ROOM='NIC1_P3V3_BOM1';

SECTION_NUMBER 1
 '@S9S_MB_2U_LIB.S9S_MB_2U(SCH_1):PAGE131_I53@PURE_QUANTA.Q_RES(CHIPS)':
 C_PATH='@s9s_mb_2u_lib.s9s_mb_2u(sch_1):page131_i53@pure_quanta.q_res(chips)',
 P_PATH='@s9s_mb_2u_lib.s9s_mb_2u(sch_1):page162_i53@pure_quanta.q_res(chips)',
 PATH='I53',
 DRAWING='@S9S_MB_2U_LIB.S9S_MB_2U(SCH_1):PAGE131',
 PHYS_PAGE='162',
 XY='(-50,2275)',
 ROT='0',
 VER='2',
 PACK_TYPE='0402LF',
 LOCATION='PR3795',
 CDS_LIB='pure_quanta',
 CDS_PART_NAME='Q_RES_0402LF-25.5K,1%,1/16W,CHA',
 WATTAGE='1/16W',
 TOLERANCE='1%',
 MATERIAL='CHIP',
 ROOM='NIC1_P3V3_BOM1',
 VALUE='25.5K',
 PRIM_FILE='./archive_libs/logical/q_res/chips/chips.prt';

PART_NAME
 PR3798 'Q_RES_0402LF-10,1%,1/16W,CHIP,A':
 ROOM='NIC1_P3V3_BOM1';

SECTION_NUMBER 1
 '@S9S_MB_2U_LIB.S9S_MB_2U(SCH_1):PAGE153_I73@PURE_QUANTA.Q_RES(CHIPS)':
 C_PATH='@s9s_mb_2u_lib.s9s_mb_2u(sch_1):page153_i73@pure_quanta.q_res(chips)',
 P_PATH='@s9s_mb_2u_lib.s9s_mb_2u(sch_1):page156_i73@pure_quanta.q_res(chips)',
 PATH='I73',
 DRAWING='@S9S_MB_2U_LIB.S9S_MB_2U(SCH_1):PAGE153',
 PHYS_PAGE='156',
 XY='(6475,13525)',
 ROT='0',
 VER='2',
 PACK_TYPE='0402LF',
 LOCATION='PR3798',
 CDS_LIB='pure_quanta',
 CDS_PART_NAME='Q_RES_0402LF-10,1%,1/16W,CHIP,A',
 WATTAGE='1/16W',
 TOLERANCE='1%',
 MATERIAL='CHIP',
 ROOM='NIC1_P3V3_BOM1',
 VALUE='10',
 PRIM_FILE='./archive_libs/logical/q_res/chips/chips.prt';

PART_NAME
 PR3805 'Q_RES_0402LF-160K,1%,1/16W,EMPA':
 ROOM='NIC1_P12V_MAM_MAM_BOM1';

SECTION_NUMBER 1
 '@S9S_MB_2U_LIB.S9S_MB_2U(SCH_1):PAGE131_I33@PURE_QUANTA.Q_RES(CHIPS)':
 C_PATH='@s9s_mb_2u_lib.s9s_mb_2u(sch_1):page131_i33@pure_quanta.q_res(chips)',
 P_PATH='@s9s_mb_2u_lib.s9s_mb_2u(sch_1):page162_i33@pure_quanta.q_res(chips)',
 PATH='I33',
 DRAWING='@S9S_MB_2U_LIB.S9S_MB_2U(SCH_1):PAGE131',
 ROOM1='NIC1_P12V_MAM_TIC_BOM2',
 PHYS_PAGE='162',
 XY='(-175,-100)',
 ROT='0',
 VER='2',
 PACK_TYPE='0402LF',
 LOCATION='PR3805',
 CDS_LIB='pure_quanta',
 CDS_PART_NAME='Q_RES_0402LF-160K,1%,1/16W,EMPA',
 WATTAGE='1/16W',
 TOLERANCE='1%',
 MATERIAL='EMPTY',
 ROOM='NIC1_P12V_MAM_MAM_BOM1',
 VALUE='160K',
 PRIM_FILE='./archive_libs/logical/q_res/chips/chips.prt';

PART_NAME
 PR3806 'Q_RES_0402LF-6.8K,1%,1/16W,EMPA':
 ROOM='NIC1_P12V_MAM_MAM_BOM1';

SECTION_NUMBER 1
 '@S9S_MB_2U_LIB.S9S_MB_2U(SCH_1):PAGE131_I32@PURE_QUANTA.Q_RES(CHIPS)':
 C_PATH='@s9s_mb_2u_lib.s9s_mb_2u(sch_1):page131_i32@pure_quanta.q_res(chips)',
 P_PATH='@s9s_mb_2u_lib.s9s_mb_2u(sch_1):page162_i32@pure_quanta.q_res(chips)',
 PATH='I32',
 DRAWING='@S9S_MB_2U_LIB.S9S_MB_2U(SCH_1):PAGE131',
 ROOM1='NIC1_P12V_MAM_TIC_BOM2',
 PHYS_PAGE='162',
 XY='(-175,-775)',
 ROT='0',
 VER='2',
 PACK_TYPE='0402LF',
 LOCATION='PR3806',
 CDS_LIB='pure_quanta',
 CDS_PART_NAME='Q_RES_0402LF-6.8K,1%,1/16W,EMPA',
 WATTAGE='1/16W',
 TOLERANCE='1%',
 MATERIAL='EMPTY',
 ROOM='NIC1_P12V_MAM_MAM_BOM1',
 VALUE='6.8K',
 PRIM_FILE='./archive_libs/logical/q_res/chips/chips.prt';

PART_NAME
 PR3812 'Q_RES_0402LF-15K,1%,1/16W,CHIPA':
 ROOM='NIC1_P3V3_BOM1';

SECTION_NUMBER 1
 '@S9S_MB_2U_LIB.S9S_MB_2U(SCH_1):PAGE131_I48@PURE_QUANTA.Q_RES(CHIPS)':
 C_PATH='@s9s_mb_2u_lib.s9s_mb_2u(sch_1):page131_i48@pure_quanta.q_res(chips)',
 P_PATH='@s9s_mb_2u_lib.s9s_mb_2u(sch_1):page162_i48@pure_quanta.q_res(chips)',
 PATH='I48',
 DRAWING='@S9S_MB_2U_LIB.S9S_MB_2U(SCH_1):PAGE131',
 PHYS_PAGE='162',
 XY='(-50,1275)',
 ROT='0',
 VER='2',
 PACK_TYPE='0402LF',
 LOCATION='PR3812',
 CDS_LIB='pure_quanta',
 CDS_PART_NAME='Q_RES_0402LF-15K,1%,1/16W,CHIPA',
 WATTAGE='1/16W',
 TOLERANCE='1%',
 MATERIAL='CHIP',
 ROOM='NIC1_P3V3_BOM1',
 VALUE='15K',
 PRIM_FILE='./archive_libs/logical/q_res/chips/chips.prt';

PART_NAME
 PR3821 'Q_RES_0402LF-30.1K,1%,1/16W,EMA':
 ROOM='NIC1_P12V_MAM_MAM_BOM1';

SECTION_NUMBER 1
 '@S9S_MB_2U_LIB.S9S_MB_2U(SCH_1):PAGE131_I59@PURE_QUANTA.Q_RES(CHIPS)':
 C_PATH='@s9s_mb_2u_lib.s9s_mb_2u(sch_1):page131_i59@pure_quanta.q_res(chips)',
 P_PATH='@s9s_mb_2u_lib.s9s_mb_2u(sch_1):page162_i59@pure_quanta.q_res(chips)',
 PATH='I59',
 DRAWING='@S9S_MB_2U_LIB.S9S_MB_2U(SCH_1):PAGE131',
 ROOM1='NIC1_P12V_MAM_TIC_BOM2',
 PHYS_PAGE='162',
 XY='(675,-1025)',
 ROT='0',
 VER='2',
 PACK_TYPE='0402LF',
 LOCATION='PR3821',
 CDS_LIB='pure_quanta',
 CDS_PART_NAME='Q_RES_0402LF-30.1K,1%,1/16W,EMA',
 WATTAGE='1/16W',
 TOLERANCE='1%',
 MATERIAL='EMPTY',
 ROOM='NIC1_P12V_MAM_MAM_BOM1',
 VALUE='30.1K',
 PRIM_FILE='./archive_libs/logical/q_res/chips/chips.prt';

PART_NAME
 PR3822 'Q_RES_0402LF-5.36K,1%,1/16W,CHA':
 ROOM='NIC1_P3V3_BOM1';

SECTION_NUMBER 1
 '@S9S_MB_2U_LIB.S9S_MB_2U(SCH_1):PAGE131_I89@PURE_QUANTA.Q_RES(CHIPS)':
 C_PATH='@s9s_mb_2u_lib.s9s_mb_2u(sch_1):page131_i89@pure_quanta.q_res(chips)',
 P_PATH='@s9s_mb_2u_lib.s9s_mb_2u(sch_1):page162_i89@pure_quanta.q_res(chips)',
 PATH='I89',
 DRAWING='@S9S_MB_2U_LIB.S9S_MB_2U(SCH_1):PAGE131',
 PHYS_PAGE='162',
 XY='(800,1300)',
 ROT='0',
 VER='2',
 PACK_TYPE='0402LF',
 LOCATION='PR3822',
 CDS_LIB='pure_quanta',
 CDS_PART_NAME='Q_RES_0402LF-5.36K,1%,1/16W,CHA',
 WATTAGE='1/16W',
 TOLERANCE='1%',
 MATERIAL='CHIP',
 ROOM='NIC1_P3V3_BOM1',
 VALUE='5.36K',
 PRIM_FILE='./archive_libs/logical/q_res/chips/chips.prt';

PART_NAME
 PR3823 'Q_RES_0402LF-845,1%,1/16W,EMPTA':
 ROOM='NIC1_P12V_MAM_MAM_BOM1';

SECTION_NUMBER 1
 '@S9S_MB_2U_LIB.S9S_MB_2U(SCH_1):PAGE131_I72@PURE_QUANTA.Q_RES(CHIPS)':
 C_PATH='@s9s_mb_2u_lib.s9s_mb_2u(sch_1):page131_i72@pure_quanta.q_res(chips)',
 P_PATH='@s9s_mb_2u_lib.s9s_mb_2u(sch_1):page162_i72@pure_quanta.q_res(chips)',
 PATH='I72',
 DRAWING='@S9S_MB_2U_LIB.S9S_MB_2U(SCH_1):PAGE131',
 ROOM1='NIC1_P12V_MAM_TIC_BOM2',
 PHYS_PAGE='162',
 XY='(2275,-900)',
 ROT='0',
 VER='2',
 PACK_TYPE='0402LF',
 LOCATION='PR3823',
 CDS_LIB='pure_quanta',
 CDS_PART_NAME='Q_RES_0402LF-845,1%,1/16W,EMPTA',
 WATTAGE='1/16W',
 TOLERANCE='1%',
 MATERIAL='EMPTY',
 ROOM='NIC1_P12V_MAM_MAM_BOM1',
 VALUE='845',
 PRIM_FILE='./archive_libs/logical/q_res/chips/chips.prt';

PART_NAME
 PR3824 'Q_RES_0402LF-4.53K,1%,1/16W,CHA':
 ROOM='NIC1_P3V3_BOM1';

SECTION_NUMBER 1
 '@S9S_MB_2U_LIB.S9S_MB_2U(SCH_1):PAGE131_I95@PURE_QUANTA.Q_RES(CHIPS)':
 C_PATH='@s9s_mb_2u_lib.s9s_mb_2u(sch_1):page131_i95@pure_quanta.q_res(chips)',
 P_PATH='@s9s_mb_2u_lib.s9s_mb_2u(sch_1):page162_i95@pure_quanta.q_res(chips)',
 PATH='I95',
 DRAWING='@S9S_MB_2U_LIB.S9S_MB_2U(SCH_1):PAGE131',
 PHYS_PAGE='162',
 XY='(2400,1450)',
 ROT='0',
 VER='2',
 PACK_TYPE='0402LF',
 LOCATION='PR3824',
 CDS_LIB='pure_quanta',
 CDS_PART_NAME='Q_RES_0402LF-4.53K,1%,1/16W,CHA',
 WATTAGE='1/16W',
 TOLERANCE='1%',
 MATERIAL='CHIP',
 ROOM='NIC1_P3V3_BOM1',
 VALUE='4.53K',
 PRIM_FILE='./archive_libs/logical/q_res/chips/chips.prt';

PART_NAME
 PR3828 'Q_RES_0402LF-15K,1%,1/16W,EMPTA':
 ROOM='NIC1_P12V_MAM_MAM_BOM1';

SECTION_NUMBER 1
 '@S9S_MB_2U_LIB.S9S_MB_2U(SCH_1):PAGE131_I29@PURE_QUANTA.Q_RES(CHIPS)':
 C_PATH='@s9s_mb_2u_lib.s9s_mb_2u(sch_1):page131_i29@pure_quanta.q_res(chips)',
 P_PATH='@s9s_mb_2u_lib.s9s_mb_2u(sch_1):page162_i29@pure_quanta.q_res(chips)',
 PATH='I29',
 DRAWING='@S9S_MB_2U_LIB.S9S_MB_2U(SCH_1):PAGE131',
 ROOM1='NIC1_P12V_MAM_TIC_BOM2',
 PHYS_PAGE='162',
 XY='(-175,-1050)',
 ROT='0',
 VER='2',
 PACK_TYPE='0402LF',
 LOCATION='PR3828',
 CDS_LIB='pure_quanta',
 CDS_PART_NAME='Q_RES_0402LF-15K,1%,1/16W,EMPTA',
 WATTAGE='1/16W',
 TOLERANCE='1%',
 MATERIAL='EMPTY',
 ROOM='NIC1_P12V_MAM_MAM_BOM1',
 VALUE='15K',
 PRIM_FILE='./archive_libs/logical/q_res/chips/chips.prt';

PART_NAME
 PR3829 'Q_RES_0402LF-7.15K,1%,1/16W,CHA':
 ROOM='NIC1_P3V3_BOM1';

SECTION_NUMBER 1
 '@S9S_MB_2U_LIB.S9S_MB_2U(SCH_1):PAGE131_I50@PURE_QUANTA.Q_RES(CHIPS)':
 C_PATH='@s9s_mb_2u_lib.s9s_mb_2u(sch_1):page131_i50@pure_quanta.q_res(chips)',
 P_PATH='@s9s_mb_2u_lib.s9s_mb_2u(sch_1):page162_i50@pure_quanta.q_res(chips)',
 PATH='I50',
 DRAWING='@S9S_MB_2U_LIB.S9S_MB_2U(SCH_1):PAGE131',
 PHYS_PAGE='162',
 XY='(-50,1550)',
 ROT='0',
 VER='2',
 PACK_TYPE='0402LF',
 LOCATION='PR3829',
 CDS_LIB='pure_quanta',
 CDS_PART_NAME='Q_RES_0402LF-7.15K,1%,1/16W,CHA',
 WATTAGE='1/16W',
 TOLERANCE='1%',
 MATERIAL='CHIP',
 ROOM='NIC1_P3V3_BOM1',
 VALUE='7.15K',
 PRIM_FILE='./archive_libs/logical/q_res/chips/chips.prt';

PART_NAME
 PR3830 'Q_RES_0402LF-10,1%,1/16W,EMPTYA':
 ROOM='NIC1_P12V_MAM_MAM_BOM1';

SECTION_NUMBER 1
 '@S9S_MB_2U_LIB.S9S_MB_2U(SCH_1):PAGE131_I85@PURE_QUANTA.Q_RES(CHIPS)':
 C_PATH='@s9s_mb_2u_lib.s9s_mb_2u(sch_1):page131_i85@pure_quanta.q_res(chips)',
 P_PATH='@s9s_mb_2u_lib.s9s_mb_2u(sch_1):page162_i85@pure_quanta.q_res(chips)',
 PATH='I85',
 DRAWING='@S9S_MB_2U_LIB.S9S_MB_2U(SCH_1):PAGE131',
 ROOM1='NIC1_P12V_MAM_TIC_BOM2',
 PHYS_PAGE='162',
 XY='(150,200)',
 ROT='0',
 VER='2',
 PACK_TYPE='0402LF',
 LOCATION='PR3830',
 CDS_LIB='pure_quanta',
 CDS_PART_NAME='Q_RES_0402LF-10,1%,1/16W,EMPTYA',
 WATTAGE='1/16W',
 TOLERANCE='1%',
 MATERIAL='EMPTY',
 ROOM='NIC1_P12V_MAM_MAM_BOM1',
 VALUE='10',
 PRIM_FILE='./archive_libs/logical/q_res/chips/chips.prt';

PART_NAME
 PR3835 'Q_RES_0402LF-14.3K,1%,1/16W,CHA':
 ROOM='NIC1_P12V_MPS_MAM_BOM3';

SECTION_NUMBER 1
 '@S9S_MB_2U_LIB.S9S_MB_2U(SCH_1):PAGE236_I62@PURE_QUANTA.Q_RES(CHIPS)':
 C_PATH='@s9s_mb_2u_lib.s9s_mb_2u(sch_1):page236_i62@pure_quanta.q_res(chips)',
 P_PATH='@s9s_mb_2u_lib.s9s_mb_2u(sch_1):page157_i62@pure_quanta.q_res(chips)',
 PATH='I62',
 DRAWING='@S9S_MB_2U_LIB.S9S_MB_2U(SCH_1):PAGE236',
 ROOM1='NIC1_P12V_MPS_TIC_BOM4',
 PHYS_PAGE='157',
 XY='(-7625,9075)',
 ROT='0',
 VER='2',
 PACK_TYPE='0402LF',
 LOCATION='PR3835',
 CDS_LIB='pure_quanta',
 CDS_PART_NAME='Q_RES_0402LF-14.3K,1%,1/16W,CHA',
 WATTAGE='1/16W',
 TOLERANCE='1%',
 MATERIAL='CHIP',
 ROOM='NIC1_P12V_MPS_MAM_BOM3',
 VALUE='14.3K',
 PRIM_FILE='./archive_libs/logical/q_res/chips/chips.prt';

PART_NAME
 PR3837 'Q_RES_0402LF-17.4K,1%,1/16W,CHA':
 ROOM='NIC1_P12V_MPS_MAM_BOM3';

SECTION_NUMBER 1
 '@S9S_MB_2U_LIB.S9S_MB_2U(SCH_1):PAGE236_I72@PURE_QUANTA.Q_RES(CHIPS)':
 C_PATH='@s9s_mb_2u_lib.s9s_mb_2u(sch_1):page236_i72@pure_quanta.q_res(chips)',
 P_PATH='@s9s_mb_2u_lib.s9s_mb_2u(sch_1):page157_i72@pure_quanta.q_res(chips)',
 PATH='I72',
 DRAWING='@S9S_MB_2U_LIB.S9S_MB_2U(SCH_1):PAGE236',
 ROOM1='NIC1_P12V_MPS_TIC_BOM4',
 PHYS_PAGE='157',
 XY='(-5800,8775)',
 ROT='0',
 VER='2',
 PACK_TYPE='0402LF',
 LOCATION='PR3837',
 CDS_LIB='pure_quanta',
 CDS_PART_NAME='Q_RES_0402LF-17.4K,1%,1/16W,CHA',
 WATTAGE='1/16W',
 TOLERANCE='1%',
 MATERIAL='CHIP',
 ROOM='NIC1_P12V_MPS_MAM_BOM3',
 VALUE='17.4K',
 PRIM_FILE='./archive_libs/logical/q_res/chips/chips.prt';

PART_NAME
 PR3838 'Q_RES_0402LF-100,1%,1/16W,EMPTA':;

SECTION_NUMBER 1
 '@S9S_MB_2U_LIB.S9S_MB_2U(SCH_1):PAGE236_I77@PURE_QUANTA.Q_RES(CHIPS)':
 C_PATH='@s9s_mb_2u_lib.s9s_mb_2u(sch_1):page236_i77@pure_quanta.q_res(chips)',
 P_PATH='@s9s_mb_2u_lib.s9s_mb_2u(sch_1):page157_i77@pure_quanta.q_res(chips)',
 PATH='I77',
 DRAWING='@S9S_MB_2U_LIB.S9S_MB_2U(SCH_1):PAGE236',
 PHYS_PAGE='157',
 XY='(-5425,9625)',
 ROT='0',
 VER='2',
 PACK_TYPE='0402LF',
 LOCATION='PR3838',
 CDS_LIB='pure_quanta',
 CDS_PART_NAME='Q_RES_0402LF-100,1%,1/16W,EMPTA',
 WATTAGE='1/16W',
 TOLERANCE='1%',
 MATERIAL='EMPTY',
 VALUE='100',
 PRIM_FILE='./archive_libs/logical/q_res/chips/chips.prt';

PART_NAME
 PR3839 'Q_RES_0402LF-10K,1%,1/16W,CHIPA':
 ROOM='NIC1_P12V_MPS_MAM_BOM3';

SECTION_NUMBER 1
 '@S9S_MB_2U_LIB.S9S_MB_2U(SCH_1):PAGE236_I75@PURE_QUANTA.Q_RES(CHIPS)':
 C_PATH='@s9s_mb_2u_lib.s9s_mb_2u(sch_1):page236_i75@pure_quanta.q_res(chips)',
 P_PATH='@s9s_mb_2u_lib.s9s_mb_2u(sch_1):page157_i75@pure_quanta.q_res(chips)',
 PATH='I75',
 DRAWING='@S9S_MB_2U_LIB.S9S_MB_2U(SCH_1):PAGE236',
 ROOM1='NIC1_P12V_MPS_TIC_BOM4',
 PHYS_PAGE='157',
 XY='(-5425,9150)',
 ROT='0',
 VER='1',
 PACK_TYPE='0402LF',
 LOCATION='PR3839',
 CDS_LIB='pure_quanta',
 CDS_PART_NAME='Q_RES_0402LF-10K,1%,1/16W,CHIPA',
 WATTAGE='1/16W',
 TOLERANCE='1%',
 MATERIAL='CHIP',
 ROOM='NIC1_P12V_MPS_MAM_BOM3',
 VALUE='10K',
 PRIM_FILE='./archive_libs/logical/q_res/chips/chips.prt';

PART_NAME
 PR3840 'Q_RES_0402LF-71.5K,1%,1/16W,EMA':;

SECTION_NUMBER 1
 '@S9S_MB_2U_LIB.S9S_MB_2U(SCH_1):PAGE236_I85@PURE_QUANTA.Q_RES(CHIPS)':
 C_PATH='@s9s_mb_2u_lib.s9s_mb_2u(sch_1):page236_i85@pure_quanta.q_res(chips)',
 P_PATH='@s9s_mb_2u_lib.s9s_mb_2u(sch_1):page157_i85@pure_quanta.q_res(chips)',
 PATH='I85',
 DRAWING='@S9S_MB_2U_LIB.S9S_MB_2U(SCH_1):PAGE236',
 PHYS_PAGE='157',
 XY='(-4825,9625)',
 ROT='0',
 VER='2',
 PACK_TYPE='0402LF',
 LOCATION='PR3840',
 CDS_LIB='pure_quanta',
 CDS_PART_NAME='Q_RES_0402LF-71.5K,1%,1/16W,EMA',
 WATTAGE='1/16W',
 TOLERANCE='1%',
 MATERIAL='EMPTY',
 VALUE='71.5K',
 PRIM_FILE='./archive_libs/logical/q_res/chips/chips.prt';

PART_NAME
 PR3841 'Q_RES_0402LF-120K,1%,1/16W,CHIA':
 ROOM='NIC1_P12V_MPS_MAM_BOM3';

SECTION_NUMBER 1
 '@S9S_MB_2U_LIB.S9S_MB_2U(SCH_1):PAGE236_I86@PURE_QUANTA.Q_RES(CHIPS)':
 C_PATH='@s9s_mb_2u_lib.s9s_mb_2u(sch_1):page236_i86@pure_quanta.q_res(chips)',
 P_PATH='@s9s_mb_2u_lib.s9s_mb_2u(sch_1):page157_i86@pure_quanta.q_res(chips)',
 PATH='I86',
 DRAWING='@S9S_MB_2U_LIB.S9S_MB_2U(SCH_1):PAGE236',
 ROOM1='NIC1_P12V_MPS_TIC_BOM4',
 PHYS_PAGE='157',
 XY='(-4425,9550)',
 ROT='0',
 VER='2',
 PACK_TYPE='0402LF',
 LOCATION='PR3841',
 CDS_LIB='pure_quanta',
 CDS_PART_NAME='Q_RES_0402LF-120K,1%,1/16W,CHIA',
 WATTAGE='1/16W',
 TOLERANCE='1%',
 MATERIAL='CHIP',
 ROOM='NIC1_P12V_MPS_MAM_BOM3',
 VALUE='120K',
 PRIM_FILE='./archive_libs/logical/q_res/chips/chips.prt';

PART_NAME
 PR3842 'Q_RES_0402LF-10K,1%,1/16W,CHIPA':
 ROOM='NIC1_P12V_MPS_MAM_BOM3';

SECTION_NUMBER 1
 '@S9S_MB_2U_LIB.S9S_MB_2U(SCH_1):PAGE236_I83@PURE_QUANTA.Q_RES(CHIPS)':
 C_PATH='@s9s_mb_2u_lib.s9s_mb_2u(sch_1):page236_i83@pure_quanta.q_res(chips)',
 P_PATH='@s9s_mb_2u_lib.s9s_mb_2u(sch_1):page157_i83@pure_quanta.q_res(chips)',
 PATH='I83',
 DRAWING='@S9S_MB_2U_LIB.S9S_MB_2U(SCH_1):PAGE236',
 ROOM1='NIC1_P12V_MPS_TIC_BOM4',
 PHYS_PAGE='157',
 XY='(-4425,9125)',
 ROT='0',
 VER='2',
 PACK_TYPE='0402LF',
 LOCATION='PR3842',
 CDS_LIB='pure_quanta',
 CDS_PART_NAME='Q_RES_0402LF-10K,1%,1/16W,CHIPA',
 WATTAGE='1/16W',
 TOLERANCE='1%',
 MATERIAL='CHIP',
 ROOM='NIC1_P12V_MPS_MAM_BOM3',
 VALUE='10K',
 PRIM_FILE='./archive_libs/logical/q_res/chips/chips.prt';

PART_NAME
 PR3843 'Q_RES_0603LF-49.9,1%,1/10W,CHIA':
 ROOM='NIC1_P12V_MPS_MAM_BOM3';

SECTION_NUMBER 1
 '@S9S_MB_2U_LIB.S9S_MB_2U(SCH_1):PAGE236_I89@PURE_QUANTA.Q_RES(CHIPS)':
 C_PATH='@s9s_mb_2u_lib.s9s_mb_2u(sch_1):page236_i89@pure_quanta.q_res(chips)',
 P_PATH='@s9s_mb_2u_lib.s9s_mb_2u(sch_1):page157_i89@pure_quanta.q_res(chips)',
 PATH='I89',
 DRAWING='@S9S_MB_2U_LIB.S9S_MB_2U(SCH_1):PAGE236',
 ROOM1='NIC1_P12V_MPS_TIC_BOM4',
 PHYS_PAGE='157',
 XY='(-3900,9550)',
 ROT='0',
 VER='2',
 PACK_TYPE='0603LF',
 LOCATION='PR3843',
 CDS_LIB='pure_quanta',
 CDS_PART_NAME='Q_RES_0603LF-49.9,1%,1/10W,CHIA',
 WATTAGE='1/10W',
 TOLERANCE='1%',
 MATERIAL='CHIP',
 ROOM='NIC1_P12V_MPS_MAM_BOM3',
 VALUE='49.9',
 PRIM_FILE='./archive_libs/logical/q_res/chips/chips.prt';

PART_NAME
 PR3844 'Q_RES_0402LF-71.5K,1%,1/16W,EMA':
 ROOM='NIC1_P3V3_BOM2';

SECTION_NUMBER 1
 '@S9S_MB_2U_LIB.S9S_MB_2U(SCH_1):PAGE236_I43@PURE_QUANTA.Q_RES(CHIPS)':
 C_PATH='@s9s_mb_2u_lib.s9s_mb_2u(sch_1):page236_i43@pure_quanta.q_res(chips)',
 P_PATH='@s9s_mb_2u_lib.s9s_mb_2u(sch_1):page157_i43@pure_quanta.q_res(chips)',
 PATH='I43',
 DRAWING='@S9S_MB_2U_LIB.S9S_MB_2U(SCH_1):PAGE236',
 PHYS_PAGE='157',
 XY='(-3825,12300)',
 ROT='0',
 VER='2',
 PACK_TYPE='0402LF',
 LOCATION='PR3844',
 CDS_LIB='pure_quanta',
 CDS_PART_NAME='Q_RES_0402LF-71.5K,1%,1/16W,EMA',
 WATTAGE='1/16W',
 TOLERANCE='1%',
 MATERIAL='EMPTY',
 ROOM='NIC1_P3V3_BOM2',
 VALUE='71.5K',
 PRIM_FILE='./archive_libs/logical/q_res/chips/chips.prt';

PART_NAME
 PR3846 'Q_RES_0402LF-1.33K,1%,1/16W,EMA':
 ROOM='NIC1_P3V3_BOM2';

SECTION_NUMBER 1
 '@S9S_MB_2U_LIB.S9S_MB_2U(SCH_1):PAGE236_I45@PURE_QUANTA.Q_RES(CHIPS)':
 C_PATH='@s9s_mb_2u_lib.s9s_mb_2u(sch_1):page236_i45@pure_quanta.q_res(chips)',
 P_PATH='@s9s_mb_2u_lib.s9s_mb_2u(sch_1):page157_i45@pure_quanta.q_res(chips)',
 PATH='I45',
 DRAWING='@S9S_MB_2U_LIB.S9S_MB_2U(SCH_1):PAGE236',
 PHYS_PAGE='157',
 XY='(-3525,12250)',
 ROT='1',
 VER='1',
 PACK_TYPE='0402LF',
 LOCATION='PR3846',
 CDS_LIB='pure_quanta',
 CDS_PART_NAME='Q_RES_0402LF-1.33K,1%,1/16W,EMA',
 WATTAGE='1/16W',
 TOLERANCE='1%',
 MATERIAL='EMPTY',
 ROOM='NIC1_P3V3_BOM2',
 VALUE='1.33K',
 PRIM_FILE='./archive_libs/logical/q_res/chips/chips.prt';

PART_NAME
 PR3847 'Q_RES_0402LF-14.3K,1%,1/16W,CHA':
 ROOM='NIC1_P12V_MPS_MAM_BOM3';

SECTION_NUMBER 1
 '@S9S_MB_2U_LIB.S9S_MB_2U(SCH_1):PAGE237_I61@PURE_QUANTA.Q_RES(CHIPS)':
 C_PATH='@s9s_mb_2u_lib.s9s_mb_2u(sch_1):page237_i61@pure_quanta.q_res(chips)',
 P_PATH='@s9s_mb_2u_lib.s9s_mb_2u(sch_1):page163_i61@pure_quanta.q_res(chips)',
 PATH='I61',
 DRAWING='@S9S_MB_2U_LIB.S9S_MB_2U(SCH_1):PAGE237',
 ROOM1='NIC1_P12V_MPS_TIC_BOM4',
 PHYS_PAGE='163',
 XY='(-3750,2575)',
 ROT='0',
 VER='2',
 PACK_TYPE='0402LF',
 LOCATION='PR3847',
 CDS_LIB='pure_quanta',
 CDS_PART_NAME='Q_RES_0402LF-14.3K,1%,1/16W,CHA',
 WATTAGE='1/16W',
 TOLERANCE='1%',
 MATERIAL='CHIP',
 ROOM='NIC1_P12V_MPS_MAM_BOM3',
 VALUE='14.3K',
 PRIM_FILE='./archive_libs/logical/q_res/chips/chips.prt';

PART_NAME
 PR3849 'Q_RES_0402LF-17.4K,1%,1/16W,CHA':
 ROOM='NIC1_P12V_MPS_MAM_BOM3';

SECTION_NUMBER 1
 '@S9S_MB_2U_LIB.S9S_MB_2U(SCH_1):PAGE237_I72@PURE_QUANTA.Q_RES(CHIPS)':
 C_PATH='@s9s_mb_2u_lib.s9s_mb_2u(sch_1):page237_i72@pure_quanta.q_res(chips)',
 P_PATH='@s9s_mb_2u_lib.s9s_mb_2u(sch_1):page163_i72@pure_quanta.q_res(chips)',
 PATH='I72',
 DRAWING='@S9S_MB_2U_LIB.S9S_MB_2U(SCH_1):PAGE237',
 ROOM1='NIC1_P12V_MPS_TIC_BOM4',
 PHYS_PAGE='163',
 XY='(-2000,2325)',
 ROT='0',
 VER='2',
 PACK_TYPE='0402LF',
 LOCATION='PR3849',
 CDS_LIB='pure_quanta',
 CDS_PART_NAME='Q_RES_0402LF-17.4K,1%,1/16W,CHA',
 WATTAGE='1/16W',
 TOLERANCE='1%',
 MATERIAL='CHIP',
 ROOM='NIC1_P12V_MPS_MAM_BOM3',
 VALUE='17.4K',
 PRIM_FILE='./archive_libs/logical/q_res/chips/chips.prt';

PART_NAME
 PR3850 'Q_RES_0402LF-100,1%,1/16W,EMPTA':;

SECTION_NUMBER 1
 '@S9S_MB_2U_LIB.S9S_MB_2U(SCH_1):PAGE237_I77@PURE_QUANTA.Q_RES(CHIPS)':
 C_PATH='@s9s_mb_2u_lib.s9s_mb_2u(sch_1):page237_i77@pure_quanta.q_res(chips)',
 P_PATH='@s9s_mb_2u_lib.s9s_mb_2u(sch_1):page163_i77@pure_quanta.q_res(chips)',
 PATH='I77',
 DRAWING='@S9S_MB_2U_LIB.S9S_MB_2U(SCH_1):PAGE237',
 PHYS_PAGE='163',
 XY='(-1500,3150)',
 ROT='0',
 VER='2',
 PACK_TYPE='0402LF',
 LOCATION='PR3850',
 CDS_LIB='pure_quanta',
 CDS_PART_NAME='Q_RES_0402LF-100,1%,1/16W,EMPTA',
 WATTAGE='1/16W',
 TOLERANCE='1%',
 MATERIAL='EMPTY',
 VALUE='100',
 PRIM_FILE='./archive_libs/logical/q_res/chips/chips.prt';

PART_NAME
 PR3851 'Q_RES_0402LF-10K,1%,1/16W,CHIPA':
 ROOM='NIC1_P12V_MPS_MAM_BOM3';

SECTION_NUMBER 1
 '@S9S_MB_2U_LIB.S9S_MB_2U(SCH_1):PAGE237_I74@PURE_QUANTA.Q_RES(CHIPS)':
 C_PATH='@s9s_mb_2u_lib.s9s_mb_2u(sch_1):page237_i74@pure_quanta.q_res(chips)',
 P_PATH='@s9s_mb_2u_lib.s9s_mb_2u(sch_1):page163_i74@pure_quanta.q_res(chips)',
 PATH='I74',
 DRAWING='@S9S_MB_2U_LIB.S9S_MB_2U(SCH_1):PAGE237',
 ROOM1='NIC1_P12V_MPS_TIC_BOM4',
 PHYS_PAGE='163',
 XY='(-1425,2675)',
 ROT='0',
 VER='1',
 PACK_TYPE='0402LF',
 LOCATION='PR3851',
 CDS_LIB='pure_quanta',
 CDS_PART_NAME='Q_RES_0402LF-10K,1%,1/16W,CHIPA',
 WATTAGE='1/16W',
 TOLERANCE='1%',
 MATERIAL='CHIP',
 ROOM='NIC1_P12V_MPS_MAM_BOM3',
 VALUE='10K',
 PRIM_FILE='./archive_libs/logical/q_res/chips/chips.prt';

PART_NAME
 PR3852 'Q_RES_0402LF-71.5K,1%,1/16W,EMA':;

SECTION_NUMBER 1
 '@S9S_MB_2U_LIB.S9S_MB_2U(SCH_1):PAGE237_I85@PURE_QUANTA.Q_RES(CHIPS)':
 C_PATH='@s9s_mb_2u_lib.s9s_mb_2u(sch_1):page237_i85@pure_quanta.q_res(chips)',
 P_PATH='@s9s_mb_2u_lib.s9s_mb_2u(sch_1):page163_i85@pure_quanta.q_res(chips)',
 PATH='I85',
 DRAWING='@S9S_MB_2U_LIB.S9S_MB_2U(SCH_1):PAGE237',
 PHYS_PAGE='163',
 XY='(-950,3150)',
 ROT='0',
 VER='2',
 PACK_TYPE='0402LF',
 LOCATION='PR3852',
 CDS_LIB='pure_quanta',
 CDS_PART_NAME='Q_RES_0402LF-71.5K,1%,1/16W,EMA',
 WATTAGE='1/16W',
 TOLERANCE='1%',
 MATERIAL='EMPTY',
 VALUE='71.5K',
 PRIM_FILE='./archive_libs/logical/q_res/chips/chips.prt';

PART_NAME
 PR3853 'Q_RES_0402LF-120K,1%,1/16W,CHIA':
 ROOM='NIC1_P12V_MPS_MAM_BOM3';

SECTION_NUMBER 1
 '@S9S_MB_2U_LIB.S9S_MB_2U(SCH_1):PAGE237_I84@PURE_QUANTA.Q_RES(CHIPS)':
 C_PATH='@s9s_mb_2u_lib.s9s_mb_2u(sch_1):page237_i84@pure_quanta.q_res(chips)',
 P_PATH='@s9s_mb_2u_lib.s9s_mb_2u(sch_1):page163_i84@pure_quanta.q_res(chips)',
 PATH='I84',
 DRAWING='@S9S_MB_2U_LIB.S9S_MB_2U(SCH_1):PAGE237',
 ROOM1='NIC1_P12V_MPS_TIC_BOM4',
 PHYS_PAGE='163',
 XY='(-555,3083)',
 ROT='0',
 VER='2',
 PACK_TYPE='0402LF',
 LOCATION='PR3853',
 CDS_LIB='pure_quanta',
 CDS_PART_NAME='Q_RES_0402LF-120K,1%,1/16W,CHIA',
 WATTAGE='1/16W',
 TOLERANCE='1%',
 MATERIAL='CHIP',
 ROOM='NIC1_P12V_MPS_MAM_BOM3',
 VALUE='120K',
 PRIM_FILE='./archive_libs/logical/q_res/chips/chips.prt';

PART_NAME
 PR3854 'Q_RES_0402LF-10K,1%,1/16W,CHIPA':
 ROOM='NIC1_P12V_MPS_MAM_BOM3';

SECTION_NUMBER 1
 '@S9S_MB_2U_LIB.S9S_MB_2U(SCH_1):PAGE237_I83@PURE_QUANTA.Q_RES(CHIPS)':
 C_PATH='@s9s_mb_2u_lib.s9s_mb_2u(sch_1):page237_i83@pure_quanta.q_res(chips)',
 P_PATH='@s9s_mb_2u_lib.s9s_mb_2u(sch_1):page163_i83@pure_quanta.q_res(chips)',
 PATH='I83',
 DRAWING='@S9S_MB_2U_LIB.S9S_MB_2U(SCH_1):PAGE237',
 ROOM1='NIC1_P12V_MPS_TIC_BOM4',
 PHYS_PAGE='163',
 XY='(-555,2658)',
 ROT='0',
 VER='2',
 PACK_TYPE='0402LF',
 LOCATION='PR3854',
 CDS_LIB='pure_quanta',
 CDS_PART_NAME='Q_RES_0402LF-10K,1%,1/16W,CHIPA',
 WATTAGE='1/16W',
 TOLERANCE='1%',
 MATERIAL='CHIP',
 ROOM='NIC1_P12V_MPS_MAM_BOM3',
 VALUE='10K',
 PRIM_FILE='./archive_libs/logical/q_res/chips/chips.prt';

PART_NAME
 PR3855 'Q_RES_0402LF-71.5K,1%,1/16W,EMA':
 ROOM='NIC1_P3V3_BOM2';

SECTION_NUMBER 1
 '@S9S_MB_2U_LIB.S9S_MB_2U(SCH_1):PAGE237_I43@PURE_QUANTA.Q_RES(CHIPS)':
 C_PATH='@s9s_mb_2u_lib.s9s_mb_2u(sch_1):page237_i43@pure_quanta.q_res(chips)',
 P_PATH='@s9s_mb_2u_lib.s9s_mb_2u(sch_1):page163_i43@pure_quanta.q_res(chips)',
 PATH='I43',
 DRAWING='@S9S_MB_2U_LIB.S9S_MB_2U(SCH_1):PAGE237',
 PHYS_PAGE='163',
 XY='(150,6175)',
 ROT='0',
 VER='2',
 PACK_TYPE='0402LF',
 LOCATION='PR3855',
 CDS_LIB='pure_quanta',
 CDS_PART_NAME='Q_RES_0402LF-71.5K,1%,1/16W,EMA',
 WATTAGE='1/16W',
 TOLERANCE='1%',
 MATERIAL='EMPTY',
 ROOM='NIC1_P3V3_BOM2',
 VALUE='71.5K',
 PRIM_FILE='./archive_libs/logical/q_res/chips/chips.prt';

PART_NAME
 PR3856 'Q_RES_0402LF-1.33K,1%,1/16W,EMA':
 ROOM='NIC1_P3V3_BOM2';

SECTION_NUMBER 1
 '@S9S_MB_2U_LIB.S9S_MB_2U(SCH_1):PAGE237_I46@PURE_QUANTA.Q_RES(CHIPS)':
 C_PATH='@s9s_mb_2u_lib.s9s_mb_2u(sch_1):page237_i46@pure_quanta.q_res(chips)',
 P_PATH='@s9s_mb_2u_lib.s9s_mb_2u(sch_1):page163_i46@pure_quanta.q_res(chips)',
 PATH='I46',
 DRAWING='@S9S_MB_2U_LIB.S9S_MB_2U(SCH_1):PAGE237',
 PHYS_PAGE='163',
 XY='(495,6158)',
 ROT='1',
 VER='1',
 PACK_TYPE='0402LF',
 LOCATION='PR3856',
 CDS_LIB='pure_quanta',
 CDS_PART_NAME='Q_RES_0402LF-1.33K,1%,1/16W,EMA',
 WATTAGE='1/16W',
 TOLERANCE='1%',
 MATERIAL='EMPTY',
 ROOM='NIC1_P3V3_BOM2',
 VALUE='1.33K',
 PRIM_FILE='./archive_libs/logical/q_res/chips/chips.prt';

PART_NAME
 PR3857 'Q_RES_0603LF-49.9,1%,1/10W,CHIA':
 ROOM='NIC1_P12V_MPS_MAM_BOM3';

SECTION_NUMBER 1
 '@S9S_MB_2U_LIB.S9S_MB_2U(SCH_1):PAGE237_I87@PURE_QUANTA.Q_RES(CHIPS)':
 C_PATH='@s9s_mb_2u_lib.s9s_mb_2u(sch_1):page237_i87@pure_quanta.q_res(chips)',
 P_PATH='@s9s_mb_2u_lib.s9s_mb_2u(sch_1):page163_i87@pure_quanta.q_res(chips)',
 PATH='I87',
 DRAWING='@S9S_MB_2U_LIB.S9S_MB_2U(SCH_1):PAGE237',
 ROOM1='NIC1_P12V_MPS_TIC_BOM4',
 PHYS_PAGE='163',
 XY='(-25,3075)',
 ROT='0',
 VER='2',
 PACK_TYPE='0603LF',
 LOCATION='PR3857',
 CDS_LIB='pure_quanta',
 CDS_PART_NAME='Q_RES_0603LF-49.9,1%,1/10W,CHIA',
 WATTAGE='1/10W',
 TOLERANCE='1%',
 MATERIAL='CHIP',
 ROOM='NIC1_P12V_MPS_MAM_BOM3',
 VALUE='49.9',
 PRIM_FILE='./archive_libs/logical/q_res/chips/chips.prt';

PART_NAME
 PR3910 'Q_RES_0402LF-0,5%,1/16W,CHIP,CA':
 ROOM='HSC1_BOM1';

SECTION_NUMBER 1
 '@S9S_MB_2U_LIB.S9S_MB_2U(SCH_1):PAGE301_I21@PURE_QUANTA.Q_RES(CHIPS)':
 C_PATH='@s9s_mb_2u_lib.s9s_mb_2u(sch_1):page301_i21@pure_quanta.q_res(chips)',
 P_PATH='@s9s_mb_2u_lib.s9s_mb_2u(sch_1):page302_i21@pure_quanta.q_res(chips)',
 PATH='I21',
 DRAWING='@S9S_MB_2U_LIB.S9S_MB_2U(SCH_1):PAGE301',
 PHYS_PAGE='302',
 XY='(-3675,1900)',
 ROT='1',
 VER='1',
 PACK_TYPE='0402LF',
 LOCATION='PR3910',
 CDS_LIB='pure_quanta',
 CDS_PART_NAME='Q_RES_0402LF-0,5%,1/16W,CHIP,CA',
 WATTAGE='1/16W',
 TOLERANCE='5%',
 MATERIAL='CHIP',
 ROOM='HSC1_BOM1',
 VALUE='0',
 PRIM_FILE='./archive_libs/logical/q_res/chips/chips.prt';

PART_NAME
 PR3911 'Q_RES_0402LF-0,5%,1/16W,CHIP,CA':
 ROOM='HSC1_BOM1';

SECTION_NUMBER 1
 '@S9S_MB_2U_LIB.S9S_MB_2U(SCH_1):PAGE301_I5@PURE_QUANTA.Q_RES(CHIPS)':
 C_PATH='@s9s_mb_2u_lib.s9s_mb_2u(sch_1):page301_i5@pure_quanta.q_res(chips)',
 P_PATH='@s9s_mb_2u_lib.s9s_mb_2u(sch_1):page302_i5@pure_quanta.q_res(chips)',
 PATH='I5',
 DRAWING='@S9S_MB_2U_LIB.S9S_MB_2U(SCH_1):PAGE301',
 PHYS_PAGE='302',
 XY='(-3700,-900)',
 ROT='1',
 VER='1',
 PACK_TYPE='0402LF',
 LOCATION='PR3911',
 CDS_LIB='pure_quanta',
 CDS_PART_NAME='Q_RES_0402LF-0,5%,1/16W,CHIP,CA',
 WATTAGE='1/16W',
 TOLERANCE='5%',
 MATERIAL='CHIP',
 ROOM='HSC1_BOM1',
 VALUE='0',
 PRIM_FILE='./archive_libs/logical/q_res/chips/chips.prt';

PART_NAME
 PR3912 'Q_RES_0402LF-120K,1%,1/16W,CHIA':
 ROOM='HSC1_BOM1';

SECTION_NUMBER 1
 '@S9S_MB_2U_LIB.S9S_MB_2U(SCH_1):PAGE301_I15@PURE_QUANTA.Q_RES(CHIPS)':
 C_PATH='@s9s_mb_2u_lib.s9s_mb_2u(sch_1):page301_i15@pure_quanta.q_res(chips)',
 P_PATH='@s9s_mb_2u_lib.s9s_mb_2u(sch_1):page302_i15@pure_quanta.q_res(chips)',
 PATH='I15',
 DRAWING='@S9S_MB_2U_LIB.S9S_MB_2U(SCH_1):PAGE301',
 PHYS_PAGE='302',
 XY='(-2150,-1200)',
 ROT='0',
 VER='1',
 PACK_TYPE='0402LF',
 LOCATION='PR3912',
 CDS_LIB='pure_quanta',
 CDS_PART_NAME='Q_RES_0402LF-120K,1%,1/16W,CHIA',
 WATTAGE='1/16W',
 TOLERANCE='1%',
 MATERIAL='CHIP',
 ROOM='HSC1_BOM1',
 VALUE='120K',
 PRIM_FILE='./archive_libs/logical/q_res/chips/chips.prt';

PART_NAME
 PR3914 'Q_RES_0402LF-2K,0.1%,1/16W,CHIA':
 ROOM='HSC1_BOM1';

SECTION_NUMBER 1
 '@S9S_MB_2U_LIB.S9S_MB_2U(SCH_1):PAGE301_I30@PURE_QUANTA.Q_RES(CHIPS)':
 C_PATH='@s9s_mb_2u_lib.s9s_mb_2u(sch_1):page301_i30@pure_quanta.q_res(chips)',
 P_PATH='@s9s_mb_2u_lib.s9s_mb_2u(sch_1):page302_i30@pure_quanta.q_res(chips)',
 PATH='I30',
 DRAWING='@S9S_MB_2U_LIB.S9S_MB_2U(SCH_1):PAGE301',
 PHYS_PAGE='302',
 XY='(-1725,775)',
 ROT='0',
 VER='2',
 PACK_TYPE='0402LF',
 LOCATION='PR3914',
 CDS_LIB='pure_quanta',
 CDS_PART_NAME='Q_RES_0402LF-2K,0.1%,1/16W,CHIA',
 WATTAGE='1/16W',
 TOLERANCE='0.1%',
 MATERIAL='CHIP',
 ROOM='HSC1_BOM1',
 VALUE='2K',
 PRIM_FILE='./archive_libs/logical/q_res/chips/chips.prt';

PART_NAME
 PR3915 'Q_RES_0402LF-2K,0.1%,1/16W,CHIA':
 ROOM='HSC1_BOM1';

SECTION_NUMBER 1
 '@S9S_MB_2U_LIB.S9S_MB_2U(SCH_1):PAGE301_I12@PURE_QUANTA.Q_RES(CHIPS)':
 C_PATH='@s9s_mb_2u_lib.s9s_mb_2u(sch_1):page301_i12@pure_quanta.q_res(chips)',
 P_PATH='@s9s_mb_2u_lib.s9s_mb_2u(sch_1):page302_i12@pure_quanta.q_res(chips)',
 PATH='I12',
 DRAWING='@S9S_MB_2U_LIB.S9S_MB_2U(SCH_1):PAGE301',
 PHYS_PAGE='302',
 XY='(-1725,-2025)',
 ROT='0',
 VER='2',
 PACK_TYPE='0402LF',
 LOCATION='PR3915',
 CDS_LIB='pure_quanta',
 CDS_PART_NAME='Q_RES_0402LF-2K,0.1%,1/16W,CHIA',
 WATTAGE='1/16W',
 TOLERANCE='0.1%',
 MATERIAL='CHIP',
 ROOM='HSC1_BOM1',
 VALUE='2K',
 PRIM_FILE='./archive_libs/logical/q_res/chips/chips.prt';

PART_NAME
 PR3916 'Q_RES_0402LF-0,5%,1/16W,CHIP,CA':
 ROOM='HSC1_BOM1';

SECTION_NUMBER 1
 '@S9S_MB_2U_LIB.S9S_MB_2U(SCH_1):PAGE301_I33@PURE_QUANTA.Q_RES(CHIPS)':
 C_PATH='@s9s_mb_2u_lib.s9s_mb_2u(sch_1):page301_i33@pure_quanta.q_res(chips)',
 P_PATH='@s9s_mb_2u_lib.s9s_mb_2u(sch_1):page302_i33@pure_quanta.q_res(chips)',
 PATH='I33',
 DRAWING='@S9S_MB_2U_LIB.S9S_MB_2U(SCH_1):PAGE301',
 PHYS_PAGE='302',
 XY='(-1575,1425)',
 ROT='0',
 VER='1',
 PACK_TYPE='0402LF',
 LOCATION='PR3916',
 CDS_LIB='pure_quanta',
 CDS_PART_NAME='Q_RES_0402LF-0,5%,1/16W,CHIP,CA',
 WATTAGE='1/16W',
 TOLERANCE='5%',
 MATERIAL='CHIP',
 ROOM='HSC1_BOM1',
 VALUE='0',
 PRIM_FILE='./archive_libs/logical/q_res/chips/chips.prt';

PART_NAME
 PR3917 'Q_RES_0402LF-0,5%,1/16W,CHIP,CA':
 ROOM='HSC1_BOM1';

SECTION_NUMBER 1
 '@S9S_MB_2U_LIB.S9S_MB_2U(SCH_1):PAGE301_I17@PURE_QUANTA.Q_RES(CHIPS)':
 C_PATH='@s9s_mb_2u_lib.s9s_mb_2u(sch_1):page301_i17@pure_quanta.q_res(chips)',
 P_PATH='@s9s_mb_2u_lib.s9s_mb_2u(sch_1):page302_i17@pure_quanta.q_res(chips)',
 PATH='I17',
 DRAWING='@S9S_MB_2U_LIB.S9S_MB_2U(SCH_1):PAGE301',
 PHYS_PAGE='302',
 XY='(-1550,-1375)',
 ROT='0',
 VER='1',
 PACK_TYPE='0402LF',
 LOCATION='PR3917',
 CDS_LIB='pure_quanta',
 CDS_PART_NAME='Q_RES_0402LF-0,5%,1/16W,CHIP,CA',
 WATTAGE='1/16W',
 TOLERANCE='5%',
 MATERIAL='CHIP',
 ROOM='HSC1_BOM1',
 VALUE='0',
 PRIM_FILE='./archive_libs/logical/q_res/chips/chips.prt';

PART_NAME
 PR3918 'Q_RES_0402LF-2K,0.1%,1/16W,CHIA':
 ROOM='HSC1_BOM1';

SECTION_NUMBER 1
 '@S9S_MB_2U_LIB.S9S_MB_2U(SCH_1):PAGE301_I34@PURE_QUANTA.Q_RES(CHIPS)':
 C_PATH='@s9s_mb_2u_lib.s9s_mb_2u(sch_1):page301_i34@pure_quanta.q_res(chips)',
 P_PATH='@s9s_mb_2u_lib.s9s_mb_2u(sch_1):page302_i34@pure_quanta.q_res(chips)',
 PATH='I34',
 DRAWING='@S9S_MB_2U_LIB.S9S_MB_2U(SCH_1):PAGE301',
 PHYS_PAGE='302',
 XY='(-1200,775)',
 ROT='0',
 VER='2',
 PACK_TYPE='0402LF',
 LOCATION='PR3918',
 CDS_LIB='pure_quanta',
 CDS_PART_NAME='Q_RES_0402LF-2K,0.1%,1/16W,CHIA',
 WATTAGE='1/16W',
 TOLERANCE='0.1%',
 MATERIAL='CHIP',
 ROOM='HSC1_BOM1',
 VALUE='2K',
 PRIM_FILE='./archive_libs/logical/q_res/chips/chips.prt';

PART_NAME
 PR3919 'Q_RES_0402LF-0,5%,1/16W,CHIP,CA':
 ROOM='HSC1_BOM1';

SECTION_NUMBER 1
 '@S9S_MB_2U_LIB.S9S_MB_2U(SCH_1):PAGE301_I49@PURE_QUANTA.Q_RES(CHIPS)':
 C_PATH='@s9s_mb_2u_lib.s9s_mb_2u(sch_1):page301_i49@pure_quanta.q_res(chips)',
 P_PATH='@s9s_mb_2u_lib.s9s_mb_2u(sch_1):page302_i49@pure_quanta.q_res(chips)',
 PATH='I49',
 DRAWING='@S9S_MB_2U_LIB.S9S_MB_2U(SCH_1):PAGE301',
 PHYS_PAGE='302',
 XY='(1250,1525)',
 ROT='0',
 VER='1',
 PACK_TYPE='0402LF',
 LOCATION='PR3919',
 CDS_LIB='pure_quanta',
 CDS_PART_NAME='Q_RES_0402LF-0,5%,1/16W,CHIP,CA',
 WATTAGE='1/16W',
 TOLERANCE='5%',
 MATERIAL='CHIP',
 ROOM='HSC1_BOM1',
 VALUE='0',
 PRIM_FILE='./archive_libs/logical/q_res/chips/chips.prt';

PART_NAME
 PR3920 'Q_RES_0402LF-0,5%,1/16W,CHIP,CA':
 ROOM='HSC1_BOM1';

SECTION_NUMBER 1
 '@S9S_MB_2U_LIB.S9S_MB_2U(SCH_1):PAGE301_I50@PURE_QUANTA.Q_RES(CHIPS)':
 C_PATH='@s9s_mb_2u_lib.s9s_mb_2u(sch_1):page301_i50@pure_quanta.q_res(chips)',
 P_PATH='@s9s_mb_2u_lib.s9s_mb_2u(sch_1):page302_i50@pure_quanta.q_res(chips)',
 PATH='I50',
 DRAWING='@S9S_MB_2U_LIB.S9S_MB_2U(SCH_1):PAGE301',
 PHYS_PAGE='302',
 XY='(1250,1350)',
 ROT='0',
 VER='1',
 PACK_TYPE='0402LF',
 LOCATION='PR3920',
 CDS_LIB='pure_quanta',
 CDS_PART_NAME='Q_RES_0402LF-0,5%,1/16W,CHIP,CA',
 WATTAGE='1/16W',
 TOLERANCE='5%',
 MATERIAL='CHIP',
 ROOM='HSC1_BOM1',
 VALUE='0',
 PRIM_FILE='./archive_libs/logical/q_res/chips/chips.prt';

PART_NAME
 PR3921 'Q_RES_0402LF-0,5%,1/16W,CHIP,CA':
 ROOM='HSC1_BOM1';

SECTION_NUMBER 1
 '@S9S_MB_2U_LIB.S9S_MB_2U(SCH_1):PAGE301_I39@PURE_QUANTA.Q_RES(CHIPS)':
 C_PATH='@s9s_mb_2u_lib.s9s_mb_2u(sch_1):page301_i39@pure_quanta.q_res(chips)',
 P_PATH='@s9s_mb_2u_lib.s9s_mb_2u(sch_1):page302_i39@pure_quanta.q_res(chips)',
 PATH='I39',
 DRAWING='@S9S_MB_2U_LIB.S9S_MB_2U(SCH_1):PAGE301',
 PHYS_PAGE='302',
 XY='(1250,-1275)',
 ROT='0',
 VER='1',
 PACK_TYPE='0402LF',
 LOCATION='PR3921',
 CDS_LIB='pure_quanta',
 CDS_PART_NAME='Q_RES_0402LF-0,5%,1/16W,CHIP,CA',
 WATTAGE='1/16W',
 TOLERANCE='5%',
 MATERIAL='CHIP',
 ROOM='HSC1_BOM1',
 VALUE='0',
 PRIM_FILE='./archive_libs/logical/q_res/chips/chips.prt';

PART_NAME
 PR3922 'Q_RES_0402LF-0,5%,1/16W,CHIP,CA':
 ROOM='HSC1_BOM1';

SECTION_NUMBER 1
 '@S9S_MB_2U_LIB.S9S_MB_2U(SCH_1):PAGE301_I40@PURE_QUANTA.Q_RES(CHIPS)':
 C_PATH='@s9s_mb_2u_lib.s9s_mb_2u(sch_1):page301_i40@pure_quanta.q_res(chips)',
 P_PATH='@s9s_mb_2u_lib.s9s_mb_2u(sch_1):page302_i40@pure_quanta.q_res(chips)',
 PATH='I40',
 DRAWING='@S9S_MB_2U_LIB.S9S_MB_2U(SCH_1):PAGE301',
 PHYS_PAGE='302',
 XY='(1250,-1450)',
 ROT='0',
 VER='1',
 PACK_TYPE='0402LF',
 LOCATION='PR3922',
 CDS_LIB='pure_quanta',
 CDS_PART_NAME='Q_RES_0402LF-0,5%,1/16W,CHIP,CA',
 WATTAGE='1/16W',
 TOLERANCE='5%',
 MATERIAL='CHIP',
 ROOM='HSC1_BOM1',
 VALUE='0',
 PRIM_FILE='./archive_libs/logical/q_res/chips/chips.prt';

PART_NAME
 PR3926 'Q_RES_0402LF-75K,0.1%,1/16W,CHA':
 ROOM='HSC1_BOM1';

SECTION_NUMBER 1
 '@S9S_MB_2U_LIB.S9S_MB_2U(SCH_1):PAGE303_I52@PURE_QUANTA.Q_RES(CHIPS)':
 C_PATH='@s9s_mb_2u_lib.s9s_mb_2u(sch_1):page303_i52@pure_quanta.q_res(chips)',
 P_PATH='@s9s_mb_2u_lib.s9s_mb_2u(sch_1):page301_i52@pure_quanta.q_res(chips)',
 PATH='I52',
 DRAWING='@S9S_MB_2U_LIB.S9S_MB_2U(SCH_1):PAGE303',
 PHYS_PAGE='301',
 XY='(-15425,5050)',
 ROT='0',
 VER='2',
 PACK_TYPE='0402LF',
 LOCATION='PR3926',
 CDS_LIB='pure_quanta',
 CDS_PART_NAME='Q_RES_0402LF-75K,0.1%,1/16W,CHA',
 WATTAGE='1/16W',
 TOLERANCE='0.1%',
 MATERIAL='CHIP',
 ROOM='HSC1_BOM1',
 VALUE='75K',
 PRIM_FILE='./archive_libs/logical/q_res/chips/chips.prt';

PART_NAME
 PR3927 'Q_RES_0402LF-4.99K,0.1%,1/16W,A':
 ROOM='HSC1_BOM1';

SECTION_NUMBER 1
 '@S9S_MB_2U_LIB.S9S_MB_2U(SCH_1):PAGE303_I40@PURE_QUANTA.Q_RES(CHIPS)':
 C_PATH='@s9s_mb_2u_lib.s9s_mb_2u(sch_1):page303_i40@pure_quanta.q_res(chips)',
 P_PATH='@s9s_mb_2u_lib.s9s_mb_2u(sch_1):page301_i40@pure_quanta.q_res(chips)',
 PATH='I40',
 DRAWING='@S9S_MB_2U_LIB.S9S_MB_2U(SCH_1):PAGE303',
 PHYS_PAGE='301',
 XY='(-15425,4600)',
 ROT='0',
 VER='2',
 PACK_TYPE='0402LF',
 LOCATION='PR3927',
 CDS_LIB='pure_quanta',
 CDS_PART_NAME='Q_RES_0402LF-4.99K,0.1%,1/16W,A',
 WATTAGE='1/16W',
 TOLERANCE='0.1%',
 MATERIAL='CHIP',
 ROOM='HSC1_BOM1',
 VALUE='4.99K',
 PRIM_FILE='./archive_libs/logical/q_res/chips/chips.prt';

PART_NAME
 PR3928 'Q_RES_0402LF-0,5%,1/16W,CHIP,CA':
 ROOM='HSC1_BOM1';

SECTION_NUMBER 1
 '@S9S_MB_2U_LIB.S9S_MB_2U(SCH_1):PAGE303_I41@PURE_QUANTA.Q_RES(CHIPS)':
 C_PATH='@s9s_mb_2u_lib.s9s_mb_2u(sch_1):page303_i41@pure_quanta.q_res(chips)',
 P_PATH='@s9s_mb_2u_lib.s9s_mb_2u(sch_1):page301_i41@pure_quanta.q_res(chips)',
 PATH='I41',
 DRAWING='@S9S_MB_2U_LIB.S9S_MB_2U(SCH_1):PAGE303',
 PHYS_PAGE='301',
 XY='(-14825,3225)',
 ROT='0',
 VER='1',
 PACK_TYPE='0402LF',
 LOCATION='PR3928',
 CDS_LIB='pure_quanta',
 CDS_PART_NAME='Q_RES_0402LF-0,5%,1/16W,CHIP,CA',
 WATTAGE='1/16W',
 TOLERANCE='5%',
 MATERIAL='CHIP',
 ROOM='HSC1_BOM1',
 VALUE='0',
 PRIM_FILE='./archive_libs/logical/q_res/chips/chips.prt';

PART_NAME
 PR3929 'Q_RES_0402LF-1K,1%,1/16W,EMPTYA':;

SECTION_NUMBER 1
 '@S9S_MB_2U_LIB.S9S_MB_2U(SCH_1):PAGE303_I42@PURE_QUANTA.Q_RES(CHIPS)':
 C_PATH='@s9s_mb_2u_lib.s9s_mb_2u(sch_1):page303_i42@pure_quanta.q_res(chips)',
 P_PATH='@s9s_mb_2u_lib.s9s_mb_2u(sch_1):page301_i42@pure_quanta.q_res(chips)',
 PATH='I42',
 DRAWING='@S9S_MB_2U_LIB.S9S_MB_2U(SCH_1):PAGE303',
 PHYS_PAGE='301',
 XY='(-14575,2850)',
 ROT='1',
 VER='1',
 PACK_TYPE='0402LF',
 LOCATION='PR3929',
 CDS_LIB='pure_quanta',
 CDS_PART_NAME='Q_RES_0402LF-1K,1%,1/16W,EMPTYA',
 WATTAGE='1/16W',
 TOLERANCE='1%',
 MATERIAL='EMPTY',
 VALUE='1K',
 PRIM_FILE='./archive_libs/logical/q_res/chips/chips.prt';

PART_NAME
 PR3930 'Q_RES_0402LF-0,5%,1/16W,CHIP,CA':
 ROOM='HSC1_BOM1';

SECTION_NUMBER 1
 '@S9S_MB_2U_LIB.S9S_MB_2U(SCH_1):PAGE303_I32@PURE_QUANTA.Q_RES(CHIPS)':
 C_PATH='@s9s_mb_2u_lib.s9s_mb_2u(sch_1):page303_i32@pure_quanta.q_res(chips)',
 P_PATH='@s9s_mb_2u_lib.s9s_mb_2u(sch_1):page301_i32@pure_quanta.q_res(chips)',
 PATH='I32',
 DRAWING='@S9S_MB_2U_LIB.S9S_MB_2U(SCH_1):PAGE303',
 PHYS_PAGE='301',
 XY='(-14575,2450)',
 ROT='1',
 VER='1',
 PACK_TYPE='0402LF',
 LOCATION='PR3930',
 CDS_LIB='pure_quanta',
 CDS_PART_NAME='Q_RES_0402LF-0,5%,1/16W,CHIP,CA',
 WATTAGE='1/16W',
 TOLERANCE='5%',
 MATERIAL='CHIP',
 ROOM='HSC1_BOM1',
 VALUE='0',
 PRIM_FILE='./archive_libs/logical/q_res/chips/chips.prt';

PART_NAME
 PR3931 'Q_RES_0402LF-75K,0.1%,1/16W,CHA':
 ROOM='HSC1_BOM1';

SECTION_NUMBER 1
 '@S9S_MB_2U_LIB.S9S_MB_2U(SCH_1):PAGE303_I86@PURE_QUANTA.Q_RES(CHIPS)':
 C_PATH='@s9s_mb_2u_lib.s9s_mb_2u(sch_1):page303_i86@pure_quanta.q_res(chips)',
 P_PATH='@s9s_mb_2u_lib.s9s_mb_2u(sch_1):page301_i86@pure_quanta.q_res(chips)',
 PATH='I86',
 DRAWING='@S9S_MB_2U_LIB.S9S_MB_2U(SCH_1):PAGE303',
 PHYS_PAGE='301',
 XY='(-12050,5125)',
 ROT='0',
 VER='2',
 PACK_TYPE='0402LF',
 LOCATION='PR3931',
 CDS_LIB='pure_quanta',
 CDS_PART_NAME='Q_RES_0402LF-75K,0.1%,1/16W,CHA',
 WATTAGE='1/16W',
 TOLERANCE='0.1%',
 MATERIAL='CHIP',
 ROOM='HSC1_BOM1',
 VALUE='75K',
 PRIM_FILE='./archive_libs/logical/q_res/chips/chips.prt';

PART_NAME
 PR3932 'Q_RES_0402LF-4.99K,0.1%,1/16W,A':
 ROOM='HSC1_BOM1';

SECTION_NUMBER 1
 '@S9S_MB_2U_LIB.S9S_MB_2U(SCH_1):PAGE303_I59@PURE_QUANTA.Q_RES(CHIPS)':
 C_PATH='@s9s_mb_2u_lib.s9s_mb_2u(sch_1):page303_i59@pure_quanta.q_res(chips)',
 P_PATH='@s9s_mb_2u_lib.s9s_mb_2u(sch_1):page301_i59@pure_quanta.q_res(chips)',
 PATH='I59',
 DRAWING='@S9S_MB_2U_LIB.S9S_MB_2U(SCH_1):PAGE303',
 PHYS_PAGE='301',
 XY='(-11975,4675)',
 ROT='0',
 VER='2',
 PACK_TYPE='0402LF',
 LOCATION='PR3932',
 CDS_LIB='pure_quanta',
 CDS_PART_NAME='Q_RES_0402LF-4.99K,0.1%,1/16W,A',
 WATTAGE='1/16W',
 TOLERANCE='0.1%',
 MATERIAL='CHIP',
 ROOM='HSC1_BOM1',
 VALUE='4.99K',
 PRIM_FILE='./archive_libs/logical/q_res/chips/chips.prt';

PART_NAME
 PR3935 'Q_RES_0402LF-10K,1%,1/16W,CHIPA':
 ROOM='HSC1_BOM1';

SECTION_NUMBER 1
 '@S9S_MB_2U_LIB.S9S_MB_2U(SCH_1):PAGE303_I79@PURE_QUANTA.Q_RES(CHIPS)':
 C_PATH='@s9s_mb_2u_lib.s9s_mb_2u(sch_1):page303_i79@pure_quanta.q_res(chips)',
 P_PATH='@s9s_mb_2u_lib.s9s_mb_2u(sch_1):page301_i79@pure_quanta.q_res(chips)',
 PATH='I79',
 DRAWING='@S9S_MB_2U_LIB.S9S_MB_2U(SCH_1):PAGE303',
 PHYS_PAGE='301',
 XY='(-10175,3150)',
 ROT='0',
 VER='2',
 PACK_TYPE='0402LF',
 LOCATION='PR3935',
 CDS_LIB='pure_quanta',
 CDS_PART_NAME='Q_RES_0402LF-10K,1%,1/16W,CHIPA',
 WATTAGE='1/16W',
 TOLERANCE='1%',
 MATERIAL='CHIP',
 ROOM='HSC1_BOM1',
 VALUE='10K',
 PRIM_FILE='./archive_libs/logical/q_res/chips/chips.prt';

PART_NAME
 PR3937 'Q_RES_0402LF-120K,1%,1/16W,CHIA':
 ROOM='HSC1_BOM1';

SECTION_NUMBER 1
 '@S9S_MB_2U_LIB.S9S_MB_2U(SCH_1):PAGE303_I84@PURE_QUANTA.Q_RES(CHIPS)':
 C_PATH='@s9s_mb_2u_lib.s9s_mb_2u(sch_1):page303_i84@pure_quanta.q_res(chips)',
 P_PATH='@s9s_mb_2u_lib.s9s_mb_2u(sch_1):page301_i84@pure_quanta.q_res(chips)',
 PATH='I84',
 DRAWING='@S9S_MB_2U_LIB.S9S_MB_2U(SCH_1):PAGE303',
 PHYS_PAGE='301',
 XY='(-9850,3975)',
 ROT='0',
 VER='1',
 PACK_TYPE='0402LF',
 LOCATION='PR3937',
 CDS_LIB='pure_quanta',
 CDS_PART_NAME='Q_RES_0402LF-120K,1%,1/16W,CHIA',
 WATTAGE='1/16W',
 TOLERANCE='1%',
 MATERIAL='CHIP',
 ROOM='HSC1_BOM1',
 VALUE='120K',
 PRIM_FILE='./archive_libs/logical/q_res/chips/chips.prt';

PART_NAME
 PR3944 'Q_RES_0402LF-46.4K,1%,1/16W,CHA':
 ROOM='E1S1_P12V_MPS_MAM_BOM3';

SECTION_NUMBER 1
 '@S9S_MB_2U_LIB.S9S_MB_2U(SCH_1):PAGE323_I40@PURE_QUANTA.Q_RES(CHIPS)':
 C_PATH='@s9s_mb_2u_lib.s9s_mb_2u(sch_1):page323_i40@pure_quanta.q_res(chips)',
 P_PATH='@s9s_mb_2u_lib.s9s_mb_2u(sch_1):page193_i40@pure_quanta.q_res(chips)',
 PATH='I40',
 DRAWING='@S9S_MB_2U_LIB.S9S_MB_2U(SCH_1):PAGE323',
 ROOM1='E1S1_P12V_MPS_TIC_BOM4',
 PHYS_PAGE='193',
 XY='(-1775,600)',
 ROT='0',
 VER='2',
 PACK_TYPE='0402LF',
 LOCATION='PR3944',
 CDS_LIB='pure_quanta',
 CDS_PART_NAME='Q_RES_0402LF-46.4K,1%,1/16W,CHA',
 WATTAGE='1/16W',
 TOLERANCE='1%',
 MATERIAL='CHIP',
 ROOM='E1S1_P12V_MPS_MAM_BOM3',
 VALUE='46.4K',
 PRIM_FILE='./archive_libs/logical/q_res/chips/chips.prt';

PART_NAME
 PR3945 'Q_RES_0402LF-71.5K,1%,1/16W,EMA':
 ROOM='E1S1_P3V3_BOM2';

SECTION_NUMBER 1
 '@S9S_MB_2U_LIB.S9S_MB_2U(SCH_1):PAGE323_I4@PURE_QUANTA.Q_RES(CHIPS)':
 C_PATH='@s9s_mb_2u_lib.s9s_mb_2u(sch_1):page323_i4@pure_quanta.q_res(chips)',
 P_PATH='@s9s_mb_2u_lib.s9s_mb_2u(sch_1):page193_i4@pure_quanta.q_res(chips)',
 PATH='I4',
 DRAWING='@S9S_MB_2U_LIB.S9S_MB_2U(SCH_1):PAGE323',
 PHYS_PAGE='193',
 XY='(-750,-1625)',
 ROT='0',
 VER='2',
 PACK_TYPE='0402LF',
 LOCATION='PR3945',
 CDS_LIB='pure_quanta',
 CDS_PART_NAME='Q_RES_0402LF-71.5K,1%,1/16W,EMA',
 WATTAGE='1/16W',
 TOLERANCE='1%',
 MATERIAL='EMPTY',
 ROOM='E1S1_P3V3_BOM2',
 VALUE='71.5K',
 PRIM_FILE='./archive_libs/logical/q_res/chips/chips.prt';

PART_NAME
 PR3947 'Q_RES_0402LF-2.8K,1%,1/16W,EMPA':
 ROOM='E1S1_P3V3_BOM2';

SECTION_NUMBER 1
 '@S9S_MB_2U_LIB.S9S_MB_2U(SCH_1):PAGE323_I6@PURE_QUANTA.Q_RES(CHIPS)':
 C_PATH='@s9s_mb_2u_lib.s9s_mb_2u(sch_1):page323_i6@pure_quanta.q_res(chips)',
 P_PATH='@s9s_mb_2u_lib.s9s_mb_2u(sch_1):page193_i6@pure_quanta.q_res(chips)',
 PATH='I6',
 DRAWING='@S9S_MB_2U_LIB.S9S_MB_2U(SCH_1):PAGE323',
 PHYS_PAGE='193',
 XY='(-425,-1675)',
 ROT='1',
 VER='1',
 PACK_TYPE='0402LF',
 LOCATION='PR3947',
 CDS_LIB='pure_quanta',
 CDS_PART_NAME='Q_RES_0402LF-2.8K,1%,1/16W,EMPA',
 WATTAGE='1/16W',
 TOLERANCE='1%',
 MATERIAL='EMPTY',
 ROOM='E1S1_P3V3_BOM2',
 VALUE='2.8K',
 PRIM_FILE='./archive_libs/logical/q_res/chips/chips.prt';

PART_NAME
 PR3949 'Q_RES_0402LF-56K,1%,1/16W,CHIPA':
 ROOM='E1S1_P12V_MPS_MAM_BOM3';

SECTION_NUMBER 1
 '@S9S_MB_2U_LIB.S9S_MB_2U(SCH_1):PAGE323_I53@PURE_QUANTA.Q_RES(CHIPS)':
 C_PATH='@s9s_mb_2u_lib.s9s_mb_2u(sch_1):page323_i53@pure_quanta.q_res(chips)',
 P_PATH='@s9s_mb_2u_lib.s9s_mb_2u(sch_1):page193_i53@pure_quanta.q_res(chips)',
 PATH='I53',
 DRAWING='@S9S_MB_2U_LIB.S9S_MB_2U(SCH_1):PAGE323',
 ROOM1='E1S1_P12V_MPS_TIC_BOM4',
 PHYS_PAGE='193',
 XY='(525,300)',
 ROT='0',
 VER='2',
 PACK_TYPE='0402LF',
 LOCATION='PR3949',
 CDS_LIB='pure_quanta',
 CDS_PART_NAME='Q_RES_0402LF-56K,1%,1/16W,CHIPA',
 WATTAGE='1/16W',
 TOLERANCE='1%',
 MATERIAL='CHIP',
 ROOM='E1S1_P12V_MPS_MAM_BOM3',
 VALUE='56K',
 PRIM_FILE='./archive_libs/logical/q_res/chips/chips.prt';

PART_NAME
 PR3950 'Q_RES_0402LF-100,1%,1/16W,EMPTA':;

SECTION_NUMBER 1
 '@S9S_MB_2U_LIB.S9S_MB_2U(SCH_1):PAGE323_I55@PURE_QUANTA.Q_RES(CHIPS)':
 C_PATH='@s9s_mb_2u_lib.s9s_mb_2u(sch_1):page323_i55@pure_quanta.q_res(chips)',
 P_PATH='@s9s_mb_2u_lib.s9s_mb_2u(sch_1):page193_i55@pure_quanta.q_res(chips)',
 PATH='I55',
 DRAWING='@S9S_MB_2U_LIB.S9S_MB_2U(SCH_1):PAGE323',
 PHYS_PAGE='193',
 XY='(900,1150)',
 ROT='0',
 VER='2',
 PACK_TYPE='0402LF',
 LOCATION='PR3950',
 CDS_LIB='pure_quanta',
 CDS_PART_NAME='Q_RES_0402LF-100,1%,1/16W,EMPTA',
 WATTAGE='1/16W',
 TOLERANCE='1%',
 MATERIAL='EMPTY',
 VALUE='100',
 PRIM_FILE='./archive_libs/logical/q_res/chips/chips.prt';

PART_NAME
 PR3951 'Q_RES_0402LF-10K,1%,1/16W,CHIPA':
 ROOM='E1S1_P12V_MPS_MAM_BOM3';

SECTION_NUMBER 1
 '@S9S_MB_2U_LIB.S9S_MB_2U(SCH_1):PAGE323_I54@PURE_QUANTA.Q_RES(CHIPS)':
 C_PATH='@s9s_mb_2u_lib.s9s_mb_2u(sch_1):page323_i54@pure_quanta.q_res(chips)',
 P_PATH='@s9s_mb_2u_lib.s9s_mb_2u(sch_1):page193_i54@pure_quanta.q_res(chips)',
 PATH='I54',
 DRAWING='@S9S_MB_2U_LIB.S9S_MB_2U(SCH_1):PAGE323',
 ROOM1='E1S1_P12V_MPS_TIC_BOM4',
 PHYS_PAGE='193',
 XY='(950,675)',
 ROT='0',
 VER='1',
 PACK_TYPE='0402LF',
 LOCATION='PR3951',
 CDS_LIB='pure_quanta',
 CDS_PART_NAME='Q_RES_0402LF-10K,1%,1/16W,CHIPA',
 WATTAGE='1/16W',
 TOLERANCE='1%',
 MATERIAL='CHIP',
 ROOM='E1S1_P12V_MPS_MAM_BOM3',
 VALUE='10K',
 PRIM_FILE='./archive_libs/logical/q_res/chips/chips.prt';

PART_NAME
 PR3952 'Q_RES_0402LF-71.5K,1%,1/16W,EMA':;

SECTION_NUMBER 1
 '@S9S_MB_2U_LIB.S9S_MB_2U(SCH_1):PAGE323_I62@PURE_QUANTA.Q_RES(CHIPS)':
 C_PATH='@s9s_mb_2u_lib.s9s_mb_2u(sch_1):page323_i62@pure_quanta.q_res(chips)',
 P_PATH='@s9s_mb_2u_lib.s9s_mb_2u(sch_1):page193_i62@pure_quanta.q_res(chips)',
 PATH='I62',
 DRAWING='@S9S_MB_2U_LIB.S9S_MB_2U(SCH_1):PAGE323',
 PHYS_PAGE='193',
 XY='(1500,1150)',
 ROT='0',
 VER='2',
 PACK_TYPE='0402LF',
 LOCATION='PR3952',
 CDS_LIB='pure_quanta',
 CDS_PART_NAME='Q_RES_0402LF-71.5K,1%,1/16W,EMA',
 WATTAGE='1/16W',
 TOLERANCE='1%',
 MATERIAL='EMPTY',
 VALUE='71.5K',
 PRIM_FILE='./archive_libs/logical/q_res/chips/chips.prt';

PART_NAME
 PR3953 'Q_RES_0402LF-120K,1%,1/16W,CHIA':
 ROOM='E1S1_P12V_MPS_MAM_BOM3';

SECTION_NUMBER 1
 '@S9S_MB_2U_LIB.S9S_MB_2U(SCH_1):PAGE323_I63@PURE_QUANTA.Q_RES(CHIPS)':
 C_PATH='@s9s_mb_2u_lib.s9s_mb_2u(sch_1):page323_i63@pure_quanta.q_res(chips)',
 P_PATH='@s9s_mb_2u_lib.s9s_mb_2u(sch_1):page193_i63@pure_quanta.q_res(chips)',
 PATH='I63',
 DRAWING='@S9S_MB_2U_LIB.S9S_MB_2U(SCH_1):PAGE323',
 ROOM1='E1S1_P12V_MPS_TIC_BOM4',
 PHYS_PAGE='193',
 XY='(1900,1075)',
 ROT='0',
 VER='2',
 PACK_TYPE='0402LF',
 LOCATION='PR3953',
 CDS_LIB='pure_quanta',
 CDS_PART_NAME='Q_RES_0402LF-120K,1%,1/16W,CHIA',
 WATTAGE='1/16W',
 TOLERANCE='1%',
 MATERIAL='CHIP',
 ROOM='E1S1_P12V_MPS_MAM_BOM3',
 VALUE='120K',
 PRIM_FILE='./archive_libs/logical/q_res/chips/chips.prt';

PART_NAME
 PR3954 'Q_RES_0402LF-10K,1%,1/16W,CHIPA':
 ROOM='E1S1_P12V_MPS_MAM_BOM3';

SECTION_NUMBER 1
 '@S9S_MB_2U_LIB.S9S_MB_2U(SCH_1):PAGE323_I58@PURE_QUANTA.Q_RES(CHIPS)':
 C_PATH='@s9s_mb_2u_lib.s9s_mb_2u(sch_1):page323_i58@pure_quanta.q_res(chips)',
 P_PATH='@s9s_mb_2u_lib.s9s_mb_2u(sch_1):page193_i58@pure_quanta.q_res(chips)',
 PATH='I58',
 DRAWING='@S9S_MB_2U_LIB.S9S_MB_2U(SCH_1):PAGE323',
 ROOM1='E1S1_P12V_MPS_TIC_BOM4',
 PHYS_PAGE='193',
 XY='(1900,650)',
 ROT='0',
 VER='2',
 PACK_TYPE='0402LF',
 LOCATION='PR3954',
 CDS_LIB='pure_quanta',
 CDS_PART_NAME='Q_RES_0402LF-10K,1%,1/16W,CHIPA',
 WATTAGE='1/16W',
 TOLERANCE='1%',
 MATERIAL='CHIP',
 ROOM='E1S1_P12V_MPS_MAM_BOM3',
 VALUE='10K',
 PRIM_FILE='./archive_libs/logical/q_res/chips/chips.prt';

PART_NAME
 PR3957 'Q_RES_0603LF-49.9,1%,1/10W,CHIA':
 ROOM='E1S1_P12V_MPS_MAM_BOM3';

SECTION_NUMBER 1
 '@S9S_MB_2U_LIB.S9S_MB_2U(SCH_1):PAGE323_I70@PURE_QUANTA.Q_RES(CHIPS)':
 C_PATH='@s9s_mb_2u_lib.s9s_mb_2u(sch_1):page323_i70@pure_quanta.q_res(chips)',
 P_PATH='@s9s_mb_2u_lib.s9s_mb_2u(sch_1):page193_i70@pure_quanta.q_res(chips)',
 PATH='I70',
 DRAWING='@S9S_MB_2U_LIB.S9S_MB_2U(SCH_1):PAGE323',
 ROOM1='E1S1_P12V_MPS_TIC_BOM4',
 PHYS_PAGE='193',
 XY='(2425,1075)',
 ROT='0',
 VER='2',
 PACK_TYPE='0603LF',
 LOCATION='PR3957',
 CDS_LIB='pure_quanta',
 CDS_PART_NAME='Q_RES_0603LF-49.9,1%,1/10W,CHIA',
 WATTAGE='1/10W',
 TOLERANCE='1%',
 MATERIAL='CHIP',
 ROOM='E1S1_P12V_MPS_MAM_BOM3',
 VALUE='49.9',
 PRIM_FILE='./archive_libs/logical/q_res/chips/chips.prt';

PART_NAME
 PR3960 'Q_RES_0402LF-160K,1%,1/16W,EMPA':
 ROOM='E1S1_P12V_MAM_MAM_BOM1';

SECTION_NUMBER 1
 '@S9S_MB_2U_LIB.S9S_MB_2U(SCH_1):PAGE324_I32@PURE_QUANTA.Q_RES(CHIPS)':
 C_PATH='@s9s_mb_2u_lib.s9s_mb_2u(sch_1):page324_i32@pure_quanta.q_res(chips)',
 P_PATH='@s9s_mb_2u_lib.s9s_mb_2u(sch_1):page192_i32@pure_quanta.q_res(chips)',
 PATH='I32',
 DRAWING='@S9S_MB_2U_LIB.S9S_MB_2U(SCH_1):PAGE324',
 ROOM1='E1S1_P12V_MAM_TIC_BOM2',
 PHYS_PAGE='192',
 XY='(-150,1325)',
 ROT='0',
 VER='2',
 PACK_TYPE='0402LF',
 LOCATION='PR3960',
 CDS_LIB='pure_quanta',
 CDS_PART_NAME='Q_RES_0402LF-160K,1%,1/16W,EMPA',
 WATTAGE='1/16W',
 TOLERANCE='1%',
 MATERIAL='EMPTY',
 ROOM='E1S1_P12V_MAM_MAM_BOM1',
 VALUE='160K',
 PRIM_FILE='./archive_libs/logical/q_res/chips/chips.prt';

PART_NAME
 PR3961 'Q_RES_0402LF-6.8K,1%,1/16W,EMPA':
 ROOM='E1S1_P12V_MAM_MAM_BOM1';

SECTION_NUMBER 1
 '@S9S_MB_2U_LIB.S9S_MB_2U(SCH_1):PAGE324_I85@PURE_QUANTA.Q_RES(CHIPS)':
 C_PATH='@s9s_mb_2u_lib.s9s_mb_2u(sch_1):page324_i85@pure_quanta.q_res(chips)',
 P_PATH='@s9s_mb_2u_lib.s9s_mb_2u(sch_1):page192_i85@pure_quanta.q_res(chips)',
 PATH='I85',
 DRAWING='@S9S_MB_2U_LIB.S9S_MB_2U(SCH_1):PAGE324',
 ROOM1='E1S1_P12V_MAM_TIC_BOM2',
 PHYS_PAGE='192',
 XY='(-150,650)',
 ROT='0',
 VER='2',
 PACK_TYPE='0402LF',
 LOCATION='PR3961',
 CDS_LIB='pure_quanta',
 CDS_PART_NAME='Q_RES_0402LF-6.8K,1%,1/16W,EMPA',
 WATTAGE='1/16W',
 TOLERANCE='1%',
 MATERIAL='EMPTY',
 ROOM='E1S1_P12V_MAM_MAM_BOM1',
 VALUE='6.8K',
 PRIM_FILE='./archive_libs/logical/q_res/chips/chips.prt';

PART_NAME
 PR3962 'Q_RES_0402LF-15K,1%,1/16W,EMPTA':
 ROOM='E1S1_P12V_MAM_MAM_BOM1';

SECTION_NUMBER 1
 '@S9S_MB_2U_LIB.S9S_MB_2U(SCH_1):PAGE324_I28@PURE_QUANTA.Q_RES(CHIPS)':
 C_PATH='@s9s_mb_2u_lib.s9s_mb_2u(sch_1):page324_i28@pure_quanta.q_res(chips)',
 P_PATH='@s9s_mb_2u_lib.s9s_mb_2u(sch_1):page192_i28@pure_quanta.q_res(chips)',
 PATH='I28',
 DRAWING='@S9S_MB_2U_LIB.S9S_MB_2U(SCH_1):PAGE324',
 ROOM1='E1S1_P12V_MAM_TIC_BOM2',
 PHYS_PAGE='192',
 XY='(-150,375)',
 ROT='0',
 VER='2',
 PACK_TYPE='0402LF',
 LOCATION='PR3962',
 CDS_LIB='pure_quanta',
 CDS_PART_NAME='Q_RES_0402LF-15K,1%,1/16W,EMPTA',
 WATTAGE='1/16W',
 TOLERANCE='1%',
 MATERIAL='EMPTY',
 ROOM='E1S1_P12V_MAM_MAM_BOM1',
 VALUE='15K',
 PRIM_FILE='./archive_libs/logical/q_res/chips/chips.prt';

PART_NAME
 PR3963 'Q_RES_0402LF-25.5K,1%,1/16W,CHA':
 ROOM='E1S1_P3V3_BOM1';

SECTION_NUMBER 1
 '@S9S_MB_2U_LIB.S9S_MB_2U(SCH_1):PAGE324_I18@PURE_QUANTA.Q_RES(CHIPS)':
 C_PATH='@s9s_mb_2u_lib.s9s_mb_2u(sch_1):page324_i18@pure_quanta.q_res(chips)',
 P_PATH='@s9s_mb_2u_lib.s9s_mb_2u(sch_1):page192_i18@pure_quanta.q_res(chips)',
 PATH='I18',
 DRAWING='@S9S_MB_2U_LIB.S9S_MB_2U(SCH_1):PAGE324',
 PHYS_PAGE='192',
 XY='(-125,-1350)',
 ROT='0',
 VER='2',
 PACK_TYPE='0402LF',
 LOCATION='PR3963',
 CDS_LIB='pure_quanta',
 CDS_PART_NAME='Q_RES_0402LF-25.5K,1%,1/16W,CHA',
 WATTAGE='1/16W',
 TOLERANCE='1%',
 MATERIAL='CHIP',
 ROOM='E1S1_P3V3_BOM1',
 VALUE='25.5K',
 PRIM_FILE='./archive_libs/logical/q_res/chips/chips.prt';

PART_NAME
 PR3964 'Q_RES_0402LF-7.15K,1%,1/16W,CHA':
 ROOM='E1S1_P3V3_BOM1';

SECTION_NUMBER 1
 '@S9S_MB_2U_LIB.S9S_MB_2U(SCH_1):PAGE324_I14@PURE_QUANTA.Q_RES(CHIPS)':
 C_PATH='@s9s_mb_2u_lib.s9s_mb_2u(sch_1):page324_i14@pure_quanta.q_res(chips)',
 P_PATH='@s9s_mb_2u_lib.s9s_mb_2u(sch_1):page192_i14@pure_quanta.q_res(chips)',
 PATH='I14',
 DRAWING='@S9S_MB_2U_LIB.S9S_MB_2U(SCH_1):PAGE324',
 PHYS_PAGE='192',
 XY='(-125,-2075)',
 ROT='0',
 VER='2',
 PACK_TYPE='0402LF',
 LOCATION='PR3964',
 CDS_LIB='pure_quanta',
 CDS_PART_NAME='Q_RES_0402LF-7.15K,1%,1/16W,CHA',
 WATTAGE='1/16W',
 TOLERANCE='1%',
 MATERIAL='CHIP',
 ROOM='E1S1_P3V3_BOM1',
 VALUE='7.15K',
 PRIM_FILE='./archive_libs/logical/q_res/chips/chips.prt';

PART_NAME
 PR3965 'Q_RES_0402LF-15K,1%,1/16W,CHIPA':
 ROOM='E1S1_P3V3_BOM1';

SECTION_NUMBER 1
 '@S9S_MB_2U_LIB.S9S_MB_2U(SCH_1):PAGE324_I13@PURE_QUANTA.Q_RES(CHIPS)':
 C_PATH='@s9s_mb_2u_lib.s9s_mb_2u(sch_1):page324_i13@pure_quanta.q_res(chips)',
 P_PATH='@s9s_mb_2u_lib.s9s_mb_2u(sch_1):page192_i13@pure_quanta.q_res(chips)',
 PATH='I13',
 DRAWING='@S9S_MB_2U_LIB.S9S_MB_2U(SCH_1):PAGE324',
 PHYS_PAGE='192',
 XY='(-125,-2350)',
 ROT='0',
 VER='2',
 PACK_TYPE='0402LF',
 LOCATION='PR3965',
 CDS_LIB='pure_quanta',
 CDS_PART_NAME='Q_RES_0402LF-15K,1%,1/16W,CHIPA',
 WATTAGE='1/16W',
 TOLERANCE='1%',
 MATERIAL='CHIP',
 ROOM='E1S1_P3V3_BOM1',
 VALUE='15K',
 PRIM_FILE='./archive_libs/logical/q_res/chips/chips.prt';

PART_NAME
 PR3966 'Q_RES_0402LF-10,1%,1/16W,EMPTYA':
 ROOM='E1S1_P12V_MAM_MAM_BOM1';

SECTION_NUMBER 1
 '@S9S_MB_2U_LIB.S9S_MB_2U(SCH_1):PAGE324_I61@PURE_QUANTA.Q_RES(CHIPS)':
 C_PATH='@s9s_mb_2u_lib.s9s_mb_2u(sch_1):page324_i61@pure_quanta.q_res(chips)',
 P_PATH='@s9s_mb_2u_lib.s9s_mb_2u(sch_1):page192_i61@pure_quanta.q_res(chips)',
 PATH='I61',
 DRAWING='@S9S_MB_2U_LIB.S9S_MB_2U(SCH_1):PAGE324',
 ROOM1='E1S1_P12V_MAM_TIC_BOM2',
 PHYS_PAGE='192',
 XY='(175,1625)',
 ROT='0',
 VER='2',
 PACK_TYPE='0402LF',
 LOCATION='PR3966',
 CDS_LIB='pure_quanta',
 CDS_PART_NAME='Q_RES_0402LF-10,1%,1/16W,EMPTYA',
 WATTAGE='1/16W',
 TOLERANCE='1%',
 MATERIAL='EMPTY',
 ROOM='E1S1_P12V_MAM_MAM_BOM1',
 VALUE='10',
 PRIM_FILE='./archive_libs/logical/q_res/chips/chips.prt';

PART_NAME
 PR3967 'Q_RES_0402LF-10,1%,1/16W,CHIP,A':
 ROOM='E1S1_P3V3_BOM1';

SECTION_NUMBER 1
 '@S9S_MB_2U_LIB.S9S_MB_2U(SCH_1):PAGE324_I39@PURE_QUANTA.Q_RES(CHIPS)':
 C_PATH='@s9s_mb_2u_lib.s9s_mb_2u(sch_1):page324_i39@pure_quanta.q_res(chips)',
 P_PATH='@s9s_mb_2u_lib.s9s_mb_2u(sch_1):page192_i39@pure_quanta.q_res(chips)',
 PATH='I39',
 DRAWING='@S9S_MB_2U_LIB.S9S_MB_2U(SCH_1):PAGE324',
 PHYS_PAGE='192',
 XY='(200,-1100)',
 ROT='0',
 VER='2',
 PACK_TYPE='0402LF',
 LOCATION='PR3967',
 CDS_LIB='pure_quanta',
 CDS_PART_NAME='Q_RES_0402LF-10,1%,1/16W,CHIP,A',
 WATTAGE='1/16W',
 TOLERANCE='1%',
 MATERIAL='CHIP',
 ROOM='E1S1_P3V3_BOM1',
 VALUE='10',
 PRIM_FILE='./archive_libs/logical/q_res/chips/chips.prt';

PART_NAME
 PR3968 'Q_RES_0402LF-9.31K,1%,1/16W,EMA':
 ROOM='E1S1_P12V_MAM_MAM_BOM1';

SECTION_NUMBER 1
 '@S9S_MB_2U_LIB.S9S_MB_2U(SCH_1):PAGE324_I59@PURE_QUANTA.Q_RES(CHIPS)':
 C_PATH='@s9s_mb_2u_lib.s9s_mb_2u(sch_1):page324_i59@pure_quanta.q_res(chips)',
 P_PATH='@s9s_mb_2u_lib.s9s_mb_2u(sch_1):page192_i59@pure_quanta.q_res(chips)',
 PATH='I59',
 DRAWING='@S9S_MB_2U_LIB.S9S_MB_2U(SCH_1):PAGE324',
 ROOM1='E1S1_P12V_MAM_TIC_BOM2',
 PHYS_PAGE='192',
 XY='(700,400)',
 ROT='0',
 VER='2',
 PACK_TYPE='0402LF',
 LOCATION='PR3968',
 CDS_LIB='pure_quanta',
 CDS_PART_NAME='Q_RES_0402LF-9.31K,1%,1/16W,EMA',
 WATTAGE='1/16W',
 TOLERANCE='1%',
 MATERIAL='EMPTY',
 ROOM='E1S1_P12V_MAM_MAM_BOM1',
 VALUE='9.31K',
 PRIM_FILE='./archive_libs/logical/q_res/chips/chips.prt';

PART_NAME
 PR3969 'Q_RES_0402LF-2.49K,1%,1/16W,CHA':
 ROOM='E1S1_P3V3_BOM1';

SECTION_NUMBER 1
 '@S9S_MB_2U_LIB.S9S_MB_2U(SCH_1):PAGE324_I34@PURE_QUANTA.Q_RES(CHIPS)':
 C_PATH='@s9s_mb_2u_lib.s9s_mb_2u(sch_1):page324_i34@pure_quanta.q_res(chips)',
 P_PATH='@s9s_mb_2u_lib.s9s_mb_2u(sch_1):page192_i34@pure_quanta.q_res(chips)',
 PATH='I34',
 DRAWING='@S9S_MB_2U_LIB.S9S_MB_2U(SCH_1):PAGE324',
 PHYS_PAGE='192',
 XY='(725,-2325)',
 ROT='0',
 VER='2',
 PACK_TYPE='0402LF',
 LOCATION='PR3969',
 CDS_LIB='pure_quanta',
 CDS_PART_NAME='Q_RES_0402LF-2.49K,1%,1/16W,CHA',
 WATTAGE='1/16W',
 TOLERANCE='1%',
 MATERIAL='CHIP',
 ROOM='E1S1_P3V3_BOM1',
 VALUE='2.49K',
 PRIM_FILE='./archive_libs/logical/q_res/chips/chips.prt';

PART_NAME
 PR3970 'Q_RES_0402LF-2.67K,1%,1/16W,EMA':
 ROOM='E1S1_P12V_MAM_MAM_BOM1';

SECTION_NUMBER 1
 '@S9S_MB_2U_LIB.S9S_MB_2U(SCH_1):PAGE324_I64@PURE_QUANTA.Q_RES(CHIPS)':
 C_PATH='@s9s_mb_2u_lib.s9s_mb_2u(sch_1):page324_i64@pure_quanta.q_res(chips)',
 P_PATH='@s9s_mb_2u_lib.s9s_mb_2u(sch_1):page192_i64@pure_quanta.q_res(chips)',
 PATH='I64',
 DRAWING='@S9S_MB_2U_LIB.S9S_MB_2U(SCH_1):PAGE324',
 ROOM1='E1S1_P12V_MAM_TIC_BOM2',
 PHYS_PAGE='192',
 XY='(2300,525)',
 ROT='0',
 VER='2',
 PACK_TYPE='0402LF',
 LOCATION='PR3970',
 CDS_LIB='pure_quanta',
 CDS_PART_NAME='Q_RES_0402LF-2.67K,1%,1/16W,EMA',
 WATTAGE='1/16W',
 TOLERANCE='1%',
 MATERIAL='EMPTY',
 ROOM='E1S1_P12V_MAM_MAM_BOM1',
 VALUE='2.67K',
 PRIM_FILE='./archive_libs/logical/q_res/chips/chips.prt';

PART_NAME
 PR3971 'Q_RES_0402LF-9.76K,1%,1/16W,CHA':
 ROOM='E1S1_P3V3_BOM1';

SECTION_NUMBER 1
 '@S9S_MB_2U_LIB.S9S_MB_2U(SCH_1):PAGE324_I41@PURE_QUANTA.Q_RES(CHIPS)':
 C_PATH='@s9s_mb_2u_lib.s9s_mb_2u(sch_1):page324_i41@pure_quanta.q_res(chips)',
 P_PATH='@s9s_mb_2u_lib.s9s_mb_2u(sch_1):page192_i41@pure_quanta.q_res(chips)',
 PATH='I41',
 DRAWING='@S9S_MB_2U_LIB.S9S_MB_2U(SCH_1):PAGE324',
 PHYS_PAGE='192',
 XY='(2325,-2175)',
 ROT='0',
 VER='2',
 PACK_TYPE='0402LF',
 LOCATION='PR3971',
 CDS_LIB='pure_quanta',
 CDS_PART_NAME='Q_RES_0402LF-9.76K,1%,1/16W,CHA',
 WATTAGE='1/16W',
 TOLERANCE='1%',
 MATERIAL='CHIP',
 ROOM='E1S1_P3V3_BOM1',
 VALUE='9.76K',
 PRIM_FILE='./archive_libs/logical/q_res/chips/chips.prt';

PART_NAME
 PR3980 'Q_RES_0402LF-0,5%,1/16W,CHIP,CA':
 ROOM='HSC1_BOM1';

SECTION_NUMBER 1
 '@S9S_MB_2U_LIB.S9S_MB_2U(SCH_1):PAGE325_I21@PURE_QUANTA.Q_RES(CHIPS)':
 C_PATH='@s9s_mb_2u_lib.s9s_mb_2u(sch_1):page325_i21@pure_quanta.q_res(chips)',
 P_PATH='@s9s_mb_2u_lib.s9s_mb_2u(sch_1):page303_i21@pure_quanta.q_res(chips)',
 PATH='I21',
 DRAWING='@S9S_MB_2U_LIB.S9S_MB_2U(SCH_1):PAGE325',
 PHYS_PAGE='303',
 XY='(-2775,2075)',
 ROT='1',
 VER='1',
 PACK_TYPE='0402LF',
 LOCATION='PR3980',
 CDS_LIB='pure_quanta',
 CDS_PART_NAME='Q_RES_0402LF-0,5%,1/16W,CHIP,CA',
 WATTAGE='1/16W',
 TOLERANCE='5%',
 MATERIAL='CHIP',
 ROOM='HSC1_BOM1',
 VALUE='0',
 PRIM_FILE='./archive_libs/logical/q_res/chips/chips.prt';

PART_NAME
 PR3981 'Q_RES_0402LF-0,5%,1/16W,CHIP,CA':
 ROOM='HSC1_BOM1';

SECTION_NUMBER 1
 '@S9S_MB_2U_LIB.S9S_MB_2U(SCH_1):PAGE325_I5@PURE_QUANTA.Q_RES(CHIPS)':
 C_PATH='@s9s_mb_2u_lib.s9s_mb_2u(sch_1):page325_i5@pure_quanta.q_res(chips)',
 P_PATH='@s9s_mb_2u_lib.s9s_mb_2u(sch_1):page303_i5@pure_quanta.q_res(chips)',
 PATH='I5',
 DRAWING='@S9S_MB_2U_LIB.S9S_MB_2U(SCH_1):PAGE325',
 PHYS_PAGE='303',
 XY='(-2750,-700)',
 ROT='1',
 VER='1',
 PACK_TYPE='0402LF',
 LOCATION='PR3981',
 CDS_LIB='pure_quanta',
 CDS_PART_NAME='Q_RES_0402LF-0,5%,1/16W,CHIP,CA',
 WATTAGE='1/16W',
 TOLERANCE='5%',
 MATERIAL='CHIP',
 ROOM='HSC1_BOM1',
 VALUE='0',
 PRIM_FILE='./archive_libs/logical/q_res/chips/chips.prt';

PART_NAME
 PR3982 'Q_RES_0402LF-120K,1%,1/16W,CHIA':
 ROOM='HSC1_BOM1';

SECTION_NUMBER 1
 '@S9S_MB_2U_LIB.S9S_MB_2U(SCH_1):PAGE325_I32@PURE_QUANTA.Q_RES(CHIPS)':
 C_PATH='@s9s_mb_2u_lib.s9s_mb_2u(sch_1):page325_i32@pure_quanta.q_res(chips)',
 P_PATH='@s9s_mb_2u_lib.s9s_mb_2u(sch_1):page303_i32@pure_quanta.q_res(chips)',
 PATH='I32',
 DRAWING='@S9S_MB_2U_LIB.S9S_MB_2U(SCH_1):PAGE325',
 PHYS_PAGE='303',
 XY='(-1075,1775)',
 ROT='0',
 VER='1',
 PACK_TYPE='0402LF',
 LOCATION='PR3982',
 CDS_LIB='pure_quanta',
 CDS_PART_NAME='Q_RES_0402LF-120K,1%,1/16W,CHIA',
 WATTAGE='1/16W',
 TOLERANCE='1%',
 MATERIAL='CHIP',
 ROOM='HSC1_BOM1',
 VALUE='120K',
 PRIM_FILE='./archive_libs/logical/q_res/chips/chips.prt';

PART_NAME
 PR3984 'Q_RES_0402LF-120K,1%,1/16W,CHIA':
 ROOM='HSC1_BOM1';

SECTION_NUMBER 1
 '@S9S_MB_2U_LIB.S9S_MB_2U(SCH_1):PAGE325_I14@PURE_QUANTA.Q_RES(CHIPS)':
 C_PATH='@s9s_mb_2u_lib.s9s_mb_2u(sch_1):page325_i14@pure_quanta.q_res(chips)',
 P_PATH='@s9s_mb_2u_lib.s9s_mb_2u(sch_1):page303_i14@pure_quanta.q_res(chips)',
 PATH='I14',
 DRAWING='@S9S_MB_2U_LIB.S9S_MB_2U(SCH_1):PAGE325',
 PHYS_PAGE='303',
 XY='(-1075,-1000)',
 ROT='0',
 VER='1',
 PACK_TYPE='0402LF',
 LOCATION='PR3984',
 CDS_LIB='pure_quanta',
 CDS_PART_NAME='Q_RES_0402LF-120K,1%,1/16W,CHIA',
 WATTAGE='1/16W',
 TOLERANCE='1%',
 MATERIAL='CHIP',
 ROOM='HSC1_BOM1',
 VALUE='120K',
 PRIM_FILE='./archive_libs/logical/q_res/chips/chips.prt';

PART_NAME
 PR3986 'Q_RES_0402LF-2K,0.1%,1/16W,CHIA':
 ROOM='HSC1_BOM1';

SECTION_NUMBER 1
 '@S9S_MB_2U_LIB.S9S_MB_2U(SCH_1):PAGE325_I30@PURE_QUANTA.Q_RES(CHIPS)':
 C_PATH='@s9s_mb_2u_lib.s9s_mb_2u(sch_1):page325_i30@pure_quanta.q_res(chips)',
 P_PATH='@s9s_mb_2u_lib.s9s_mb_2u(sch_1):page303_i30@pure_quanta.q_res(chips)',
 PATH='I30',
 DRAWING='@S9S_MB_2U_LIB.S9S_MB_2U(SCH_1):PAGE325',
 PHYS_PAGE='303',
 XY='(-650,950)',
 ROT='0',
 VER='2',
 PACK_TYPE='0402LF',
 LOCATION='PR3986',
 CDS_LIB='pure_quanta',
 CDS_PART_NAME='Q_RES_0402LF-2K,0.1%,1/16W,CHIA',
 WATTAGE='1/16W',
 TOLERANCE='0.1%',
 MATERIAL='CHIP',
 ROOM='HSC1_BOM1',
 VALUE='2K',
 PRIM_FILE='./archive_libs/logical/q_res/chips/chips.prt';

PART_NAME
 PR3987 'Q_RES_0402LF-2K,0.1%,1/16W,CHIA':
 ROOM='HSC1_BOM1';

SECTION_NUMBER 1
 '@S9S_MB_2U_LIB.S9S_MB_2U(SCH_1):PAGE325_I12@PURE_QUANTA.Q_RES(CHIPS)':
 C_PATH='@s9s_mb_2u_lib.s9s_mb_2u(sch_1):page325_i12@pure_quanta.q_res(chips)',
 P_PATH='@s9s_mb_2u_lib.s9s_mb_2u(sch_1):page303_i12@pure_quanta.q_res(chips)',
 PATH='I12',
 DRAWING='@S9S_MB_2U_LIB.S9S_MB_2U(SCH_1):PAGE325',
 PHYS_PAGE='303',
 XY='(-650,-1825)',
 ROT='0',
 VER='2',
 PACK_TYPE='0402LF',
 LOCATION='PR3987',
 CDS_LIB='pure_quanta',
 CDS_PART_NAME='Q_RES_0402LF-2K,0.1%,1/16W,CHIA',
 WATTAGE='1/16W',
 TOLERANCE='0.1%',
 MATERIAL='CHIP',
 ROOM='HSC1_BOM1',
 VALUE='2K',
 PRIM_FILE='./archive_libs/logical/q_res/chips/chips.prt';

PART_NAME
 PR3988 'Q_RES_0402LF-0,5%,1/16W,CHIP,CA':
 ROOM='HSC1_BOM1';

SECTION_NUMBER 1
 '@S9S_MB_2U_LIB.S9S_MB_2U(SCH_1):PAGE325_I33@PURE_QUANTA.Q_RES(CHIPS)':
 C_PATH='@s9s_mb_2u_lib.s9s_mb_2u(sch_1):page325_i33@pure_quanta.q_res(chips)',
 P_PATH='@s9s_mb_2u_lib.s9s_mb_2u(sch_1):page303_i33@pure_quanta.q_res(chips)',
 PATH='I33',
 DRAWING='@S9S_MB_2U_LIB.S9S_MB_2U(SCH_1):PAGE325',
 PHYS_PAGE='303',
 XY='(-500,1600)',
 ROT='0',
 VER='1',
 PACK_TYPE='0402LF',
 LOCATION='PR3988',
 CDS_LIB='pure_quanta',
 CDS_PART_NAME='Q_RES_0402LF-0,5%,1/16W,CHIP,CA',
 WATTAGE='1/16W',
 TOLERANCE='5%',
 MATERIAL='CHIP',
 ROOM='HSC1_BOM1',
 VALUE='0',
 PRIM_FILE='./archive_libs/logical/q_res/chips/chips.prt';

PART_NAME
 PR3989 'Q_RES_0402LF-0,5%,1/16W,CHIP,CA':
 ROOM='HSC1_BOM1';

SECTION_NUMBER 1
 '@S9S_MB_2U_LIB.S9S_MB_2U(SCH_1):PAGE325_I16@PURE_QUANTA.Q_RES(CHIPS)':
 C_PATH='@s9s_mb_2u_lib.s9s_mb_2u(sch_1):page325_i16@pure_quanta.q_res(chips)',
 P_PATH='@s9s_mb_2u_lib.s9s_mb_2u(sch_1):page303_i16@pure_quanta.q_res(chips)',
 PATH='I16',
 DRAWING='@S9S_MB_2U_LIB.S9S_MB_2U(SCH_1):PAGE325',
 PHYS_PAGE='303',
 XY='(-475,-1175)',
 ROT='0',
 VER='1',
 PACK_TYPE='0402LF',
 LOCATION='PR3989',
 CDS_LIB='pure_quanta',
 CDS_PART_NAME='Q_RES_0402LF-0,5%,1/16W,CHIP,CA',
 WATTAGE='1/16W',
 TOLERANCE='5%',
 MATERIAL='CHIP',
 ROOM='HSC1_BOM1',
 VALUE='0',
 PRIM_FILE='./archive_libs/logical/q_res/chips/chips.prt';

PART_NAME
 PR3990 'Q_RES_0402LF-2K,0.1%,1/16W,CHIA':
 ROOM='HSC1_BOM1';

SECTION_NUMBER 1
 '@S9S_MB_2U_LIB.S9S_MB_2U(SCH_1):PAGE325_I34@PURE_QUANTA.Q_RES(CHIPS)':
 C_PATH='@s9s_mb_2u_lib.s9s_mb_2u(sch_1):page325_i34@pure_quanta.q_res(chips)',
 P_PATH='@s9s_mb_2u_lib.s9s_mb_2u(sch_1):page303_i34@pure_quanta.q_res(chips)',
 PATH='I34',
 DRAWING='@S9S_MB_2U_LIB.S9S_MB_2U(SCH_1):PAGE325',
 PHYS_PAGE='303',
 XY='(-125,950)',
 ROT='0',
 VER='2',
 PACK_TYPE='0402LF',
 LOCATION='PR3990',
 CDS_LIB='pure_quanta',
 CDS_PART_NAME='Q_RES_0402LF-2K,0.1%,1/16W,CHIA',
 WATTAGE='1/16W',
 TOLERANCE='0.1%',
 MATERIAL='CHIP',
 ROOM='HSC1_BOM1',
 VALUE='2K',
 PRIM_FILE='./archive_libs/logical/q_res/chips/chips.prt';

PART_NAME
 PR3991 'Q_RES_0402LF-2K,0.1%,1/16W,CHIA':
 ROOM='HSC1_BOM1';

SECTION_NUMBER 1
 '@S9S_MB_2U_LIB.S9S_MB_2U(SCH_1):PAGE325_I13@PURE_QUANTA.Q_RES(CHIPS)':
 C_PATH='@s9s_mb_2u_lib.s9s_mb_2u(sch_1):page325_i13@pure_quanta.q_res(chips)',
 P_PATH='@s9s_mb_2u_lib.s9s_mb_2u(sch_1):page303_i13@pure_quanta.q_res(chips)',
 PATH='I13',
 DRAWING='@S9S_MB_2U_LIB.S9S_MB_2U(SCH_1):PAGE325',
 PHYS_PAGE='303',
 XY='(-125,-1825)',
 ROT='0',
 VER='2',
 PACK_TYPE='0402LF',
 LOCATION='PR3991',
 CDS_LIB='pure_quanta',
 CDS_PART_NAME='Q_RES_0402LF-2K,0.1%,1/16W,CHIA',
 WATTAGE='1/16W',
 TOLERANCE='0.1%',
 MATERIAL='CHIP',
 ROOM='HSC1_BOM1',
 VALUE='2K',
 PRIM_FILE='./archive_libs/logical/q_res/chips/chips.prt';

PART_NAME
 PR3992 'Q_RES_0402LF-0,5%,1/16W,CHIP,CA':
 ROOM='HSC1_BOM1';

SECTION_NUMBER 1
 '@S9S_MB_2U_LIB.S9S_MB_2U(SCH_1):PAGE325_I50@PURE_QUANTA.Q_RES(CHIPS)':
 C_PATH='@s9s_mb_2u_lib.s9s_mb_2u(sch_1):page325_i50@pure_quanta.q_res(chips)',
 P_PATH='@s9s_mb_2u_lib.s9s_mb_2u(sch_1):page303_i50@pure_quanta.q_res(chips)',
 PATH='I50',
 DRAWING='@S9S_MB_2U_LIB.S9S_MB_2U(SCH_1):PAGE325',
 PHYS_PAGE='303',
 XY='(2325,1700)',
 ROT='0',
 VER='1',
 PACK_TYPE='0402LF',
 LOCATION='PR3992',
 CDS_LIB='pure_quanta',
 CDS_PART_NAME='Q_RES_0402LF-0,5%,1/16W,CHIP,CA',
 WATTAGE='1/16W',
 TOLERANCE='5%',
 MATERIAL='CHIP',
 ROOM='HSC1_BOM1',
 VALUE='0',
 PRIM_FILE='./archive_libs/logical/q_res/chips/chips.prt';

PART_NAME
 PR3993 'Q_RES_0402LF-0,5%,1/16W,CHIP,CA':
 ROOM='HSC1_BOM1';

SECTION_NUMBER 1
 '@S9S_MB_2U_LIB.S9S_MB_2U(SCH_1):PAGE325_I49@PURE_QUANTA.Q_RES(CHIPS)':
 C_PATH='@s9s_mb_2u_lib.s9s_mb_2u(sch_1):page325_i49@pure_quanta.q_res(chips)',
 P_PATH='@s9s_mb_2u_lib.s9s_mb_2u(sch_1):page303_i49@pure_quanta.q_res(chips)',
 PATH='I49',
 DRAWING='@S9S_MB_2U_LIB.S9S_MB_2U(SCH_1):PAGE325',
 PHYS_PAGE='303',
 XY='(2325,1525)',
 ROT='0',
 VER='1',
 PACK_TYPE='0402LF',
 LOCATION='PR3993',
 CDS_LIB='pure_quanta',
 CDS_PART_NAME='Q_RES_0402LF-0,5%,1/16W,CHIP,CA',
 WATTAGE='1/16W',
 TOLERANCE='5%',
 MATERIAL='CHIP',
 ROOM='HSC1_BOM1',
 VALUE='0',
 PRIM_FILE='./archive_libs/logical/q_res/chips/chips.prt';

PART_NAME
 PR3994 'Q_RES_0402LF-0,5%,1/16W,CHIP,CA':
 ROOM='HSC1_BOM1';

SECTION_NUMBER 1
 '@S9S_MB_2U_LIB.S9S_MB_2U(SCH_1):PAGE325_I40@PURE_QUANTA.Q_RES(CHIPS)':
 C_PATH='@s9s_mb_2u_lib.s9s_mb_2u(sch_1):page325_i40@pure_quanta.q_res(chips)',
 P_PATH='@s9s_mb_2u_lib.s9s_mb_2u(sch_1):page303_i40@pure_quanta.q_res(chips)',
 PATH='I40',
 DRAWING='@S9S_MB_2U_LIB.S9S_MB_2U(SCH_1):PAGE325',
 PHYS_PAGE='303',
 XY='(2325,-1075)',
 ROT='0',
 VER='1',
 PACK_TYPE='0402LF',
 LOCATION='PR3994',
 CDS_LIB='pure_quanta',
 CDS_PART_NAME='Q_RES_0402LF-0,5%,1/16W,CHIP,CA',
 WATTAGE='1/16W',
 TOLERANCE='5%',
 MATERIAL='CHIP',
 ROOM='HSC1_BOM1',
 VALUE='0',
 PRIM_FILE='./archive_libs/logical/q_res/chips/chips.prt';

PART_NAME
 PR3995 'Q_RES_0402LF-0,5%,1/16W,CHIP,CA':
 ROOM='HSC1_BOM1';

SECTION_NUMBER 1
 '@S9S_MB_2U_LIB.S9S_MB_2U(SCH_1):PAGE325_I39@PURE_QUANTA.Q_RES(CHIPS)':
 C_PATH='@s9s_mb_2u_lib.s9s_mb_2u(sch_1):page325_i39@pure_quanta.q_res(chips)',
 P_PATH='@s9s_mb_2u_lib.s9s_mb_2u(sch_1):page303_i39@pure_quanta.q_res(chips)',
 PATH='I39',
 DRAWING='@S9S_MB_2U_LIB.S9S_MB_2U(SCH_1):PAGE325',
 PHYS_PAGE='303',
 XY='(2325,-1250)',
 ROT='0',
 VER='1',
 PACK_TYPE='0402LF',
 LOCATION='PR3995',
 CDS_LIB='pure_quanta',
 CDS_PART_NAME='Q_RES_0402LF-0,5%,1/16W,CHIP,CA',
 WATTAGE='1/16W',
 TOLERANCE='5%',
 MATERIAL='CHIP',
 ROOM='HSC1_BOM1',
 VALUE='0',
 PRIM_FILE='./archive_libs/logical/q_res/chips/chips.prt';

PART_NAME
 PR3999 'Q_RES_0402LF-24.3K,1%,1/16W,CHA':
 ROOM='SCM_P12V_BOM2';

SECTION_NUMBER 1
 '@S9S_MB_2U_LIB.S9S_MB_2U(SCH_1):PAGE229_I11@PURE_QUANTA.Q_RES(CHIPS)':
 C_PATH='@s9s_mb_2u_lib.s9s_mb_2u(sch_1):page229_i11@pure_quanta.q_res(chips)',
 P_PATH='@s9s_mb_2u_lib.s9s_mb_2u(sch_1):page242_i11@pure_quanta.q_res(chips)',
 PATH='I11',
 DRAWING='@S9S_MB_2U_LIB.S9S_MB_2U(SCH_1):PAGE229',
 PHYS_PAGE='242',
 XY='(-675,-1825)',
 ROT='0',
 VER='2',
 PACK_TYPE='0402LF',
 LOCATION='PR3999',
 CDS_LIB='pure_quanta',
 CDS_PART_NAME='Q_RES_0402LF-24.3K,1%,1/16W,CHA',
 WATTAGE='1/16W',
 TOLERANCE='1%',
 MATERIAL='CHIP',
 ROOM='SCM_P12V_BOM2',
 VALUE='24.3K',
 PRIM_FILE='./archive_libs/logical/q_res/chips/chips.prt';

PART_NAME
 PR4000 'Q_RES_0402LF-160K,1%,1/16W,EMPA':
 ROOM='SCM_P12V_BOM1';

SECTION_NUMBER 1
 '@S9S_MB_2U_LIB.S9S_MB_2U(SCH_1):PAGE229_I67@PURE_QUANTA.Q_RES(CHIPS)':
 C_PATH='@s9s_mb_2u_lib.s9s_mb_2u(sch_1):page229_i67@pure_quanta.q_res(chips)',
 P_PATH='@s9s_mb_2u_lib.s9s_mb_2u(sch_1):page242_i67@pure_quanta.q_res(chips)',
 PATH='I67',
 DRAWING='@S9S_MB_2U_LIB.S9S_MB_2U(SCH_1):PAGE229',
 PHYS_PAGE='242',
 XY='(75,1925)',
 ROT='0',
 VER='2',
 PACK_TYPE='0402LF',
 LOCATION='PR4000',
 CDS_LIB='pure_quanta',
 CDS_PART_NAME='Q_RES_0402LF-160K,1%,1/16W,EMPA',
 WATTAGE='1/16W',
 TOLERANCE='1%',
 MATERIAL='EMPTY',
 ROOM='SCM_P12V_BOM1',
 VALUE='160K',
 PRIM_FILE='./archive_libs/logical/q_res/chips/chips.prt';

PART_NAME
 PR4001 'Q_RES_0402LF-6.8K,1%,1/16W,EMPA':
 ROOM='SCM_P12V_BOM1';

SECTION_NUMBER 1
 '@S9S_MB_2U_LIB.S9S_MB_2U(SCH_1):PAGE229_I64@PURE_QUANTA.Q_RES(CHIPS)':
 C_PATH='@s9s_mb_2u_lib.s9s_mb_2u(sch_1):page229_i64@pure_quanta.q_res(chips)',
 P_PATH='@s9s_mb_2u_lib.s9s_mb_2u(sch_1):page242_i64@pure_quanta.q_res(chips)',
 PATH='I64',
 DRAWING='@S9S_MB_2U_LIB.S9S_MB_2U(SCH_1):PAGE229',
 PHYS_PAGE='242',
 XY='(75,1250)',
 ROT='0',
 VER='2',
 PACK_TYPE='0402LF',
 LOCATION='PR4001',
 CDS_LIB='pure_quanta',
 CDS_PART_NAME='Q_RES_0402LF-6.8K,1%,1/16W,EMPA',
 WATTAGE='1/16W',
 TOLERANCE='1%',
 MATERIAL='EMPTY',
 ROOM='SCM_P12V_BOM1',
 VALUE='6.8K',
 PRIM_FILE='./archive_libs/logical/q_res/chips/chips.prt';

PART_NAME
 PR4002 'Q_RES_0402LF-15K,1%,1/16W,EMPTA':
 ROOM='SCM_P12V_BOM1';

SECTION_NUMBER 1
 '@S9S_MB_2U_LIB.S9S_MB_2U(SCH_1):PAGE229_I61@PURE_QUANTA.Q_RES(CHIPS)':
 C_PATH='@s9s_mb_2u_lib.s9s_mb_2u(sch_1):page229_i61@pure_quanta.q_res(chips)',
 P_PATH='@s9s_mb_2u_lib.s9s_mb_2u(sch_1):page242_i61@pure_quanta.q_res(chips)',
 PATH='I61',
 DRAWING='@S9S_MB_2U_LIB.S9S_MB_2U(SCH_1):PAGE229',
 PHYS_PAGE='242',
 XY='(75,975)',
 ROT='0',
 VER='2',
 PACK_TYPE='0402LF',
 LOCATION='PR4002',
 CDS_LIB='pure_quanta',
 CDS_PART_NAME='Q_RES_0402LF-15K,1%,1/16W,EMPTA',
 WATTAGE='1/16W',
 TOLERANCE='1%',
 MATERIAL='EMPTY',
 ROOM='SCM_P12V_BOM1',
 VALUE='15K',
 PRIM_FILE='./archive_libs/logical/q_res/chips/chips.prt';

PART_NAME
 PR4003 'Q_RES_0402LF-10,1%,1/16W,EMPTYA':
 ROOM='SCM_P12V_BOM1';

SECTION_NUMBER 1
 '@S9S_MB_2U_LIB.S9S_MB_2U(SCH_1):PAGE229_I70@PURE_QUANTA.Q_RES(CHIPS)':
 C_PATH='@s9s_mb_2u_lib.s9s_mb_2u(sch_1):page229_i70@pure_quanta.q_res(chips)',
 P_PATH='@s9s_mb_2u_lib.s9s_mb_2u(sch_1):page242_i70@pure_quanta.q_res(chips)',
 PATH='I70',
 DRAWING='@S9S_MB_2U_LIB.S9S_MB_2U(SCH_1):PAGE229',
 PHYS_PAGE='242',
 XY='(400,2225)',
 ROT='0',
 VER='2',
 PACK_TYPE='0402LF',
 LOCATION='PR4003',
 CDS_LIB='pure_quanta',
 CDS_PART_NAME='Q_RES_0402LF-10,1%,1/16W,EMPTYA',
 WATTAGE='1/16W',
 TOLERANCE='1%',
 MATERIAL='EMPTY',
 ROOM='SCM_P12V_BOM1',
 VALUE='10',
 PRIM_FILE='./archive_libs/logical/q_res/chips/chips.prt';

PART_NAME
 PR4004 'Q_RES_0402LF-17.8K,1%,1/16W,EMA':
 ROOM='SCM_P12V_BOM1';

SECTION_NUMBER 1
 '@S9S_MB_2U_LIB.S9S_MB_2U(SCH_1):PAGE229_I63@PURE_QUANTA.Q_RES(CHIPS)':
 C_PATH='@s9s_mb_2u_lib.s9s_mb_2u(sch_1):page229_i63@pure_quanta.q_res(chips)',
 P_PATH='@s9s_mb_2u_lib.s9s_mb_2u(sch_1):page242_i63@pure_quanta.q_res(chips)',
 PATH='I63',
 DRAWING='@S9S_MB_2U_LIB.S9S_MB_2U(SCH_1):PAGE229',
 PHYS_PAGE='242',
 XY='(925,975)',
 ROT='0',
 VER='2',
 PACK_TYPE='0402LF',
 LOCATION='PR4004',
 CDS_LIB='pure_quanta',
 CDS_PART_NAME='Q_RES_0402LF-17.8K,1%,1/16W,EMA',
 WATTAGE='1/16W',
 TOLERANCE='1%',
 MATERIAL='EMPTY',
 ROOM='SCM_P12V_BOM1',
 VALUE='17.8K',
 PRIM_FILE='./archive_libs/logical/q_res/chips/chips.prt';

PART_NAME
 PR4005 'Q_RES_0402LF-30.1K,1%,1/16W,CHA':
 ROOM='SCM_P12V_BOM2';

SECTION_NUMBER 1
 '@S9S_MB_2U_LIB.S9S_MB_2U(SCH_1):PAGE229_I34@PURE_QUANTA.Q_RES(CHIPS)':
 C_PATH='@s9s_mb_2u_lib.s9s_mb_2u(sch_1):page229_i34@pure_quanta.q_res(chips)',
 P_PATH='@s9s_mb_2u_lib.s9s_mb_2u(sch_1):page242_i34@pure_quanta.q_res(chips)',
 PATH='I34',
 DRAWING='@S9S_MB_2U_LIB.S9S_MB_2U(SCH_1):PAGE229',
 PHYS_PAGE='242',
 XY='(1650,-2125)',
 ROT='0',
 VER='2',
 PACK_TYPE='0402LF',
 LOCATION='PR4005',
 CDS_LIB='pure_quanta',
 CDS_PART_NAME='Q_RES_0402LF-30.1K,1%,1/16W,CHA',
 WATTAGE='1/16W',
 TOLERANCE='1%',
 MATERIAL='CHIP',
 ROOM='SCM_P12V_BOM2',
 VALUE='30.1K',
 PRIM_FILE='./archive_libs/logical/q_res/chips/chips.prt';

PART_NAME
 PR4006 'Q_RES_0402LF-100,1%,1/16W,EMPTA':;

SECTION_NUMBER 1
 '@S9S_MB_2U_LIB.S9S_MB_2U(SCH_1):PAGE229_I39@PURE_QUANTA.Q_RES(CHIPS)':
 C_PATH='@s9s_mb_2u_lib.s9s_mb_2u(sch_1):page229_i39@pure_quanta.q_res(chips)',
 P_PATH='@s9s_mb_2u_lib.s9s_mb_2u(sch_1):page242_i39@pure_quanta.q_res(chips)',
 PATH='I39',
 DRAWING='@S9S_MB_2U_LIB.S9S_MB_2U(SCH_1):PAGE229',
 PHYS_PAGE='242',
 XY='(2025,-1275)',
 ROT='0',
 VER='2',
 PACK_TYPE='0402LF',
 LOCATION='PR4006',
 CDS_LIB='pure_quanta',
 CDS_PART_NAME='Q_RES_0402LF-100,1%,1/16W,EMPTA',
 WATTAGE='1/16W',
 TOLERANCE='1%',
 MATERIAL='EMPTY',
 VALUE='100',
 PRIM_FILE='./archive_libs/logical/q_res/chips/chips.prt';

PART_NAME
 PR4007 'Q_RES_0402LF-10K,1%,1/16W,CHIPA':
 ROOM='SCM_P12V_BOM2';

SECTION_NUMBER 1
 '@S9S_MB_2U_LIB.S9S_MB_2U(SCH_1):PAGE229_I48@PURE_QUANTA.Q_RES(CHIPS)':
 C_PATH='@s9s_mb_2u_lib.s9s_mb_2u(sch_1):page229_i48@pure_quanta.q_res(chips)',
 P_PATH='@s9s_mb_2u_lib.s9s_mb_2u(sch_1):page242_i48@pure_quanta.q_res(chips)',
 PATH='I48',
 DRAWING='@S9S_MB_2U_LIB.S9S_MB_2U(SCH_1):PAGE229',
 PHYS_PAGE='242',
 XY='(2475,-1750)',
 ROT='0',
 VER='1',
 PACK_TYPE='0402LF',
 LOCATION='PR4007',
 CDS_LIB='pure_quanta',
 CDS_PART_NAME='Q_RES_0402LF-10K,1%,1/16W,CHIPA',
 WATTAGE='1/16W',
 TOLERANCE='1%',
 MATERIAL='CHIP',
 ROOM='SCM_P12V_BOM2',
 VALUE='10K',
 PRIM_FILE='./archive_libs/logical/q_res/chips/chips.prt';

PART_NAME
 PR4008 'Q_RES_0402LF-1.33K,1%,1/16W,EMA':
 ROOM='SCM_P12V_BOM1';

SECTION_NUMBER 1
 '@S9S_MB_2U_LIB.S9S_MB_2U(SCH_1):PAGE229_I72@PURE_QUANTA.Q_RES(CHIPS)':
 C_PATH='@s9s_mb_2u_lib.s9s_mb_2u(sch_1):page229_i72@pure_quanta.q_res(chips)',
 P_PATH='@s9s_mb_2u_lib.s9s_mb_2u(sch_1):page242_i72@pure_quanta.q_res(chips)',
 PATH='I72',
 DRAWING='@S9S_MB_2U_LIB.S9S_MB_2U(SCH_1):PAGE229',
 PHYS_PAGE='242',
 XY='(2525,1125)',
 ROT='0',
 VER='2',
 PACK_TYPE='0402LF',
 LOCATION='PR4008',
 CDS_LIB='pure_quanta',
 CDS_PART_NAME='Q_RES_0402LF-1.33K,1%,1/16W,EMA',
 WATTAGE='1/16W',
 TOLERANCE='1%',
 MATERIAL='EMPTY',
 ROOM='SCM_P12V_BOM1',
 VALUE='1.33K',
 PRIM_FILE='./archive_libs/logical/q_res/chips/chips.prt';

PART_NAME
 PR4009 'Q_RES_0402LF-71.5K,1%,1/16W,EMA':;

SECTION_NUMBER 1
 '@S9S_MB_2U_LIB.S9S_MB_2U(SCH_1):PAGE229_I51@PURE_QUANTA.Q_RES(CHIPS)':
 C_PATH='@s9s_mb_2u_lib.s9s_mb_2u(sch_1):page229_i51@pure_quanta.q_res(chips)',
 P_PATH='@s9s_mb_2u_lib.s9s_mb_2u(sch_1):page242_i51@pure_quanta.q_res(chips)',
 PATH='I51',
 DRAWING='@S9S_MB_2U_LIB.S9S_MB_2U(SCH_1):PAGE229',
 PHYS_PAGE='242',
 XY='(2625,-1275)',
 ROT='0',
 VER='2',
 PACK_TYPE='0402LF',
 LOCATION='PR4009',
 CDS_LIB='pure_quanta',
 CDS_PART_NAME='Q_RES_0402LF-71.5K,1%,1/16W,EMA',
 WATTAGE='1/16W',
 TOLERANCE='1%',
 MATERIAL='EMPTY',
 VALUE='71.5K',
 PRIM_FILE='./archive_libs/logical/q_res/chips/chips.prt';

PART_NAME
 PR4010 'Q_RES_0402LF-120K,1%,1/16W,CHIA':
 ROOM='SCM_P12V_BOM2';

SECTION_NUMBER 1
 '@S9S_MB_2U_LIB.S9S_MB_2U(SCH_1):PAGE229_I52@PURE_QUANTA.Q_RES(CHIPS)':
 C_PATH='@s9s_mb_2u_lib.s9s_mb_2u(sch_1):page229_i52@pure_quanta.q_res(chips)',
 P_PATH='@s9s_mb_2u_lib.s9s_mb_2u(sch_1):page242_i52@pure_quanta.q_res(chips)',
 PATH='I52',
 DRAWING='@S9S_MB_2U_LIB.S9S_MB_2U(SCH_1):PAGE229',
 PHYS_PAGE='242',
 XY='(3025,-1350)',
 ROT='0',
 VER='2',
 PACK_TYPE='0402LF',
 LOCATION='PR4010',
 CDS_LIB='pure_quanta',
 CDS_PART_NAME='Q_RES_0402LF-120K,1%,1/16W,CHIA',
 WATTAGE='1/16W',
 TOLERANCE='1%',
 MATERIAL='CHIP',
 ROOM='SCM_P12V_BOM2',
 VALUE='120K',
 PRIM_FILE='./archive_libs/logical/q_res/chips/chips.prt';

PART_NAME
 PR4011 'Q_RES_0402LF-10K,1%,1/16W,CHIPA':
 ROOM='SCM_P12V_BOM2';

SECTION_NUMBER 1
 '@S9S_MB_2U_LIB.S9S_MB_2U(SCH_1):PAGE229_I50@PURE_QUANTA.Q_RES(CHIPS)':
 C_PATH='@s9s_mb_2u_lib.s9s_mb_2u(sch_1):page229_i50@pure_quanta.q_res(chips)',
 P_PATH='@s9s_mb_2u_lib.s9s_mb_2u(sch_1):page242_i50@pure_quanta.q_res(chips)',
 PATH='I50',
 DRAWING='@S9S_MB_2U_LIB.S9S_MB_2U(SCH_1):PAGE229',
 PHYS_PAGE='242',
 XY='(3025,-1775)',
 ROT='0',
 VER='2',
 PACK_TYPE='0402LF',
 LOCATION='PR4011',
 CDS_LIB='pure_quanta',
 CDS_PART_NAME='Q_RES_0402LF-10K,1%,1/16W,CHIPA',
 WATTAGE='1/16W',
 TOLERANCE='1%',
 MATERIAL='CHIP',
 ROOM='SCM_P12V_BOM2',
 VALUE='10K',
 PRIM_FILE='./archive_libs/logical/q_res/chips/chips.prt';

PART_NAME
 PR4012 'Q_RES_0402LF-0,5%,1/16W,EMPTY,A':
 ROOM='SCM_P12V_BOM1';

SECTION_NUMBER 1
 '@S9S_MB_2U_LIB.S9S_MB_2U(SCH_1):PAGE229_I74@PURE_QUANTA.Q_RES(CHIPS)':
 C_PATH='@s9s_mb_2u_lib.s9s_mb_2u(sch_1):page229_i74@pure_quanta.q_res(chips)',
 P_PATH='@s9s_mb_2u_lib.s9s_mb_2u(sch_1):page242_i74@pure_quanta.q_res(chips)',
 PATH='I74',
 DRAWING='@S9S_MB_2U_LIB.S9S_MB_2U(SCH_1):PAGE229',
 PHYS_PAGE='242',
 XY='(3150,1500)',
 ROT='0',
 VER='1',
 PACK_TYPE='0402LF',
 LOCATION='PR4012',
 CDS_LIB='pure_quanta',
 CDS_PART_NAME='Q_RES_0402LF-0,5%,1/16W,EMPTY,A',
 WATTAGE='1/16W',
 TOLERANCE='5%',
 MATERIAL='EMPTY',
 ROOM='SCM_P12V_BOM1',
 VALUE='0',
 PRIM_FILE='./archive_libs/logical/q_res/chips/chips.prt';

PART_NAME
 PR4014 'Q_RES_0603LF-49.9,1%,1/10W,CHIA':
 ROOM='SCM_P12V_BOM2';

SECTION_NUMBER 1
 '@S9S_MB_2U_LIB.S9S_MB_2U(SCH_1):PAGE229_I54@PURE_QUANTA.Q_RES(CHIPS)':
 C_PATH='@s9s_mb_2u_lib.s9s_mb_2u(sch_1):page229_i54@pure_quanta.q_res(chips)',
 P_PATH='@s9s_mb_2u_lib.s9s_mb_2u(sch_1):page242_i54@pure_quanta.q_res(chips)',
 PATH='I54',
 DRAWING='@S9S_MB_2U_LIB.S9S_MB_2U(SCH_1):PAGE229',
 PHYS_PAGE='242',
 XY='(3550,-1350)',
 ROT='0',
 VER='2',
 PACK_TYPE='0603LF',
 LOCATION='PR4014',
 CDS_LIB='pure_quanta',
 CDS_PART_NAME='Q_RES_0603LF-49.9,1%,1/10W,CHIA',
 WATTAGE='1/10W',
 TOLERANCE='1%',
 MATERIAL='CHIP',
 ROOM='SCM_P12V_BOM2',
 VALUE='49.9',
 PRIM_FILE='./archive_libs/logical/q_res/chips/chips.prt';

PART_NAME
 PR4217 'Q_RES_0402LF-0,5%,1/16W,EMPTY,A':;

SECTION_NUMBER 1
 '@S9S_MB_2U_LIB.S9S_MB_2U(SCH_1):PAGE252_I74@PURE_QUANTA.Q_RES(CHIPS)':
 C_PATH='@s9s_mb_2u_lib.s9s_mb_2u(sch_1):page252_i74@pure_quanta.q_res(chips)',
 P_PATH='@s9s_mb_2u_lib.s9s_mb_2u(sch_1):page266_i74@pure_quanta.q_res(chips)',
 PATH='I74',
 DRAWING='@S9S_MB_2U_LIB.S9S_MB_2U(SCH_1):PAGE252',
 PHYS_PAGE='266',
 XY='(-1725,2975)',
 ROT='0',
 VER='1',
 PACK_TYPE='0402LF',
 LOCATION='PR4217',
 CDS_LIB='pure_quanta',
 CDS_PART_NAME='Q_RES_0402LF-0,5%,1/16W,EMPTY,A',
 WATTAGE='1/16W',
 TOLERANCE='5%',
 MATERIAL='EMPTY',
 VALUE='0',
 PRIM_FILE='./archive_libs/logical/q_res/chips/chips.prt';

PART_NAME
 PR4218 'Q_RES_0402LF-0,5%,1/16W,EMPTY,A':;

SECTION_NUMBER 1
 '@S9S_MB_2U_LIB.S9S_MB_2U(SCH_1):PAGE252_I73@PURE_QUANTA.Q_RES(CHIPS)':
 C_PATH='@s9s_mb_2u_lib.s9s_mb_2u(sch_1):page252_i73@pure_quanta.q_res(chips)',
 P_PATH='@s9s_mb_2u_lib.s9s_mb_2u(sch_1):page266_i73@pure_quanta.q_res(chips)',
 PATH='I73',
 DRAWING='@S9S_MB_2U_LIB.S9S_MB_2U(SCH_1):PAGE252',
 PHYS_PAGE='266',
 XY='(-1725,2675)',
 ROT='0',
 VER='1',
 PACK_TYPE='0402LF',
 LOCATION='PR4218',
 CDS_LIB='pure_quanta',
 CDS_PART_NAME='Q_RES_0402LF-0,5%,1/16W,EMPTY,A',
 WATTAGE='1/16W',
 TOLERANCE='5%',
 MATERIAL='EMPTY',
 VALUE='0',
 PRIM_FILE='./archive_libs/logical/q_res/chips/chips.prt';

PART_NAME
 PR4219 'Q_RES_0402LF-499,1%,1/16W,CHIPA':;

SECTION_NUMBER 1
 '@S9S_MB_2U_LIB.S9S_MB_2U(SCH_1):PAGE253_I59@PURE_QUANTA.Q_RES(CHIPS)':
 C_PATH='@s9s_mb_2u_lib.s9s_mb_2u(sch_1):page253_i59@pure_quanta.q_res(chips)',
 P_PATH='@s9s_mb_2u_lib.s9s_mb_2u(sch_1):page267_i59@pure_quanta.q_res(chips)',
 PATH='I59',
 DRAWING='@S9S_MB_2U_LIB.S9S_MB_2U(SCH_1):PAGE253',
 BOM_COST='VR_PCH',
 PHYS_PAGE='267',
 XY='(3725,-2450)',
 ROT='0',
 VER='2',
 PACK_TYPE='0402LF',
 LOCATION='PR4219',
 CDS_LIB='pure_quanta',
 CDS_PART_NAME='Q_RES_0402LF-499,1%,1/16W,CHIPA',
 WATTAGE='1/16W',
 TOLERANCE='1%',
 MATERIAL='CHIP',
 VALUE='499',
 PRIM_FILE='./archive_libs/logical/q_res/chips/chips.prt';

PART_NAME
 PR4220 'Q_RES_0402LF-0,5%,1/16W,CHIP,CA':;

SECTION_NUMBER 1
 '@S9S_MB_2U_LIB.S9S_MB_2U(SCH_1):PAGE260_I19@PURE_QUANTA.Q_RES(CHIPS)':
 C_PATH='@s9s_mb_2u_lib.s9s_mb_2u(sch_1):page260_i19@pure_quanta.q_res(chips)',
 P_PATH='@s9s_mb_2u_lib.s9s_mb_2u(sch_1):page274_i19@pure_quanta.q_res(chips)',
 PATH='I19',
 DRAWING='@S9S_MB_2U_LIB.S9S_MB_2U(SCH_1):PAGE260',
 PHYS_PAGE='274',
 XY='(-8825,1925)',
 ROT='0',
 VER='2',
 PACK_TYPE='0402LF',
 LOCATION='PR4220',
 CDS_LIB='pure_quanta',
 CDS_PART_NAME='Q_RES_0402LF-0,5%,1/16W,CHIP,CA',
 WATTAGE='1/16W',
 TOLERANCE='5%',
 MATERIAL='CHIP',
 VALUE='0',
 PRIM_FILE='./archive_libs/logical/q_res/chips/chips.prt';

PART_NAME
 PR4221 'Q_RES_0402LF-0,5%,1/16W,CHIP,CA':;

SECTION_NUMBER 1
 '@S9S_MB_2U_LIB.S9S_MB_2U(SCH_1):PAGE260_I87@PURE_QUANTA.Q_RES(CHIPS)':
 C_PATH='@s9s_mb_2u_lib.s9s_mb_2u(sch_1):page260_i87@pure_quanta.q_res(chips)',
 P_PATH='@s9s_mb_2u_lib.s9s_mb_2u(sch_1):page274_i87@pure_quanta.q_res(chips)',
 PATH='I87',
 DRAWING='@S9S_MB_2U_LIB.S9S_MB_2U(SCH_1):PAGE260',
 PHYS_PAGE='274',
 XY='(-5025,5575)',
 ROT='0',
 VER='1',
 PACK_TYPE='0402LF',
 LOCATION='PR4221',
 CDS_LIB='pure_quanta',
 CDS_PART_NAME='Q_RES_0402LF-0,5%,1/16W,CHIP,CA',
 WATTAGE='1/16W',
 TOLERANCE='5%',
 MATERIAL='CHIP',
 VALUE='0',
 PRIM_FILE='./archive_libs/logical/q_res/chips/chips.prt';

PART_NAME
 PR4222 'Q_RES_0402LF-0,5%,1/16W,CHIP,CA':;

SECTION_NUMBER 1
 '@S9S_MB_2U_LIB.S9S_MB_2U(SCH_1):PAGE260_I86@PURE_QUANTA.Q_RES(CHIPS)':
 C_PATH='@s9s_mb_2u_lib.s9s_mb_2u(sch_1):page260_i86@pure_quanta.q_res(chips)',
 P_PATH='@s9s_mb_2u_lib.s9s_mb_2u(sch_1):page274_i86@pure_quanta.q_res(chips)',
 PATH='I86',
 DRAWING='@S9S_MB_2U_LIB.S9S_MB_2U(SCH_1):PAGE260',
 PHYS_PAGE='274',
 XY='(-5025,5125)',
 ROT='0',
 VER='1',
 PACK_TYPE='0402LF',
 LOCATION='PR4222',
 CDS_LIB='pure_quanta',
 CDS_PART_NAME='Q_RES_0402LF-0,5%,1/16W,CHIP,CA',
 WATTAGE='1/16W',
 TOLERANCE='5%',
 MATERIAL='CHIP',
 VALUE='0',
 PRIM_FILE='./archive_libs/logical/q_res/chips/chips.prt';

PART_NAME
 PR4223 'Q_RES_0402LF-0,5%,1/16W,CHIP,CA':;

SECTION_NUMBER 1
 '@S9S_MB_2U_LIB.S9S_MB_2U(SCH_1):PAGE260_I85@PURE_QUANTA.Q_RES(CHIPS)':
 C_PATH='@s9s_mb_2u_lib.s9s_mb_2u(sch_1):page260_i85@pure_quanta.q_res(chips)',
 P_PATH='@s9s_mb_2u_lib.s9s_mb_2u(sch_1):page274_i85@pure_quanta.q_res(chips)',
 PATH='I85',
 DRAWING='@S9S_MB_2U_LIB.S9S_MB_2U(SCH_1):PAGE260',
 PHYS_PAGE='274',
 XY='(-5025,4675)',
 ROT='0',
 VER='1',
 PACK_TYPE='0402LF',
 LOCATION='PR4223',
 CDS_LIB='pure_quanta',
 CDS_PART_NAME='Q_RES_0402LF-0,5%,1/16W,CHIP,CA',
 WATTAGE='1/16W',
 TOLERANCE='5%',
 MATERIAL='CHIP',
 VALUE='0',
 PRIM_FILE='./archive_libs/logical/q_res/chips/chips.prt';

PART_NAME
 PR4224 'Q_RES_0402LF-0,5%,1/16W,CHIP,CA':;

SECTION_NUMBER 1
 '@S9S_MB_2U_LIB.S9S_MB_2U(SCH_1):PAGE260_I84@PURE_QUANTA.Q_RES(CHIPS)':
 C_PATH='@s9s_mb_2u_lib.s9s_mb_2u(sch_1):page260_i84@pure_quanta.q_res(chips)',
 P_PATH='@s9s_mb_2u_lib.s9s_mb_2u(sch_1):page274_i84@pure_quanta.q_res(chips)',
 PATH='I84',
 DRAWING='@S9S_MB_2U_LIB.S9S_MB_2U(SCH_1):PAGE260',
 PHYS_PAGE='274',
 XY='(-5025,4225)',
 ROT='0',
 VER='1',
 PACK_TYPE='0402LF',
 LOCATION='PR4224',
 CDS_LIB='pure_quanta',
 CDS_PART_NAME='Q_RES_0402LF-0,5%,1/16W,CHIP,CA',
 WATTAGE='1/16W',
 TOLERANCE='5%',
 MATERIAL='CHIP',
 VALUE='0',
 PRIM_FILE='./archive_libs/logical/q_res/chips/chips.prt';

PART_NAME
 PR4225 'Q_RES_0402LF-0,5%,1/16W,CHIP,CA':;

SECTION_NUMBER 1
 '@S9S_MB_2U_LIB.S9S_MB_2U(SCH_1):PAGE260_I76@PURE_QUANTA.Q_RES(CHIPS)':
 C_PATH='@s9s_mb_2u_lib.s9s_mb_2u(sch_1):page260_i76@pure_quanta.q_res(chips)',
 P_PATH='@s9s_mb_2u_lib.s9s_mb_2u(sch_1):page274_i76@pure_quanta.q_res(chips)',
 PATH='I76',
 DRAWING='@S9S_MB_2U_LIB.S9S_MB_2U(SCH_1):PAGE260',
 PHYS_PAGE='274',
 XY='(-5000,3775)',
 ROT='0',
 VER='1',
 PACK_TYPE='0402LF',
 LOCATION='PR4225',
 CDS_LIB='pure_quanta',
 CDS_PART_NAME='Q_RES_0402LF-0,5%,1/16W,CHIP,CA',
 WATTAGE='1/16W',
 TOLERANCE='5%',
 MATERIAL='CHIP',
 VALUE='0',
 PRIM_FILE='./archive_libs/logical/q_res/chips/chips.prt';

PART_NAME
 PR4226 'Q_RES_0402LF-499,1%,1/16W,CHIPA':;

SECTION_NUMBER 1
 '@S9S_MB_2U_LIB.S9S_MB_2U(SCH_1):PAGE261_I63@PURE_QUANTA.Q_RES(CHIPS)':
 C_PATH='@s9s_mb_2u_lib.s9s_mb_2u(sch_1):page261_i63@pure_quanta.q_res(chips)',
 P_PATH='@s9s_mb_2u_lib.s9s_mb_2u(sch_1):page275_i63@pure_quanta.q_res(chips)',
 PATH='I63',
 DRAWING='@S9S_MB_2U_LIB.S9S_MB_2U(SCH_1):PAGE261',
 BOM_COST='VR_PCH',
 PHYS_PAGE='275',
 XY='(-4575,1775)',
 ROT='0',
 VER='2',
 PACK_TYPE='0402LF',
 LOCATION='PR4226',
 CDS_LIB='pure_quanta',
 CDS_PART_NAME='Q_RES_0402LF-499,1%,1/16W,CHIPA',
 WATTAGE='1/16W',
 TOLERANCE='1%',
 MATERIAL='CHIP',
 VALUE='499',
 PRIM_FILE='./archive_libs/logical/q_res/chips/chips.prt';

PART_NAME
 PR4227 'Q_RES_0402LF-0,5%,1/16W,EMPTY,A':;

SECTION_NUMBER 1
 '@S9S_MB_2U_LIB.S9S_MB_2U(SCH_1):PAGE262_I13@PURE_QUANTA.Q_RES(CHIPS)':
 C_PATH='@s9s_mb_2u_lib.s9s_mb_2u(sch_1):page262_i13@pure_quanta.q_res(chips)',
 P_PATH='@s9s_mb_2u_lib.s9s_mb_2u(sch_1):page276_i13@pure_quanta.q_res(chips)',
 PATH='I13',
 DRAWING='@S9S_MB_2U_LIB.S9S_MB_2U(SCH_1):PAGE262',
 PHYS_PAGE='276',
 XY='(-9075,3950)',
 ROT='0',
 VER='2',
 PACK_TYPE='0402LF',
 LOCATION='PR4227',
 CDS_LIB='pure_quanta',
 CDS_PART_NAME='Q_RES_0402LF-0,5%,1/16W,EMPTY,A',
 WATTAGE='1/16W',
 TOLERANCE='5%',
 MATERIAL='EMPTY',
 VALUE='0',
 PRIM_FILE='./archive_libs/logical/q_res/chips/chips.prt';

PART_NAME
 PR4228 'Q_RES_0402LF-0,5%,1/16W,EMPTY,A':;

SECTION_NUMBER 1
 '@S9S_MB_2U_LIB.S9S_MB_2U(SCH_1):PAGE262_I15@PURE_QUANTA.Q_RES(CHIPS)':
 C_PATH='@s9s_mb_2u_lib.s9s_mb_2u(sch_1):page262_i15@pure_quanta.q_res(chips)',
 P_PATH='@s9s_mb_2u_lib.s9s_mb_2u(sch_1):page276_i15@pure_quanta.q_res(chips)',
 PATH='I15',
 DRAWING='@S9S_MB_2U_LIB.S9S_MB_2U(SCH_1):PAGE262',
 PHYS_PAGE='276',
 XY='(-6725,3050)',
 ROT='0',
 VER='1',
 PACK_TYPE='0402LF',
 LOCATION='PR4228',
 CDS_LIB='pure_quanta',
 CDS_PART_NAME='Q_RES_0402LF-0,5%,1/16W,EMPTY,A',
 WATTAGE='1/16W',
 TOLERANCE='5%',
 MATERIAL='EMPTY',
 VALUE='0',
 PRIM_FILE='./archive_libs/logical/q_res/chips/chips.prt';

PART_NAME
 PR4229 'Q_RES_0402LF-499,1%,1/16W,CHIPA':;

SECTION_NUMBER 1
 '@S9S_MB_2U_LIB.S9S_MB_2U(SCH_1):PAGE262_I36@PURE_QUANTA.Q_RES(CHIPS)':
 C_PATH='@s9s_mb_2u_lib.s9s_mb_2u(sch_1):page262_i36@pure_quanta.q_res(chips)',
 P_PATH='@s9s_mb_2u_lib.s9s_mb_2u(sch_1):page276_i36@pure_quanta.q_res(chips)',
 PATH='I36',
 DRAWING='@S9S_MB_2U_LIB.S9S_MB_2U(SCH_1):PAGE262',
 BOM_COST='VR_PCH',
 PHYS_PAGE='276',
 XY='(-3050,3350)',
 ROT='0',
 VER='2',
 PACK_TYPE='0402LF',
 LOCATION='PR4229',
 CDS_LIB='pure_quanta',
 CDS_PART_NAME='Q_RES_0402LF-499,1%,1/16W,CHIPA',
 WATTAGE='1/16W',
 TOLERANCE='1%',
 MATERIAL='CHIP',
 VALUE='499',
 PRIM_FILE='./archive_libs/logical/q_res/chips/chips.prt';

PART_NAME
 PR4230 'Q_RES_0402LF-0,5%,1/16W,CHIP,CA':;

SECTION_NUMBER 1
 '@S9S_MB_2U_LIB.S9S_MB_2U(SCH_1):PAGE264_I74@PURE_QUANTA.Q_RES(CHIPS)':
 C_PATH='@s9s_mb_2u_lib.s9s_mb_2u(sch_1):page264_i74@pure_quanta.q_res(chips)',
 P_PATH='@s9s_mb_2u_lib.s9s_mb_2u(sch_1):page278_i74@pure_quanta.q_res(chips)',
 PATH='I74',
 DRAWING='@S9S_MB_2U_LIB.S9S_MB_2U(SCH_1):PAGE264',
 PHYS_PAGE='278',
 XY='(-5200,7400)',
 ROT='0',
 VER='1',
 PACK_TYPE='0402LF',
 LOCATION='PR4230',
 CDS_LIB='pure_quanta',
 CDS_PART_NAME='Q_RES_0402LF-0,5%,1/16W,CHIP,CA',
 WATTAGE='1/16W',
 TOLERANCE='5%',
 MATERIAL='CHIP',
 VALUE='0',
 PRIM_FILE='./archive_libs/logical/q_res/chips/chips.prt';

PART_NAME
 PR4231 'Q_RES_0402LF-0,5%,1/16W,CHIP,CA':;

SECTION_NUMBER 1
 '@S9S_MB_2U_LIB.S9S_MB_2U(SCH_1):PAGE264_I69@PURE_QUANTA.Q_RES(CHIPS)':
 C_PATH='@s9s_mb_2u_lib.s9s_mb_2u(sch_1):page264_i69@pure_quanta.q_res(chips)',
 P_PATH='@s9s_mb_2u_lib.s9s_mb_2u(sch_1):page278_i69@pure_quanta.q_res(chips)',
 PATH='I69',
 DRAWING='@S9S_MB_2U_LIB.S9S_MB_2U(SCH_1):PAGE264',
 PHYS_PAGE='278',
 XY='(-5200,6950)',
 ROT='0',
 VER='1',
 PACK_TYPE='0402LF',
 LOCATION='PR4231',
 CDS_LIB='pure_quanta',
 CDS_PART_NAME='Q_RES_0402LF-0,5%,1/16W,CHIP,CA',
 WATTAGE='1/16W',
 TOLERANCE='5%',
 MATERIAL='CHIP',
 VALUE='0',
 PRIM_FILE='./archive_libs/logical/q_res/chips/chips.prt';

PART_NAME
 PR4232 'Q_RES_0402LF-0,5%,1/16W,CHIP,CA':;

SECTION_NUMBER 1
 '@S9S_MB_2U_LIB.S9S_MB_2U(SCH_1):PAGE264_I68@PURE_QUANTA.Q_RES(CHIPS)':
 C_PATH='@s9s_mb_2u_lib.s9s_mb_2u(sch_1):page264_i68@pure_quanta.q_res(chips)',
 P_PATH='@s9s_mb_2u_lib.s9s_mb_2u(sch_1):page278_i68@pure_quanta.q_res(chips)',
 PATH='I68',
 DRAWING='@S9S_MB_2U_LIB.S9S_MB_2U(SCH_1):PAGE264',
 PHYS_PAGE='278',
 XY='(-5200,6500)',
 ROT='0',
 VER='1',
 PACK_TYPE='0402LF',
 LOCATION='PR4232',
 CDS_LIB='pure_quanta',
 CDS_PART_NAME='Q_RES_0402LF-0,5%,1/16W,CHIP,CA',
 WATTAGE='1/16W',
 TOLERANCE='5%',
 MATERIAL='CHIP',
 VALUE='0',
 PRIM_FILE='./archive_libs/logical/q_res/chips/chips.prt';

PART_NAME
 PR4233 'Q_RES_0402LF-0,5%,1/16W,CHIP,CA':;

SECTION_NUMBER 1
 '@S9S_MB_2U_LIB.S9S_MB_2U(SCH_1):PAGE264_I67@PURE_QUANTA.Q_RES(CHIPS)':
 C_PATH='@s9s_mb_2u_lib.s9s_mb_2u(sch_1):page264_i67@pure_quanta.q_res(chips)',
 P_PATH='@s9s_mb_2u_lib.s9s_mb_2u(sch_1):page278_i67@pure_quanta.q_res(chips)',
 PATH='I67',
 DRAWING='@S9S_MB_2U_LIB.S9S_MB_2U(SCH_1):PAGE264',
 PHYS_PAGE='278',
 XY='(-5200,6050)',
 ROT='0',
 VER='1',
 PACK_TYPE='0402LF',
 LOCATION='PR4233',
 CDS_LIB='pure_quanta',
 CDS_PART_NAME='Q_RES_0402LF-0,5%,1/16W,CHIP,CA',
 WATTAGE='1/16W',
 TOLERANCE='5%',
 MATERIAL='CHIP',
 VALUE='0',
 PRIM_FILE='./archive_libs/logical/q_res/chips/chips.prt';

PART_NAME
 PR4234 'Q_RES_0402LF-0,5%,1/16W,CHIP,CA':;

SECTION_NUMBER 1
 '@S9S_MB_2U_LIB.S9S_MB_2U(SCH_1):PAGE264_I66@PURE_QUANTA.Q_RES(CHIPS)':
 C_PATH='@s9s_mb_2u_lib.s9s_mb_2u(sch_1):page264_i66@pure_quanta.q_res(chips)',
 P_PATH='@s9s_mb_2u_lib.s9s_mb_2u(sch_1):page278_i66@pure_quanta.q_res(chips)',
 PATH='I66',
 DRAWING='@S9S_MB_2U_LIB.S9S_MB_2U(SCH_1):PAGE264',
 PHYS_PAGE='278',
 XY='(-5200,5600)',
 ROT='0',
 VER='1',
 PACK_TYPE='0402LF',
 LOCATION='PR4234',
 CDS_LIB='pure_quanta',
 CDS_PART_NAME='Q_RES_0402LF-0,5%,1/16W,CHIP,CA',
 WATTAGE='1/16W',
 TOLERANCE='5%',
 MATERIAL='CHIP',
 VALUE='0',
 PRIM_FILE='./archive_libs/logical/q_res/chips/chips.prt';

PART_NAME
 PR4235 'Q_RES_0402LF-0,5%,1/16W,CHIP,CA':;

SECTION_NUMBER 1
 '@S9S_MB_2U_LIB.S9S_MB_2U(SCH_1):PAGE264_I62@PURE_QUANTA.Q_RES(CHIPS)':
 C_PATH='@s9s_mb_2u_lib.s9s_mb_2u(sch_1):page264_i62@pure_quanta.q_res(chips)',
 P_PATH='@s9s_mb_2u_lib.s9s_mb_2u(sch_1):page278_i62@pure_quanta.q_res(chips)',
 PATH='I62',
 DRAWING='@S9S_MB_2U_LIB.S9S_MB_2U(SCH_1):PAGE264',
 PHYS_PAGE='278',
 XY='(-5200,5150)',
 ROT='0',
 VER='1',
 PACK_TYPE='0402LF',
 LOCATION='PR4235',
 CDS_LIB='pure_quanta',
 CDS_PART_NAME='Q_RES_0402LF-0,5%,1/16W,CHIP,CA',
 WATTAGE='1/16W',
 TOLERANCE='5%',
 MATERIAL='CHIP',
 VALUE='0',
 PRIM_FILE='./archive_libs/logical/q_res/chips/chips.prt';

PART_NAME
 PR4236 'Q_RES_0402LF-0,5%,1/16W,CHIP,CA':;

SECTION_NUMBER 1
 '@S9S_MB_2U_LIB.S9S_MB_2U(SCH_1):PAGE264_I61@PURE_QUANTA.Q_RES(CHIPS)':
 C_PATH='@s9s_mb_2u_lib.s9s_mb_2u(sch_1):page264_i61@pure_quanta.q_res(chips)',
 P_PATH='@s9s_mb_2u_lib.s9s_mb_2u(sch_1):page278_i61@pure_quanta.q_res(chips)',
 PATH='I61',
 DRAWING='@S9S_MB_2U_LIB.S9S_MB_2U(SCH_1):PAGE264',
 PHYS_PAGE='278',
 XY='(-5200,4700)',
 ROT='0',
 VER='1',
 PACK_TYPE='0402LF',
 LOCATION='PR4236',
 CDS_LIB='pure_quanta',
 CDS_PART_NAME='Q_RES_0402LF-0,5%,1/16W,CHIP,CA',
 WATTAGE='1/16W',
 TOLERANCE='5%',
 MATERIAL='CHIP',
 VALUE='0',
 PRIM_FILE='./archive_libs/logical/q_res/chips/chips.prt';

PART_NAME
 PR4237 'Q_RES_0402LF-499,1%,1/16W,CHIPA':;

SECTION_NUMBER 1
 '@S9S_MB_2U_LIB.S9S_MB_2U(SCH_1):PAGE265_I37@PURE_QUANTA.Q_RES(CHIPS)':
 C_PATH='@s9s_mb_2u_lib.s9s_mb_2u(sch_1):page265_i37@pure_quanta.q_res(chips)',
 P_PATH='@s9s_mb_2u_lib.s9s_mb_2u(sch_1):page279_i37@pure_quanta.q_res(chips)',
 PATH='I37',
 DRAWING='@S9S_MB_2U_LIB.S9S_MB_2U(SCH_1):PAGE265',
 BOM_COST='VR_PCH',
 PHYS_PAGE='279',
 XY='(-1825,1725)',
 ROT='0',
 VER='2',
 PACK_TYPE='0402LF',
 LOCATION='PR4237',
 CDS_LIB='pure_quanta',
 CDS_PART_NAME='Q_RES_0402LF-499,1%,1/16W,CHIPA',
 WATTAGE='1/16W',
 TOLERANCE='1%',
 MATERIAL='CHIP',
 VALUE='499',
 PRIM_FILE='./archive_libs/logical/q_res/chips/chips.prt';

PART_NAME
 PR4238 'Q_RES_0402LF-0,5%,1/16W,EMPTY,A':;

SECTION_NUMBER 1
 '@S9S_MB_2U_LIB.S9S_MB_2U(SCH_1):PAGE270_I81@PURE_QUANTA.Q_RES(CHIPS)':
 C_PATH='@s9s_mb_2u_lib.s9s_mb_2u(sch_1):page270_i81@pure_quanta.q_res(chips)',
 P_PATH='@s9s_mb_2u_lib.s9s_mb_2u(sch_1):page284_i81@pure_quanta.q_res(chips)',
 PATH='I81',
 DRAWING='@S9S_MB_2U_LIB.S9S_MB_2U(SCH_1):PAGE270',
 PHYS_PAGE='284',
 XY='(1275,-550)',
 ROT='0',
 VER='1',
 PACK_TYPE='0402LF',
 LOCATION='PR4238',
 CDS_LIB='pure_quanta',
 CDS_PART_NAME='Q_RES_0402LF-0,5%,1/16W,EMPTY,A',
 WATTAGE='1/16W',
 TOLERANCE='5%',
 MATERIAL='EMPTY',
 VALUE='0',
 PRIM_FILE='./archive_libs/logical/q_res/chips/chips.prt';

PART_NAME
 PR4239 'Q_RES_0402LF-0,5%,1/16W,EMPTY,A':;

SECTION_NUMBER 1
 '@S9S_MB_2U_LIB.S9S_MB_2U(SCH_1):PAGE270_I80@PURE_QUANTA.Q_RES(CHIPS)':
 C_PATH='@s9s_mb_2u_lib.s9s_mb_2u(sch_1):page270_i80@pure_quanta.q_res(chips)',
 P_PATH='@s9s_mb_2u_lib.s9s_mb_2u(sch_1):page284_i80@pure_quanta.q_res(chips)',
 PATH='I80',
 DRAWING='@S9S_MB_2U_LIB.S9S_MB_2U(SCH_1):PAGE270',
 PHYS_PAGE='284',
 XY='(1275,-850)',
 ROT='0',
 VER='1',
 PACK_TYPE='0402LF',
 LOCATION='PR4239',
 CDS_LIB='pure_quanta',
 CDS_PART_NAME='Q_RES_0402LF-0,5%,1/16W,EMPTY,A',
 WATTAGE='1/16W',
 TOLERANCE='5%',
 MATERIAL='EMPTY',
 VALUE='0',
 PRIM_FILE='./archive_libs/logical/q_res/chips/chips.prt';

PART_NAME
 PR4240 'Q_RES_0402LF-499,1%,1/16W,CHIPA':;

SECTION_NUMBER 1
 '@S9S_MB_2U_LIB.S9S_MB_2U(SCH_1):PAGE271_I59@PURE_QUANTA.Q_RES(CHIPS)':
 C_PATH='@s9s_mb_2u_lib.s9s_mb_2u(sch_1):page271_i59@pure_quanta.q_res(chips)',
 P_PATH='@s9s_mb_2u_lib.s9s_mb_2u(sch_1):page285_i59@pure_quanta.q_res(chips)',
 PATH='I59',
 DRAWING='@S9S_MB_2U_LIB.S9S_MB_2U(SCH_1):PAGE271',
 BOM_COST='VR_PCH',
 PHYS_PAGE='285',
 XY='(3700,-1975)',
 ROT='0',
 VER='2',
 PACK_TYPE='0402LF',
 LOCATION='PR4240',
 CDS_LIB='pure_quanta',
 CDS_PART_NAME='Q_RES_0402LF-499,1%,1/16W,CHIPA',
 WATTAGE='1/16W',
 TOLERANCE='1%',
 MATERIAL='CHIP',
 VALUE='499',
 PRIM_FILE='./archive_libs/logical/q_res/chips/chips.prt';

PART_NAME
 PR4241 'Q_RES_0402LF-499,1%,1/16W,CHIPA':;

SECTION_NUMBER 1
 '@S9S_MB_2U_LIB.S9S_MB_2U(SCH_1):PAGE275_I64@PURE_QUANTA.Q_RES(CHIPS)':
 C_PATH='@s9s_mb_2u_lib.s9s_mb_2u(sch_1):page275_i64@pure_quanta.q_res(chips)',
 P_PATH='@s9s_mb_2u_lib.s9s_mb_2u(sch_1):page289_i64@pure_quanta.q_res(chips)',
 PATH='I64',
 DRAWING='@S9S_MB_2U_LIB.S9S_MB_2U(SCH_1):PAGE275',
 BOM_COST='VR_PCH',
 PHYS_PAGE='289',
 XY='(-3650,1675)',
 ROT='0',
 VER='2',
 PACK_TYPE='0402LF',
 LOCATION='PR4241',
 CDS_LIB='pure_quanta',
 CDS_PART_NAME='Q_RES_0402LF-499,1%,1/16W,CHIPA',
 WATTAGE='1/16W',
 TOLERANCE='1%',
 MATERIAL='CHIP',
 VALUE='499',
 PRIM_FILE='./archive_libs/logical/q_res/chips/chips.prt';

PART_NAME
 PR4242 'Q_RES_0402LF-0,5%,1/16W,CHIP,CA':;

SECTION_NUMBER 1
 '@S9S_MB_2U_LIB.S9S_MB_2U(SCH_1):PAGE278_I89@PURE_QUANTA.Q_RES(CHIPS)':
 C_PATH='@s9s_mb_2u_lib.s9s_mb_2u(sch_1):page278_i89@pure_quanta.q_res(chips)',
 P_PATH='@s9s_mb_2u_lib.s9s_mb_2u(sch_1):page292_i89@pure_quanta.q_res(chips)',
 PATH='I89',
 DRAWING='@S9S_MB_2U_LIB.S9S_MB_2U(SCH_1):PAGE278',
 PHYS_PAGE='292',
 XY='(5350,7150)',
 ROT='0',
 VER='1',
 PACK_TYPE='0402LF',
 LOCATION='PR4242',
 CDS_LIB='pure_quanta',
 CDS_PART_NAME='Q_RES_0402LF-0,5%,1/16W,CHIP,CA',
 WATTAGE='1/16W',
 TOLERANCE='5%',
 MATERIAL='CHIP',
 VALUE='0',
 PRIM_FILE='./archive_libs/logical/q_res/chips/chips.prt';

PART_NAME
 PR4243 'Q_RES_0402LF-0,5%,1/16W,CHIP,CA':;

SECTION_NUMBER 1
 '@S9S_MB_2U_LIB.S9S_MB_2U(SCH_1):PAGE278_I81@PURE_QUANTA.Q_RES(CHIPS)':
 C_PATH='@s9s_mb_2u_lib.s9s_mb_2u(sch_1):page278_i81@pure_quanta.q_res(chips)',
 P_PATH='@s9s_mb_2u_lib.s9s_mb_2u(sch_1):page292_i81@pure_quanta.q_res(chips)',
 PATH='I81',
 DRAWING='@S9S_MB_2U_LIB.S9S_MB_2U(SCH_1):PAGE278',
 PHYS_PAGE='292',
 XY='(5350,6700)',
 ROT='0',
 VER='1',
 PACK_TYPE='0402LF',
 LOCATION='PR4243',
 CDS_LIB='pure_quanta',
 CDS_PART_NAME='Q_RES_0402LF-0,5%,1/16W,CHIP,CA',
 WATTAGE='1/16W',
 TOLERANCE='5%',
 MATERIAL='CHIP',
 VALUE='0',
 PRIM_FILE='./archive_libs/logical/q_res/chips/chips.prt';

PART_NAME
 PR4244 'Q_RES_0402LF-0,5%,1/16W,CHIP,CA':;

SECTION_NUMBER 1
 '@S9S_MB_2U_LIB.S9S_MB_2U(SCH_1):PAGE278_I80@PURE_QUANTA.Q_RES(CHIPS)':
 C_PATH='@s9s_mb_2u_lib.s9s_mb_2u(sch_1):page278_i80@pure_quanta.q_res(chips)',
 P_PATH='@s9s_mb_2u_lib.s9s_mb_2u(sch_1):page292_i80@pure_quanta.q_res(chips)',
 PATH='I80',
 DRAWING='@S9S_MB_2U_LIB.S9S_MB_2U(SCH_1):PAGE278',
 PHYS_PAGE='292',
 XY='(5350,6250)',
 ROT='0',
 VER='1',
 PACK_TYPE='0402LF',
 LOCATION='PR4244',
 CDS_LIB='pure_quanta',
 CDS_PART_NAME='Q_RES_0402LF-0,5%,1/16W,CHIP,CA',
 WATTAGE='1/16W',
 TOLERANCE='5%',
 MATERIAL='CHIP',
 VALUE='0',
 PRIM_FILE='./archive_libs/logical/q_res/chips/chips.prt';

PART_NAME
 PR4245 'Q_RES_0402LF-0,5%,1/16W,CHIP,CA':;

SECTION_NUMBER 1
 '@S9S_MB_2U_LIB.S9S_MB_2U(SCH_1):PAGE278_I79@PURE_QUANTA.Q_RES(CHIPS)':
 C_PATH='@s9s_mb_2u_lib.s9s_mb_2u(sch_1):page278_i79@pure_quanta.q_res(chips)',
 P_PATH='@s9s_mb_2u_lib.s9s_mb_2u(sch_1):page292_i79@pure_quanta.q_res(chips)',
 PATH='I79',
 DRAWING='@S9S_MB_2U_LIB.S9S_MB_2U(SCH_1):PAGE278',
 PHYS_PAGE='292',
 XY='(5350,5800)',
 ROT='0',
 VER='1',
 PACK_TYPE='0402LF',
 LOCATION='PR4245',
 CDS_LIB='pure_quanta',
 CDS_PART_NAME='Q_RES_0402LF-0,5%,1/16W,CHIP,CA',
 WATTAGE='1/16W',
 TOLERANCE='5%',
 MATERIAL='CHIP',
 VALUE='0',
 PRIM_FILE='./archive_libs/logical/q_res/chips/chips.prt';

PART_NAME
 PR4246 'Q_RES_0402LF-0,5%,1/16W,CHIP,CA':;

SECTION_NUMBER 1
 '@S9S_MB_2U_LIB.S9S_MB_2U(SCH_1):PAGE278_I78@PURE_QUANTA.Q_RES(CHIPS)':
 C_PATH='@s9s_mb_2u_lib.s9s_mb_2u(sch_1):page278_i78@pure_quanta.q_res(chips)',
 P_PATH='@s9s_mb_2u_lib.s9s_mb_2u(sch_1):page292_i78@pure_quanta.q_res(chips)',
 PATH='I78',
 DRAWING='@S9S_MB_2U_LIB.S9S_MB_2U(SCH_1):PAGE278',
 PHYS_PAGE='292',
 XY='(5350,5350)',
 ROT='0',
 VER='1',
 PACK_TYPE='0402LF',
 LOCATION='PR4246',
 CDS_LIB='pure_quanta',
 CDS_PART_NAME='Q_RES_0402LF-0,5%,1/16W,CHIP,CA',
 WATTAGE='1/16W',
 TOLERANCE='5%',
 MATERIAL='CHIP',
 VALUE='0',
 PRIM_FILE='./archive_libs/logical/q_res/chips/chips.prt';

PART_NAME
 PR4247 'Q_RES_0402LF-499,1%,1/16W,CHIPA':;

SECTION_NUMBER 1
 '@S9S_MB_2U_LIB.S9S_MB_2U(SCH_1):PAGE279_I34@PURE_QUANTA.Q_RES(CHIPS)':
 C_PATH='@s9s_mb_2u_lib.s9s_mb_2u(sch_1):page279_i34@pure_quanta.q_res(chips)',
 P_PATH='@s9s_mb_2u_lib.s9s_mb_2u(sch_1):page293_i34@pure_quanta.q_res(chips)',
 PATH='I34',
 DRAWING='@S9S_MB_2U_LIB.S9S_MB_2U(SCH_1):PAGE279',
 BOM_COST='VR_PCH',
 PHYS_PAGE='293',
 XY='(-2800,8225)',
 ROT='0',
 VER='2',
 PACK_TYPE='0402LF',
 LOCATION='PR4247',
 CDS_LIB='pure_quanta',
 CDS_PART_NAME='Q_RES_0402LF-499,1%,1/16W,CHIPA',
 WATTAGE='1/16W',
 TOLERANCE='1%',
 MATERIAL='CHIP',
 VALUE='499',
 PRIM_FILE='./archive_libs/logical/q_res/chips/chips.prt';

PART_NAME
 PR4248 'Q_RES_0402LF-0,5%,1/16W,EMPTY,A':;

SECTION_NUMBER 1
 '@S9S_MB_2U_LIB.S9S_MB_2U(SCH_1):PAGE280_I13@PURE_QUANTA.Q_RES(CHIPS)':
 C_PATH='@s9s_mb_2u_lib.s9s_mb_2u(sch_1):page280_i13@pure_quanta.q_res(chips)',
 P_PATH='@s9s_mb_2u_lib.s9s_mb_2u(sch_1):page294_i13@pure_quanta.q_res(chips)',
 PATH='I13',
 DRAWING='@S9S_MB_2U_LIB.S9S_MB_2U(SCH_1):PAGE280',
 PHYS_PAGE='294',
 XY='(-5650,9600)',
 ROT='1',
 VER='1',
 PACK_TYPE='0402LF',
 LOCATION='PR4248',
 CDS_LIB='pure_quanta',
 CDS_PART_NAME='Q_RES_0402LF-0,5%,1/16W,EMPTY,A',
 WATTAGE='1/16W',
 TOLERANCE='5%',
 MATERIAL='EMPTY',
 VALUE='0',
 PRIM_FILE='./archive_libs/logical/q_res/chips/chips.prt';

PART_NAME
 PR4249 'Q_RES_0402LF-0,5%,1/16W,EMPTY,A':;

SECTION_NUMBER 1
 '@S9S_MB_2U_LIB.S9S_MB_2U(SCH_1):PAGE280_I18@PURE_QUANTA.Q_RES(CHIPS)':
 C_PATH='@s9s_mb_2u_lib.s9s_mb_2u(sch_1):page280_i18@pure_quanta.q_res(chips)',
 P_PATH='@s9s_mb_2u_lib.s9s_mb_2u(sch_1):page294_i18@pure_quanta.q_res(chips)',
 PATH='I18',
 DRAWING='@S9S_MB_2U_LIB.S9S_MB_2U(SCH_1):PAGE280',
 PHYS_PAGE='294',
 XY='(-3125,8700)',
 ROT='0',
 VER='1',
 PACK_TYPE='0402LF',
 LOCATION='PR4249',
 CDS_LIB='pure_quanta',
 CDS_PART_NAME='Q_RES_0402LF-0,5%,1/16W,EMPTY,A',
 WATTAGE='1/16W',
 TOLERANCE='5%',
 MATERIAL='EMPTY',
 VALUE='0',
 PRIM_FILE='./archive_libs/logical/q_res/chips/chips.prt';

PART_NAME
 PR4250 'Q_RES_0402LF-499,1%,1/16W,CHIPA':;

SECTION_NUMBER 1
 '@S9S_MB_2U_LIB.S9S_MB_2U(SCH_1):PAGE280_I37@PURE_QUANTA.Q_RES(CHIPS)':
 C_PATH='@s9s_mb_2u_lib.s9s_mb_2u(sch_1):page280_i37@pure_quanta.q_res(chips)',
 P_PATH='@s9s_mb_2u_lib.s9s_mb_2u(sch_1):page294_i37@pure_quanta.q_res(chips)',
 PATH='I37',
 DRAWING='@S9S_MB_2U_LIB.S9S_MB_2U(SCH_1):PAGE280',
 BOM_COST='VR_PCH',
 PHYS_PAGE='294',
 XY='(125,9000)',
 ROT='0',
 VER='2',
 PACK_TYPE='0402LF',
 LOCATION='PR4250',
 CDS_LIB='pure_quanta',
 CDS_PART_NAME='Q_RES_0402LF-499,1%,1/16W,CHIPA',
 WATTAGE='1/16W',
 TOLERANCE='1%',
 MATERIAL='CHIP',
 VALUE='499',
 PRIM_FILE='./archive_libs/logical/q_res/chips/chips.prt';

PART_NAME
 PR4251 'Q_RES_0402LF-0,5%,1/16W,CHIP,CA':;

SECTION_NUMBER 1
 '@S9S_MB_2U_LIB.S9S_MB_2U(SCH_1):PAGE282_I70@PURE_QUANTA.Q_RES(CHIPS)':
 C_PATH='@s9s_mb_2u_lib.s9s_mb_2u(sch_1):page282_i70@pure_quanta.q_res(chips)',
 P_PATH='@s9s_mb_2u_lib.s9s_mb_2u(sch_1):page296_i70@pure_quanta.q_res(chips)',
 PATH='I70',
 DRAWING='@S9S_MB_2U_LIB.S9S_MB_2U(SCH_1):PAGE282',
 PHYS_PAGE='296',
 XY='(-800,3900)',
 ROT='0',
 VER='1',
 PACK_TYPE='0402LF',
 LOCATION='PR4251',
 CDS_LIB='pure_quanta',
 CDS_PART_NAME='Q_RES_0402LF-0,5%,1/16W,CHIP,CA',
 WATTAGE='1/16W',
 TOLERANCE='5%',
 MATERIAL='CHIP',
 VALUE='0',
 PRIM_FILE='./archive_libs/logical/q_res/chips/chips.prt';

PART_NAME
 PR4252 'Q_RES_0402LF-0,5%,1/16W,CHIP,CA':;

SECTION_NUMBER 1
 '@S9S_MB_2U_LIB.S9S_MB_2U(SCH_1):PAGE282_I64@PURE_QUANTA.Q_RES(CHIPS)':
 C_PATH='@s9s_mb_2u_lib.s9s_mb_2u(sch_1):page282_i64@pure_quanta.q_res(chips)',
 P_PATH='@s9s_mb_2u_lib.s9s_mb_2u(sch_1):page296_i64@pure_quanta.q_res(chips)',
 PATH='I64',
 DRAWING='@S9S_MB_2U_LIB.S9S_MB_2U(SCH_1):PAGE282',
 PHYS_PAGE='296',
 XY='(-800,3450)',
 ROT='0',
 VER='1',
 PACK_TYPE='0402LF',
 LOCATION='PR4252',
 CDS_LIB='pure_quanta',
 CDS_PART_NAME='Q_RES_0402LF-0,5%,1/16W,CHIP,CA',
 WATTAGE='1/16W',
 TOLERANCE='5%',
 MATERIAL='CHIP',
 VALUE='0',
 PRIM_FILE='./archive_libs/logical/q_res/chips/chips.prt';

PART_NAME
 PR4253 'Q_RES_0402LF-0,5%,1/16W,CHIP,CA':;

SECTION_NUMBER 1
 '@S9S_MB_2U_LIB.S9S_MB_2U(SCH_1):PAGE282_I65@PURE_QUANTA.Q_RES(CHIPS)':
 C_PATH='@s9s_mb_2u_lib.s9s_mb_2u(sch_1):page282_i65@pure_quanta.q_res(chips)',
 P_PATH='@s9s_mb_2u_lib.s9s_mb_2u(sch_1):page296_i65@pure_quanta.q_res(chips)',
 PATH='I65',
 DRAWING='@S9S_MB_2U_LIB.S9S_MB_2U(SCH_1):PAGE282',
 PHYS_PAGE='296',
 XY='(-800,3000)',
 ROT='0',
 VER='1',
 PACK_TYPE='0402LF',
 LOCATION='PR4253',
 CDS_LIB='pure_quanta',
 CDS_PART_NAME='Q_RES_0402LF-0,5%,1/16W,CHIP,CA',
 WATTAGE='1/16W',
 TOLERANCE='5%',
 MATERIAL='CHIP',
 VALUE='0',
 PRIM_FILE='./archive_libs/logical/q_res/chips/chips.prt';

PART_NAME
 PR4254 'Q_RES_0402LF-0,5%,1/16W,CHIP,CA':;

SECTION_NUMBER 1
 '@S9S_MB_2U_LIB.S9S_MB_2U(SCH_1):PAGE282_I66@PURE_QUANTA.Q_RES(CHIPS)':
 C_PATH='@s9s_mb_2u_lib.s9s_mb_2u(sch_1):page282_i66@pure_quanta.q_res(chips)',
 P_PATH='@s9s_mb_2u_lib.s9s_mb_2u(sch_1):page296_i66@pure_quanta.q_res(chips)',
 PATH='I66',
 DRAWING='@S9S_MB_2U_LIB.S9S_MB_2U(SCH_1):PAGE282',
 PHYS_PAGE='296',
 XY='(-800,2550)',
 ROT='0',
 VER='1',
 PACK_TYPE='0402LF',
 LOCATION='PR4254',
 CDS_LIB='pure_quanta',
 CDS_PART_NAME='Q_RES_0402LF-0,5%,1/16W,CHIP,CA',
 WATTAGE='1/16W',
 TOLERANCE='5%',
 MATERIAL='CHIP',
 VALUE='0',
 PRIM_FILE='./archive_libs/logical/q_res/chips/chips.prt';

PART_NAME
 PR4255 'Q_RES_0402LF-0,5%,1/16W,CHIP,CA':;

SECTION_NUMBER 1
 '@S9S_MB_2U_LIB.S9S_MB_2U(SCH_1):PAGE282_I62@PURE_QUANTA.Q_RES(CHIPS)':
 C_PATH='@s9s_mb_2u_lib.s9s_mb_2u(sch_1):page282_i62@pure_quanta.q_res(chips)',
 P_PATH='@s9s_mb_2u_lib.s9s_mb_2u(sch_1):page296_i62@pure_quanta.q_res(chips)',
 PATH='I62',
 DRAWING='@S9S_MB_2U_LIB.S9S_MB_2U(SCH_1):PAGE282',
 PHYS_PAGE='296',
 XY='(-800,2100)',
 ROT='0',
 VER='1',
 PACK_TYPE='0402LF',
 LOCATION='PR4255',
 CDS_LIB='pure_quanta',
 CDS_PART_NAME='Q_RES_0402LF-0,5%,1/16W,CHIP,CA',
 WATTAGE='1/16W',
 TOLERANCE='5%',
 MATERIAL='CHIP',
 VALUE='0',
 PRIM_FILE='./archive_libs/logical/q_res/chips/chips.prt';

PART_NAME
 PR4256 'Q_RES_0402LF-0,5%,1/16W,CHIP,CA':;

SECTION_NUMBER 1
 '@S9S_MB_2U_LIB.S9S_MB_2U(SCH_1):PAGE282_I63@PURE_QUANTA.Q_RES(CHIPS)':
 C_PATH='@s9s_mb_2u_lib.s9s_mb_2u(sch_1):page282_i63@pure_quanta.q_res(chips)',
 P_PATH='@s9s_mb_2u_lib.s9s_mb_2u(sch_1):page296_i63@pure_quanta.q_res(chips)',
 PATH='I63',
 DRAWING='@S9S_MB_2U_LIB.S9S_MB_2U(SCH_1):PAGE282',
 PHYS_PAGE='296',
 XY='(-800,1650)',
 ROT='0',
 VER='1',
 PACK_TYPE='0402LF',
 LOCATION='PR4256',
 CDS_LIB='pure_quanta',
 CDS_PART_NAME='Q_RES_0402LF-0,5%,1/16W,CHIP,CA',
 WATTAGE='1/16W',
 TOLERANCE='5%',
 MATERIAL='CHIP',
 VALUE='0',
 PRIM_FILE='./archive_libs/logical/q_res/chips/chips.prt';

PART_NAME
 PR4257 'Q_RES_0402LF-0,5%,1/16W,CHIP,CA':;

SECTION_NUMBER 1
 '@S9S_MB_2U_LIB.S9S_MB_2U(SCH_1):PAGE282_I59@PURE_QUANTA.Q_RES(CHIPS)':
 C_PATH='@s9s_mb_2u_lib.s9s_mb_2u(sch_1):page282_i59@pure_quanta.q_res(chips)',
 P_PATH='@s9s_mb_2u_lib.s9s_mb_2u(sch_1):page296_i59@pure_quanta.q_res(chips)',
 PATH='I59',
 DRAWING='@S9S_MB_2U_LIB.S9S_MB_2U(SCH_1):PAGE282',
 PHYS_PAGE='296',
 XY='(-800,1200)',
 ROT='0',
 VER='1',
 PACK_TYPE='0402LF',
 LOCATION='PR4257',
 CDS_LIB='pure_quanta',
 CDS_PART_NAME='Q_RES_0402LF-0,5%,1/16W,CHIP,CA',
 WATTAGE='1/16W',
 TOLERANCE='5%',
 MATERIAL='CHIP',
 VALUE='0',
 PRIM_FILE='./archive_libs/logical/q_res/chips/chips.prt';

PART_NAME
 PR4258 'Q_RES_0402LF-499,1%,1/16W,CHIPA':;

SECTION_NUMBER 1
 '@S9S_MB_2U_LIB.S9S_MB_2U(SCH_1):PAGE283_I35@PURE_QUANTA.Q_RES(CHIPS)':
 C_PATH='@s9s_mb_2u_lib.s9s_mb_2u(sch_1):page283_i35@pure_quanta.q_res(chips)',
 P_PATH='@s9s_mb_2u_lib.s9s_mb_2u(sch_1):page297_i35@pure_quanta.q_res(chips)',
 PATH='I35',
 DRAWING='@S9S_MB_2U_LIB.S9S_MB_2U(SCH_1):PAGE283',
 BOM_COST='VR_PCH',
 PHYS_PAGE='297',
 XY='(-1750,3425)',
 ROT='0',
 VER='2',
 PACK_TYPE='0402LF',
 LOCATION='PR4258',
 CDS_LIB='pure_quanta',
 CDS_PART_NAME='Q_RES_0402LF-499,1%,1/16W,CHIPA',
 WATTAGE='1/16W',
 TOLERANCE='1%',
 MATERIAL='CHIP',
 VALUE='499',
 PRIM_FILE='./archive_libs/logical/q_res/chips/chips.prt';

PART_NAME
 PR4265 'Q_RES_0402LF-499,1%,1/16W,CHIPA':;

SECTION_NUMBER 1
 '@S9S_MB_2U_LIB.S9S_MB_2U(SCH_1):PAGE257_I60@PURE_QUANTA.Q_RES(CHIPS)':
 C_PATH='@s9s_mb_2u_lib.s9s_mb_2u(sch_1):page257_i60@pure_quanta.q_res(chips)',
 P_PATH='@s9s_mb_2u_lib.s9s_mb_2u(sch_1):page271_i60@pure_quanta.q_res(chips)',
 PATH='I60',
 DRAWING='@S9S_MB_2U_LIB.S9S_MB_2U(SCH_1):PAGE257',
 BOM_COST='VR_PCH',
 PHYS_PAGE='271',
 XY='(2300,2200)',
 ROT='0',
 VER='2',
 PACK_TYPE='0402LF',
 LOCATION='PR4265',
 CDS_LIB='pure_quanta',
 CDS_PART_NAME='Q_RES_0402LF-499,1%,1/16W,CHIPA',
 WATTAGE='1/16W',
 TOLERANCE='1%',
 MATERIAL='CHIP',
 VALUE='499',
 PRIM_FILE='./archive_libs/logical/q_res/chips/chips.prt';

PART_NAME
 PR4271 'Q_RES_0402LF-0,5%,1/16W,CHIP,CA':;

SECTION_NUMBER 1
 '@S9S_MB_2U_LIB.S9S_MB_2U(SCH_1):PAGE268_I27@PURE_QUANTA.Q_RES(CHIPS)':
 C_PATH='@s9s_mb_2u_lib.s9s_mb_2u(sch_1):page268_i27@pure_quanta.q_res(chips)',
 P_PATH='@s9s_mb_2u_lib.s9s_mb_2u(sch_1):page282_i27@pure_quanta.q_res(chips)',
 PATH='I27',
 DRAWING='@S9S_MB_2U_LIB.S9S_MB_2U(SCH_1):PAGE268',
 PHYS_PAGE='282',
 XY='(-5450,10150)',
 ROT='0',
 VER='1',
 PACK_TYPE='0402LF',
 LOCATION='PR4271',
 SEC='1',
 CDS_LIB='pure_quanta',
 CDS_PART_NAME='Q_RES_0402LF-0,5%,1/16W,CHIP,CA',
 SEC_TYPE='0402LF',
 WATTAGE='1/16W',
 TOLERANCE='5%',
 MATERIAL='CHIP',
 VALUE='0',
 PRIM_FILE='./archive_libs/logical/q_res/chips/chips.prt';

PART_NAME
 PR4272 'Q_RES_0402LF-0,5%,1/16W,CHIP,CA':;

SECTION_NUMBER 1
 '@S9S_MB_2U_LIB.S9S_MB_2U(SCH_1):PAGE286_I25@PURE_QUANTA.Q_RES(CHIPS)':
 C_PATH='@s9s_mb_2u_lib.s9s_mb_2u(sch_1):page286_i25@pure_quanta.q_res(chips)',
 P_PATH='@s9s_mb_2u_lib.s9s_mb_2u(sch_1):page300_i25@pure_quanta.q_res(chips)',
 PATH='I25',
 DRAWING='@S9S_MB_2U_LIB.S9S_MB_2U(SCH_1):PAGE286',
 PHYS_PAGE='300',
 XY='(6375,7525)',
 ROT='0',
 VER='1',
 PACK_TYPE='0402LF',
 LOCATION='PR4272',
 SEC='1',
 CDS_LIB='pure_quanta',
 CDS_PART_NAME='Q_RES_0402LF-0,5%,1/16W,CHIP,CA',
 SEC_TYPE='0402LF',
 WATTAGE='1/16W',
 TOLERANCE='5%',
 MATERIAL='CHIP',
 VALUE='0',
 PRIM_FILE='./archive_libs/logical/q_res/chips/chips.prt';

PART_NAME
 PR4522 'Q_RES_0402LF-10M,1%,1/16W,EMPTA':
 ROOM='NIC1_P12V_MAM_MAM_BOM1';

SECTION_NUMBER 1
 '@S9S_MB_2U_LIB.S9S_MB_2U(SCH_1):PAGE131_I77@PURE_QUANTA.Q_RES(CHIPS)':
 C_PATH='@s9s_mb_2u_lib.s9s_mb_2u(sch_1):page131_i77@pure_quanta.q_res(chips)',
 P_PATH='@s9s_mb_2u_lib.s9s_mb_2u(sch_1):page162_i77@pure_quanta.q_res(chips)',
 PATH='I77',
 DRAWING='@S9S_MB_2U_LIB.S9S_MB_2U(SCH_1):PAGE131',
 ROOM1='NIC1_P12V_MAM_TIC_BOM2',
 PHYS_PAGE='162',
 XY='(2550,-200)',
 ROT='0',
 VER='2',
 PACK_TYPE='0402LF',
 LOCATION='PR4522',
 CDS_LIB='pure_quanta',
 CDS_PART_NAME='Q_RES_0402LF-10M,1%,1/16W,EMPTA',
 WATTAGE='1/16W',
 TOLERANCE='1%',
 MATERIAL='EMPTY',
 ROOM='NIC1_P12V_MAM_MAM_BOM1',
 VALUE='10M',
 PRIM_FILE='./archive_libs/logical/q_res/chips/chips.prt';

PART_NAME
 PR4523 'Q_RES_0402LF-10M,1%,1/16W,CHIPA':
 ROOM='NIC1_P3V3_BOM1';

SECTION_NUMBER 1
 '@S9S_MB_2U_LIB.S9S_MB_2U(SCH_1):PAGE131_I106@PURE_QUANTA.Q_RES(CHIPS)':
 C_PATH='@s9s_mb_2u_lib.s9s_mb_2u(sch_1):page131_i106@pure_quanta.q_res(chips)',
 P_PATH='@s9s_mb_2u_lib.s9s_mb_2u(sch_1):page162_i106@pure_quanta.q_res(chips)',
 PATH='I106',
 DRAWING='@S9S_MB_2U_LIB.S9S_MB_2U(SCH_1):PAGE131',
 PHYS_PAGE='162',
 XY='(2650,2150)',
 ROT='0',
 VER='2',
 PACK_TYPE='0402LF',
 LOCATION='PR4523',
 CDS_LIB='pure_quanta',
 CDS_PART_NAME='Q_RES_0402LF-10M,1%,1/16W,CHIPA',
 WATTAGE='1/16W',
 TOLERANCE='1%',
 MATERIAL='CHIP',
 ROOM='NIC1_P3V3_BOM1',
 VALUE='10M',
 PRIM_FILE='./archive_libs/logical/q_res/chips/chips.prt';

PART_NAME
 PR4524 'Q_RES_0402LF-10M,1%,1/16W,EMPTA':
 ROOM='NIC1_P12V_MAM_MAM_BOM1';

SECTION_NUMBER 1
 '@S9S_MB_2U_LIB.S9S_MB_2U(SCH_1):PAGE153_I84@PURE_QUANTA.Q_RES(CHIPS)':
 C_PATH='@s9s_mb_2u_lib.s9s_mb_2u(sch_1):page153_i84@pure_quanta.q_res(chips)',
 P_PATH='@s9s_mb_2u_lib.s9s_mb_2u(sch_1):page156_i84@pure_quanta.q_res(chips)',
 PATH='I84',
 DRAWING='@S9S_MB_2U_LIB.S9S_MB_2U(SCH_1):PAGE153',
 ROOM1='NIC1_P12V_MAM_TIC_BOM2',
 PHYS_PAGE='156',
 XY='(8625,11025)',
 ROT='0',
 VER='2',
 PACK_TYPE='0402LF',
 LOCATION='PR4524',
 CDS_LIB='pure_quanta',
 CDS_PART_NAME='Q_RES_0402LF-10M,1%,1/16W,EMPTA',
 WATTAGE='1/16W',
 TOLERANCE='1%',
 MATERIAL='EMPTY',
 ROOM='NIC1_P12V_MAM_MAM_BOM1',
 VALUE='10M',
 PRIM_FILE='./archive_libs/logical/q_res/chips/chips.prt';

PART_NAME
 PR4525 'Q_RES_0402LF-10M,1%,1/16W,CHIPA':
 ROOM='NIC1_P3V3_BOM1';

SECTION_NUMBER 1
 '@S9S_MB_2U_LIB.S9S_MB_2U(SCH_1):PAGE153_I103@PURE_QUANTA.Q_RES(CHIPS)':
 C_PATH='@s9s_mb_2u_lib.s9s_mb_2u(sch_1):page153_i103@pure_quanta.q_res(chips)',
 P_PATH='@s9s_mb_2u_lib.s9s_mb_2u(sch_1):page156_i103@pure_quanta.q_res(chips)',
 PATH='I103',
 DRAWING='@S9S_MB_2U_LIB.S9S_MB_2U(SCH_1):PAGE153',
 PHYS_PAGE='156',
 XY='(8825,13125)',
 ROT='0',
 VER='2',
 PACK_TYPE='0402LF',
 LOCATION='PR4525',
 CDS_LIB='pure_quanta',
 CDS_PART_NAME='Q_RES_0402LF-10M,1%,1/16W,CHIPA',
 WATTAGE='1/16W',
 TOLERANCE='1%',
 MATERIAL='CHIP',
 ROOM='NIC1_P3V3_BOM1',
 VALUE='10M',
 PRIM_FILE='./archive_libs/logical/q_res/chips/chips.prt';

PART_NAME
 PR4526 'Q_RES_0402LF-10M,1%,1/16W,EMPTA':
 ROOM='SCM_P12V_BOM1';

SECTION_NUMBER 1
 '@S9S_MB_2U_LIB.S9S_MB_2U(SCH_1):PAGE229_I76@PURE_QUANTA.Q_RES(CHIPS)':
 C_PATH='@s9s_mb_2u_lib.s9s_mb_2u(sch_1):page229_i76@pure_quanta.q_res(chips)',
 P_PATH='@s9s_mb_2u_lib.s9s_mb_2u(sch_1):page242_i76@pure_quanta.q_res(chips)',
 PATH='I76',
 DRAWING='@S9S_MB_2U_LIB.S9S_MB_2U(SCH_1):PAGE229',
 PHYS_PAGE='242',
 XY='(2800,1850)',
 ROT='0',
 VER='2',
 PACK_TYPE='0402LF',
 LOCATION='PR4526',
 CDS_LIB='pure_quanta',
 CDS_PART_NAME='Q_RES_0402LF-10M,1%,1/16W,EMPTA',
 WATTAGE='1/16W',
 TOLERANCE='1%',
 MATERIAL='EMPTY',
 ROOM='SCM_P12V_BOM1',
 VALUE='10M',
 PRIM_FILE='./archive_libs/logical/q_res/chips/chips.prt';

PART_NAME
 PR4527 'Q_RES_0402LF-10M,1%,1/16W,CHIPA':
 ROOM='E1S1_P3V3_BOM1';

SECTION_NUMBER 1
 '@S9S_MB_2U_LIB.S9S_MB_2U(SCH_1):PAGE324_I43@PURE_QUANTA.Q_RES(CHIPS)':
 C_PATH='@s9s_mb_2u_lib.s9s_mb_2u(sch_1):page324_i43@pure_quanta.q_res(chips)',
 P_PATH='@s9s_mb_2u_lib.s9s_mb_2u(sch_1):page192_i43@pure_quanta.q_res(chips)',
 PATH='I43',
 DRAWING='@S9S_MB_2U_LIB.S9S_MB_2U(SCH_1):PAGE324',
 PHYS_PAGE='192',
 XY='(2550,-1500)',
 ROT='0',
 VER='2',
 PACK_TYPE='0402LF',
 LOCATION='PR4527',
 CDS_LIB='pure_quanta',
 CDS_PART_NAME='Q_RES_0402LF-10M,1%,1/16W,CHIPA',
 WATTAGE='1/16W',
 TOLERANCE='1%',
 MATERIAL='CHIP',
 ROOM='E1S1_P3V3_BOM1',
 VALUE='10M',
 PRIM_FILE='./archive_libs/logical/q_res/chips/chips.prt';

PART_NAME
 PR4528 'Q_RES_0402LF-10M,1%,1/16W,EMPTA':
 ROOM='E1S1_P12V_MAM_MAM_BOM1';

SECTION_NUMBER 1
 '@S9S_MB_2U_LIB.S9S_MB_2U(SCH_1):PAGE324_I70@PURE_QUANTA.Q_RES(CHIPS)':
 C_PATH='@s9s_mb_2u_lib.s9s_mb_2u(sch_1):page324_i70@pure_quanta.q_res(chips)',
 P_PATH='@s9s_mb_2u_lib.s9s_mb_2u(sch_1):page192_i70@pure_quanta.q_res(chips)',
 PATH='I70',
 DRAWING='@S9S_MB_2U_LIB.S9S_MB_2U(SCH_1):PAGE324',
 ROOM1='E1S1_P12V_MAM_TIC_BOM2',
 PHYS_PAGE='192',
 XY='(2575,1250)',
 ROT='0',
 VER='2',
 PACK_TYPE='0402LF',
 LOCATION='PR4528',
 CDS_LIB='pure_quanta',
 CDS_PART_NAME='Q_RES_0402LF-10M,1%,1/16W,EMPTA',
 WATTAGE='1/16W',
 TOLERANCE='1%',
 MATERIAL='EMPTY',
 ROOM='E1S1_P12V_MAM_MAM_BOM1',
 VALUE='10M',
 PRIM_FILE='./archive_libs/logical/q_res/chips/chips.prt';

PART_NAME
 PR4540 'Q_RES_0402LF-20K,1%,1/16W,CHIPA':
 ROOM='SCM_P12V_BOM2';

SECTION_NUMBER 1
 '@S9S_MB_2U_LIB.S9S_MB_2U(SCH_1):PAGE229_I12@PURE_QUANTA.Q_RES(CHIPS)':
 C_PATH='@s9s_mb_2u_lib.s9s_mb_2u(sch_1):page229_i12@pure_quanta.q_res(chips)',
 P_PATH='@s9s_mb_2u_lib.s9s_mb_2u(sch_1):page242_i12@pure_quanta.q_res(chips)',
 PATH='I12',
 DRAWING='@S9S_MB_2U_LIB.S9S_MB_2U(SCH_1):PAGE229',
 PHYS_PAGE='242',
 XY='(-250,-1850)',
 ROT='0',
 VER='2',
 PACK_TYPE='0402LF',
 LOCATION='PR4540',
 CDS_LIB='pure_quanta',
 CDS_PART_NAME='Q_RES_0402LF-20K,1%,1/16W,CHIPA',
 WATTAGE='1/16W',
 TOLERANCE='1%',
 MATERIAL='CHIP',
 ROOM='SCM_P12V_BOM2',
 VALUE='20K',
 PRIM_FILE='./archive_libs/logical/q_res/chips/chips.prt';

PART_NAME
 PR4541 'Q_RES_0402LF-20K,1%,1/16W,CHIPA':
 ROOM='E1S1_P12V_MPS_MAM_BOM3';

SECTION_NUMBER 1
 '@S9S_MB_2U_LIB.S9S_MB_2U(SCH_1):PAGE323_I43@PURE_QUANTA.Q_RES(CHIPS)':
 C_PATH='@s9s_mb_2u_lib.s9s_mb_2u(sch_1):page323_i43@pure_quanta.q_res(chips)',
 P_PATH='@s9s_mb_2u_lib.s9s_mb_2u(sch_1):page193_i43@pure_quanta.q_res(chips)',
 PATH='I43',
 DRAWING='@S9S_MB_2U_LIB.S9S_MB_2U(SCH_1):PAGE323',
 ROOM1='E1S1_P12V_MPS_TIC_BOM4',
 PHYS_PAGE='193',
 XY='(-1425,600)',
 ROT='0',
 VER='2',
 PACK_TYPE='0402LF',
 LOCATION='PR4541',
 CDS_LIB='pure_quanta',
 CDS_PART_NAME='Q_RES_0402LF-20K,1%,1/16W,CHIPA',
 WATTAGE='1/16W',
 TOLERANCE='1%',
 MATERIAL='CHIP',
 ROOM='E1S1_P12V_MPS_MAM_BOM3',
 VALUE='20K',
 PRIM_FILE='./archive_libs/logical/q_res/chips/chips.prt';

PART_NAME
 PR4683 'Q_RES_0402LF-0,5%,1/16W,CHIP,CA':;

SECTION_NUMBER 1
 '@S9S_MB_2U_LIB.S9S_MB_2U(SCH_1):PAGE268_I41@PURE_QUANTA.Q_RES(CHIPS)':
 C_PATH='@s9s_mb_2u_lib.s9s_mb_2u(sch_1):page268_i41@pure_quanta.q_res(chips)',
 P_PATH='@s9s_mb_2u_lib.s9s_mb_2u(sch_1):page282_i41@pure_quanta.q_res(chips)',
 PATH='I41',
 DRAWING='@S9S_MB_2U_LIB.S9S_MB_2U(SCH_1):PAGE268',
 PHYS_PAGE='282',
 XY='(-2075,9000)',
 ROT='0',
 VER='1',
 PACK_TYPE='0402LF',
 LOCATION='PR4683',
 CDS_LIB='pure_quanta',
 CDS_PART_NAME='Q_RES_0402LF-0,5%,1/16W,CHIP,CA',
 WATTAGE='1/16W',
 TOLERANCE='5%',
 MATERIAL='CHIP',
 VALUE='0',
 PRIM_FILE='./archive_libs/logical/q_res/chips/chips.prt';

PART_NAME
 PR4698 'Q_RES_0402LF-0,5%,1/16W,EMPTY,A':;

SECTION_NUMBER 1
 '@S9S_MB_2U_LIB.S9S_MB_2U(SCH_1):PAGE268_I40@PURE_QUANTA.Q_RES(CHIPS)':
 C_PATH='@s9s_mb_2u_lib.s9s_mb_2u(sch_1):page268_i40@pure_quanta.q_res(chips)',
 P_PATH='@s9s_mb_2u_lib.s9s_mb_2u(sch_1):page282_i40@pure_quanta.q_res(chips)',
 PATH='I40',
 DRAWING='@S9S_MB_2U_LIB.S9S_MB_2U(SCH_1):PAGE268',
 PHYS_PAGE='282',
 XY='(-2075,8750)',
 ROT='0',
 VER='1',
 PACK_TYPE='0402LF',
 LOCATION='PR4698',
 CDS_LIB='pure_quanta',
 CDS_PART_NAME='Q_RES_0402LF-0,5%,1/16W,EMPTY,A',
 WATTAGE='1/16W',
 TOLERANCE='5%',
 MATERIAL='EMPTY',
 VALUE='0',
 PRIM_FILE='./archive_libs/logical/q_res/chips/chips.prt';

PART_NAME
 PR4699 'Q_RES_0402LF-0,5%,1/16W,CHIP,CA':;

SECTION_NUMBER 1
 '@S9S_MB_2U_LIB.S9S_MB_2U(SCH_1):PAGE286_I43@PURE_QUANTA.Q_RES(CHIPS)':
 C_PATH='@s9s_mb_2u_lib.s9s_mb_2u(sch_1):page286_i43@pure_quanta.q_res(chips)',
 P_PATH='@s9s_mb_2u_lib.s9s_mb_2u(sch_1):page300_i43@pure_quanta.q_res(chips)',
 PATH='I43',
 DRAWING='@S9S_MB_2U_LIB.S9S_MB_2U(SCH_1):PAGE286',
 PHYS_PAGE='300',
 XY='(9400,6375)',
 ROT='0',
 VER='1',
 PACK_TYPE='0402LF',
 LOCATION='PR4699',
 CDS_LIB='pure_quanta',
 CDS_PART_NAME='Q_RES_0402LF-0,5%,1/16W,CHIP,CA',
 WATTAGE='1/16W',
 TOLERANCE='5%',
 MATERIAL='CHIP',
 VALUE='0',
 PRIM_FILE='./archive_libs/logical/q_res/chips/chips.prt';

PART_NAME
 PR4700 'Q_RES_0402LF-0,5%,1/16W,EMPTY,A':;

SECTION_NUMBER 1
 '@S9S_MB_2U_LIB.S9S_MB_2U(SCH_1):PAGE286_I42@PURE_QUANTA.Q_RES(CHIPS)':
 C_PATH='@s9s_mb_2u_lib.s9s_mb_2u(sch_1):page286_i42@pure_quanta.q_res(chips)',
 P_PATH='@s9s_mb_2u_lib.s9s_mb_2u(sch_1):page300_i42@pure_quanta.q_res(chips)',
 PATH='I42',
 DRAWING='@S9S_MB_2U_LIB.S9S_MB_2U(SCH_1):PAGE286',
 PHYS_PAGE='300',
 XY='(9400,6125)',
 ROT='0',
 VER='1',
 PACK_TYPE='0402LF',
 LOCATION='PR4700',
 CDS_LIB='pure_quanta',
 CDS_PART_NAME='Q_RES_0402LF-0,5%,1/16W,EMPTY,A',
 WATTAGE='1/16W',
 TOLERANCE='5%',
 MATERIAL='EMPTY',
 VALUE='0',
 PRIM_FILE='./archive_libs/logical/q_res/chips/chips.prt';

PART_NAME
 PR5481 'Q_RES_0402LF-4.53K,1%,1/16W,CHA':
 ROOM='NIC1_P3V3_BOM1';

SECTION_NUMBER 1
 '@S9S_MB_2U_LIB.S9S_MB_2U(SCH_1):PAGE153_I102@PURE_QUANTA.Q_RES(CHIPS)':
 C_PATH='@s9s_mb_2u_lib.s9s_mb_2u(sch_1):page153_i102@pure_quanta.q_res(chips)',
 P_PATH='@s9s_mb_2u_lib.s9s_mb_2u(sch_1):page156_i102@pure_quanta.q_res(chips)',
 PATH='I102',
 DRAWING='@S9S_MB_2U_LIB.S9S_MB_2U(SCH_1):PAGE153',
 PHYS_PAGE='156',
 XY='(8600,12450)',
 ROT='0',
 VER='2',
 PACK_TYPE='0402LF',
 CDS_LIB='pure_quanta',
 CDS_PART_NAME='Q_RES_0402LF-4.53K,1%,1/16W,CHA',
 WATTAGE='1/16W',
 TOLERANCE='1%',
 MATERIAL='CHIP',
 ROOM='NIC1_P3V3_BOM1',
 VALUE='4.53K',
 PRIM_FILE='./archive_libs/logical/q_res/chips/chips.prt';

PART_NAME
 PR5484 'Q_RES_0402LF-30.1K,1%,1/16W,EMA':
 ROOM='NIC1_P12V_MAM_MAM_BOM1';

SECTION_NUMBER 1
 '@S9S_MB_2U_LIB.S9S_MB_2U(SCH_1):PAGE153_I49@PURE_QUANTA.Q_RES(CHIPS)':
 C_PATH='@s9s_mb_2u_lib.s9s_mb_2u(sch_1):page153_i49@pure_quanta.q_res(chips)',
 P_PATH='@s9s_mb_2u_lib.s9s_mb_2u(sch_1):page156_i49@pure_quanta.q_res(chips)',
 PATH='I49',
 DRAWING='@S9S_MB_2U_LIB.S9S_MB_2U(SCH_1):PAGE153',
 ROOM1='NIC1_P12V_MAM_TIC_BOM2',
 PHYS_PAGE='156',
 XY='(6775,10200)',
 ROT='0',
 VER='2',
 PACK_TYPE='0402LF',
 CDS_LIB='pure_quanta',
 CDS_PART_NAME='Q_RES_0402LF-30.1K,1%,1/16W,EMA',
 WATTAGE='1/16W',
 TOLERANCE='1%',
 MATERIAL='EMPTY',
 ROOM='NIC1_P12V_MAM_MAM_BOM1',
 VALUE='30.1K',
 PRIM_FILE='./archive_libs/logical/q_res/chips/chips.prt';

PART_NAME
 PU5 'ISL69260IRAZT-ISL69260IRAZ-T,SA':;

SECTION_NUMBER 1
 '@S9S_MB_2U_LIB.S9S_MB_2U(SCH_1):PAGE260_I65@PURE_QUANTA.ISL69260IRAZT(CHIPS)':
 C_PATH='@s9s_mb_2u_lib.s9s_mb_2u(sch_1):page260_i65@pure_quanta.isl69260irazt(c~
hips)',
 P_PATH='@s9s_mb_2u_lib.s9s_mb_2u(sch_1):page274_i65@pure_quanta.isl69260irazt(c~
hips)',
 PATH='I65',
 DRAWING='@S9S_MB_2U_LIB.S9S_MB_2U(SCH_1):PAGE260',
 PHYS_PAGE='274',
 XY='(-6825,4825)',
 ROT='0',
 VER='1',
 LOCATION='PU5',
 CDS_LIB='pure_quanta',
 CDS_PART_NAME='ISL69260IRAZT-ISL69260IRAZ-T,SA',
 PART_TYPE='SMLF',
 MATERIAL='IC',
 VALUE='ISL69260IRAZ-T',
 PRIM_FILE='./archive_libs/logical/isl69260irazt/chips/chips.prt';

PART_NAME
 PU6_P0_8 'ISL99390FRZTR5935-ISL99390FRZ-A':;

SECTION_NUMBER 1
 '@S9S_MB_2U_LIB.S9S_MB_2U(SCH_1):PAGE256_I2@PURE_QUANTA.ISL99390FRZTR5935(CHIPS)':
 C_PATH='@s9s_mb_2u_lib.s9s_mb_2u(sch_1):page256_i2@pure_quanta.isl99390frztr593~
5(chips)',
 P_PATH='@s9s_mb_2u_lib.s9s_mb_2u(sch_1):page270_i2@pure_quanta.isl99390frztr593~
5(chips)',
 PATH='I2',
 DRAWING='@S9S_MB_2U_LIB.S9S_MB_2U(SCH_1):PAGE256',
 PHYS_PAGE='270',
 XY='(-5625,-5400)',
 ROT='0',
 VER='1',
 LOCATION='PU6_P0_8',
 CDS_LIB='pure_quanta',
 CDS_PART_NAME='ISL99390FRZTR5935-ISL99390FRZ-A',
 PART_TYPE='SMLF',
 MATERIAL='IC',
 VALUE='ISL99390FRZ-TR5935',
 PRIM_FILE='./archive_libs/logical/isl99390frztr5935/chips/chips.prt';

PART_NAME
 PU7_P0_7 'ISL99390FRZTR5935-ISL99390FRZ-A':;

SECTION_NUMBER 1
 '@S9S_MB_2U_LIB.S9S_MB_2U(SCH_1):PAGE256_I32@PURE_QUANTA.ISL99390FRZTR5935(CHIPS)':
 C_PATH='@s9s_mb_2u_lib.s9s_mb_2u(sch_1):page256_i32@pure_quanta.isl99390frztr59~
35(chips)',
 P_PATH='@s9s_mb_2u_lib.s9s_mb_2u(sch_1):page270_i32@pure_quanta.isl99390frztr59~
35(chips)',
 PATH='I32',
 DRAWING='@S9S_MB_2U_LIB.S9S_MB_2U(SCH_1):PAGE256',
 PHYS_PAGE='270',
 XY='(-5600,-2575)',
 ROT='0',
 VER='1',
 LOCATION='PU7_P0_7',
 CDS_LIB='pure_quanta',
 CDS_PART_NAME='ISL99390FRZTR5935-ISL99390FRZ-A',
 PART_TYPE='SMLF',
 MATERIAL='IC',
 VALUE='ISL99390FRZ-TR5935',
 PRIM_FILE='./archive_libs/logical/isl99390frztr5935/chips/chips.prt';

PART_NAME
 PU8_P0_6 'ISL99390FRZTR5935-ISL99390FRZ-A':;

SECTION_NUMBER 1
 '@S9S_MB_2U_LIB.S9S_MB_2U(SCH_1):PAGE255_I12@PURE_QUANTA.ISL99390FRZTR5935(CHIPS)':
 C_PATH='@s9s_mb_2u_lib.s9s_mb_2u(sch_1):page255_i12@pure_quanta.isl99390frztr59~
35(chips)',
 P_PATH='@s9s_mb_2u_lib.s9s_mb_2u(sch_1):page269_i12@pure_quanta.isl99390frztr59~
35(chips)',
 PATH='I12',
 DRAWING='@S9S_MB_2U_LIB.S9S_MB_2U(SCH_1):PAGE255',
 PHYS_PAGE='269',
 XY='(3600,1900)',
 ROT='0',
 VER='1',
 LOCATION='PU8_P0_6',
 SEC='1',
 CDS_LIB='pure_quanta',
 CDS_PART_NAME='ISL99390FRZTR5935-ISL99390FRZ-A',
 SEC_TYPE='',
 PART_TYPE='SMLF',
 MATERIAL='IC',
 VALUE='ISL99390FRZ-TR5935',
 PRIM_FILE='./archive_libs/logical/isl99390frztr5935/chips/chips.prt';

PART_NAME
 PU9 'IR3889MTRPBF-IR3889MTRPBF,SMLFA':;

SECTION_NUMBER 1
 '@S9S_MB_2U_LIB.S9S_MB_2U(SCH_1):PAGE245_I95@PURE_QUANTA.IR3889MTRPBF(CHIPS)':
 C_PATH='@s9s_mb_2u_lib.s9s_mb_2u(sch_1):page245_i95@pure_quanta.ir3889mtrpbf(ch~
ips)',
 P_PATH='@s9s_mb_2u_lib.s9s_mb_2u(sch_1):page259_i95@pure_quanta.ir3889mtrpbf(ch~
ips)',
 PATH='I95',
 DRAWING='@S9S_MB_2U_LIB.S9S_MB_2U(SCH_1):PAGE245',
 PHYS_PAGE='259',
 XY='(-100,-750)',
 ROT='0',
 VER='1',
 LOCATION='PU9',
 SEC='1',
 CDS_LIB='pure_quanta',
 CDS_PART_NAME='IR3889MTRPBF-IR3889MTRPBF,SMLFA',
 SEC_TYPE='',
 PART_TYPE='SMLF',
 MATERIAL='IC',
 VALUE='IR3889MTRPBF',
 PRIM_FILE='./archive_libs/logical/ir3889mtrpbf/chips/chips.prt';

PART_NAME
 PU9_P0_5 'ISL99390FRZTR5935-ISL99390FRZ-A':;

SECTION_NUMBER 1
 '@S9S_MB_2U_LIB.S9S_MB_2U(SCH_1):PAGE255_I66@PURE_QUANTA.ISL99390FRZTR5935(CHIPS)':
 C_PATH='@s9s_mb_2u_lib.s9s_mb_2u(sch_1):page255_i66@pure_quanta.isl99390frztr59~
35(chips)',
 P_PATH='@s9s_mb_2u_lib.s9s_mb_2u(sch_1):page269_i66@pure_quanta.isl99390frztr59~
35(chips)',
 PATH='I66',
 DRAWING='@S9S_MB_2U_LIB.S9S_MB_2U(SCH_1):PAGE255',
 PHYS_PAGE='269',
 XY='(3625,4725)',
 ROT='0',
 VER='1',
 LOCATION='PU9_P0_5',
 CDS_LIB='pure_quanta',
 CDS_PART_NAME='ISL99390FRZTR5935-ISL99390FRZ-A',
 PART_TYPE='SMLF',
 MATERIAL='IC',
 VALUE='ISL99390FRZ-TR5935',
 PRIM_FILE='./archive_libs/logical/isl99390frztr5935/chips/chips.prt';

PART_NAME
 PU10_P0_4 'ISL99390FRZTR5935-ISL99390FRZ-A':;

SECTION_NUMBER 1
 '@S9S_MB_2U_LIB.S9S_MB_2U(SCH_1):PAGE254_I13@PURE_QUANTA.ISL99390FRZTR5935(CHIPS)':
 C_PATH='@s9s_mb_2u_lib.s9s_mb_2u(sch_1):page254_i13@pure_quanta.isl99390frztr59~
35(chips)',
 P_PATH='@s9s_mb_2u_lib.s9s_mb_2u(sch_1):page268_i13@pure_quanta.isl99390frztr59~
35(chips)',
 PATH='I13',
 DRAWING='@S9S_MB_2U_LIB.S9S_MB_2U(SCH_1):PAGE254',
 PHYS_PAGE='268',
 XY='(4525,1500)',
 ROT='0',
 VER='1',
 LOCATION='PU10_P0_4',
 CDS_LIB='pure_quanta',
 CDS_PART_NAME='ISL99390FRZTR5935-ISL99390FRZ-A',
 PART_TYPE='SMLF',
 MATERIAL='IC',
 VALUE='ISL99390FRZ-TR5935',
 PRIM_FILE='./archive_libs/logical/isl99390frztr5935/chips/chips.prt';

PART_NAME
 PU11_P0_3 'ISL99390FRZTR5935-ISL99390FRZ-A':;

SECTION_NUMBER 1
 '@S9S_MB_2U_LIB.S9S_MB_2U(SCH_1):PAGE254_I20@PURE_QUANTA.ISL99390FRZTR5935(CHIPS)':
 C_PATH='@s9s_mb_2u_lib.s9s_mb_2u(sch_1):page254_i20@pure_quanta.isl99390frztr59~
35(chips)',
 P_PATH='@s9s_mb_2u_lib.s9s_mb_2u(sch_1):page268_i20@pure_quanta.isl99390frztr59~
35(chips)',
 PATH='I20',
 DRAWING='@S9S_MB_2U_LIB.S9S_MB_2U(SCH_1):PAGE254',
 PHYS_PAGE='268',
 XY='(4550,4325)',
 ROT='0',
 VER='1',
 LOCATION='PU11_P0_3',
 CDS_LIB='pure_quanta',
 CDS_PART_NAME='ISL99390FRZTR5935-ISL99390FRZ-A',
 PART_TYPE='SMLF',
 MATERIAL='IC',
 VALUE='ISL99390FRZ-TR5935',
 PRIM_FILE='./archive_libs/logical/isl99390frztr5935/chips/chips.prt';

PART_NAME
 PU12_P0_2 'ISL99390FRZTR5935-ISL99390FRZ-A':;

SECTION_NUMBER 1
 '@S9S_MB_2U_LIB.S9S_MB_2U(SCH_1):PAGE253_I6@PURE_QUANTA.ISL99390FRZTR5935(CHIPS)':
 C_PATH='@s9s_mb_2u_lib.s9s_mb_2u(sch_1):page253_i6@pure_quanta.isl99390frztr593~
5(chips)',
 P_PATH='@s9s_mb_2u_lib.s9s_mb_2u(sch_1):page267_i6@pure_quanta.isl99390frztr593~
5(chips)',
 PATH='I6',
 DRAWING='@S9S_MB_2U_LIB.S9S_MB_2U(SCH_1):PAGE253',
 PHYS_PAGE='267',
 XY='(-2275,-2125)',
 ROT='0',
 VER='1',
 LOCATION='PU12_P0_2',
 SEC='1',
 CDS_LIB='pure_quanta',
 CDS_PART_NAME='ISL99390FRZTR5935-ISL99390FRZ-A',
 SEC_TYPE='',
 PART_TYPE='SMLF',
 MATERIAL='IC',
 VALUE='ISL99390FRZ-TR5935',
 PRIM_FILE='./archive_libs/logical/isl99390frztr5935/chips/chips.prt';

PART_NAME
 PU13_P0_1 'ISL99390FRZTR5935-ISL99390FRZ-A':;

SECTION_NUMBER 1
 '@S9S_MB_2U_LIB.S9S_MB_2U(SCH_1):PAGE253_I40@PURE_QUANTA.ISL99390FRZTR5935(CHIPS)':
 C_PATH='@s9s_mb_2u_lib.s9s_mb_2u(sch_1):page253_i40@pure_quanta.isl99390frztr59~
35(chips)',
 P_PATH='@s9s_mb_2u_lib.s9s_mb_2u(sch_1):page267_i40@pure_quanta.isl99390frztr59~
35(chips)',
 PATH='I40',
 DRAWING='@S9S_MB_2U_LIB.S9S_MB_2U(SCH_1):PAGE253',
 PHYS_PAGE='267',
 XY='(-2250,700)',
 ROT='0',
 VER='1',
 LOCATION='PU13_P0_1',
 CDS_LIB='pure_quanta',
 CDS_PART_NAME='ISL99390FRZTR5935-ISL99390FRZ-A',
 PART_TYPE='SMLF',
 MATERIAL='IC',
 VALUE='ISL99390FRZ-TR5935',
 PRIM_FILE='./archive_libs/logical/isl99390frztr5935/chips/chips.prt';

PART_NAME
 PU14 'RAA229126GNPHA0-RAA229126GNP#HA':;

SECTION_NUMBER 1
 '@S9S_MB_2U_LIB.S9S_MB_2U(SCH_1):PAGE252_I63@PURE_QUANTA.RAA229126GNPHA0(CHIPS)':
 C_PATH='@s9s_mb_2u_lib.s9s_mb_2u(sch_1):page252_i63@pure_quanta.raa229126gnpha0~
(chips)',
 P_PATH='@s9s_mb_2u_lib.s9s_mb_2u(sch_1):page266_i63@pure_quanta.raa229126gnpha0~
(chips)',
 PATH='I63',
 DRAWING='@S9S_MB_2U_LIB.S9S_MB_2U(SCH_1):PAGE252',
 PHYS_PAGE='266',
 XY='(-2725,3800)',
 ROT='0',
 VER='1',
 LOCATION='PU14',
 SEC='1',
 CDS_LIB='pure_quanta',
 CDS_PART_NAME='RAA229126GNPHA0-RAA229126GNP#HA',
 SEC_TYPE='',
 PART_TYPE='SMLF',
 MATERIAL='IC',
 VALUE='RAA229126GNP#HA0',
 PRIM_FILE='./archive_libs/logical/raa229126gnpha0/chips/chips.prt';

PART_NAME
 PU17 'ISL99390FRZTR5935-ISL99390FRZ-A':;

SECTION_NUMBER 1
 '@S9S_MB_2U_LIB.S9S_MB_2U(SCH_1):PAGE283_I10@PURE_QUANTA.ISL99390FRZTR5935(CHIPS)':
 C_PATH='@s9s_mb_2u_lib.s9s_mb_2u(sch_1):page283_i10@pure_quanta.isl99390frztr59~
35(chips)',
 P_PATH='@s9s_mb_2u_lib.s9s_mb_2u(sch_1):page297_i10@pure_quanta.isl99390frztr59~
35(chips)',
 PATH='I10',
 DRAWING='@S9S_MB_2U_LIB.S9S_MB_2U(SCH_1):PAGE283',
 PHYS_PAGE='297',
 XY='(-6525,3625)',
 ROT='0',
 VER='1',
 LOCATION='PU17',
 SEC='1',
 CDS_LIB='pure_quanta',
 CDS_PART_NAME='ISL99390FRZTR5935-ISL99390FRZ-A',
 SEC_TYPE='',
 PART_TYPE='SMLF',
 MATERIAL='IC',
 VALUE='ISL99390FRZ-TR5935',
 PRIM_FILE='./archive_libs/logical/isl99390frztr5935/chips/chips.prt';

PART_NAME
 PU18 'ISL69260IRAZT-ISL69260IRAZ-T,SA':;

SECTION_NUMBER 1
 '@S9S_MB_2U_LIB.S9S_MB_2U(SCH_1):PAGE282_I53@PURE_QUANTA.ISL69260IRAZT(CHIPS)':
 C_PATH='@s9s_mb_2u_lib.s9s_mb_2u(sch_1):page282_i53@pure_quanta.isl69260irazt(c~
hips)',
 P_PATH='@s9s_mb_2u_lib.s9s_mb_2u(sch_1):page296_i53@pure_quanta.isl69260irazt(c~
hips)',
 PATH='I53',
 DRAWING='@S9S_MB_2U_LIB.S9S_MB_2U(SCH_1):PAGE282',
 PHYS_PAGE='296',
 XY='(-2950,2700)',
 ROT='0',
 VER='1',
 LOCATION='PU18',
 CDS_LIB='pure_quanta',
 CDS_PART_NAME='ISL69260IRAZT-ISL69260IRAZ-T,SA',
 PART_TYPE='SMLF',
 MATERIAL='IC',
 VALUE='ISL69260IRAZ-T',
 PRIM_FILE='./archive_libs/logical/isl69260irazt/chips/chips.prt';

PART_NAME
 PU22 'ISL69260IRAZT-ISL69260IRAZ-T,SA':;

SECTION_NUMBER 1
 '@S9S_MB_2U_LIB.S9S_MB_2U(SCH_1):PAGE278_I38@PURE_QUANTA.ISL69260IRAZT(CHIPS)':
 C_PATH='@s9s_mb_2u_lib.s9s_mb_2u(sch_1):page278_i38@pure_quanta.isl69260irazt(c~
hips)',
 P_PATH='@s9s_mb_2u_lib.s9s_mb_2u(sch_1):page292_i38@pure_quanta.isl69260irazt(c~
hips)',
 PATH='I38',
 DRAWING='@S9S_MB_2U_LIB.S9S_MB_2U(SCH_1):PAGE278',
 PHYS_PAGE='292',
 XY='(3550,6400)',
 ROT='0',
 VER='1',
 LOCATION='PU22',
 CDS_LIB='pure_quanta',
 CDS_PART_NAME='ISL69260IRAZT-ISL69260IRAZ-T,SA',
 PART_TYPE='SMLF',
 MATERIAL='IC',
 VALUE='ISL69260IRAZ-T',
 PRIM_FILE='./archive_libs/logical/isl69260irazt/chips/chips.prt';

PART_NAME
 PU23_P1_8 'ISL99390FRZTR5935-ISL99390FRZ-A':;

SECTION_NUMBER 1
 '@S9S_MB_2U_LIB.S9S_MB_2U(SCH_1):PAGE274_I11@PURE_QUANTA.ISL99390FRZTR5935(CHIPS)':
 C_PATH='@s9s_mb_2u_lib.s9s_mb_2u(sch_1):page274_i11@pure_quanta.isl99390frztr59~
35(chips)',
 P_PATH='@s9s_mb_2u_lib.s9s_mb_2u(sch_1):page288_i11@pure_quanta.isl99390frztr59~
35(chips)',
 PATH='I11',
 DRAWING='@S9S_MB_2U_LIB.S9S_MB_2U(SCH_1):PAGE274',
 PHYS_PAGE='288',
 XY='(-6025,1700)',
 ROT='0',
 VER='1',
 LOCATION='PU23_P1_8',
 CDS_LIB='pure_quanta',
 CDS_PART_NAME='ISL99390FRZTR5935-ISL99390FRZ-A',
 PART_TYPE='SMLF',
 MATERIAL='IC',
 VALUE='ISL99390FRZ-TR5935',
 PRIM_FILE='./archive_libs/logical/isl99390frztr5935/chips/chips.prt';

PART_NAME
 PU24_P1_7 'ISL99390FRZTR5935-ISL99390FRZ-A':;

SECTION_NUMBER 1
 '@S9S_MB_2U_LIB.S9S_MB_2U(SCH_1):PAGE274_I20@PURE_QUANTA.ISL99390FRZTR5935(CHIPS)':
 C_PATH='@s9s_mb_2u_lib.s9s_mb_2u(sch_1):page274_i20@pure_quanta.isl99390frztr59~
35(chips)',
 P_PATH='@s9s_mb_2u_lib.s9s_mb_2u(sch_1):page288_i20@pure_quanta.isl99390frztr59~
35(chips)',
 PATH='I20',
 DRAWING='@S9S_MB_2U_LIB.S9S_MB_2U(SCH_1):PAGE274',
 PHYS_PAGE='288',
 XY='(-6000,4525)',
 ROT='0',
 VER='1',
 LOCATION='PU24_P1_7',
 CDS_LIB='pure_quanta',
 CDS_PART_NAME='ISL99390FRZTR5935-ISL99390FRZ-A',
 PART_TYPE='SMLF',
 MATERIAL='IC',
 VALUE='ISL99390FRZ-TR5935',
 PRIM_FILE='./archive_libs/logical/isl99390frztr5935/chips/chips.prt';

PART_NAME
 PU25_P1_6 'ISL99390FRZTR5935-ISL99390FRZ-A':;

SECTION_NUMBER 1
 '@S9S_MB_2U_LIB.S9S_MB_2U(SCH_1):PAGE273_I16@PURE_QUANTA.ISL99390FRZTR5935(CHIPS)':
 C_PATH='@s9s_mb_2u_lib.s9s_mb_2u(sch_1):page273_i16@pure_quanta.isl99390frztr59~
35(chips)',
 P_PATH='@s9s_mb_2u_lib.s9s_mb_2u(sch_1):page287_i16@pure_quanta.isl99390frztr59~
35(chips)',
 PATH='I16',
 DRAWING='@S9S_MB_2U_LIB.S9S_MB_2U(SCH_1):PAGE273',
 PHYS_PAGE='287',
 XY='(5300,-325)',
 ROT='0',
 VER='1',
 LOCATION='PU25_P1_6',
 CDS_LIB='pure_quanta',
 CDS_PART_NAME='ISL99390FRZTR5935-ISL99390FRZ-A',
 PART_TYPE='SMLF',
 MATERIAL='IC',
 VALUE='ISL99390FRZ-TR5935',
 PRIM_FILE='./archive_libs/logical/isl99390frztr5935/chips/chips.prt';

PART_NAME
 PU26_P1_5 'ISL99390FRZTR5935-ISL99390FRZ-A':;

SECTION_NUMBER 1
 '@S9S_MB_2U_LIB.S9S_MB_2U(SCH_1):PAGE273_I23@PURE_QUANTA.ISL99390FRZTR5935(CHIPS)':
 C_PATH='@s9s_mb_2u_lib.s9s_mb_2u(sch_1):page273_i23@pure_quanta.isl99390frztr59~
35(chips)',
 P_PATH='@s9s_mb_2u_lib.s9s_mb_2u(sch_1):page287_i23@pure_quanta.isl99390frztr59~
35(chips)',
 PATH='I23',
 DRAWING='@S9S_MB_2U_LIB.S9S_MB_2U(SCH_1):PAGE273',
 PHYS_PAGE='287',
 XY='(5325,2500)',
 ROT='0',
 VER='1',
 LOCATION='PU26_P1_5',
 CDS_LIB='pure_quanta',
 CDS_PART_NAME='ISL99390FRZTR5935-ISL99390FRZ-A',
 PART_TYPE='SMLF',
 MATERIAL='IC',
 VALUE='ISL99390FRZ-TR5935',
 PRIM_FILE='./archive_libs/logical/isl99390frztr5935/chips/chips.prt';

PART_NAME
 PU27_P1_4 'ISL99390FRZTR5935-ISL99390FRZ-A':;

SECTION_NUMBER 1
 '@S9S_MB_2U_LIB.S9S_MB_2U(SCH_1):PAGE272_I10@PURE_QUANTA.ISL99390FRZTR5935(CHIPS)':
 C_PATH='@s9s_mb_2u_lib.s9s_mb_2u(sch_1):page272_i10@pure_quanta.isl99390frztr59~
35(chips)',
 P_PATH='@s9s_mb_2u_lib.s9s_mb_2u(sch_1):page286_i10@pure_quanta.isl99390frztr59~
35(chips)',
 PATH='I10',
 DRAWING='@S9S_MB_2U_LIB.S9S_MB_2U(SCH_1):PAGE272',
 PHYS_PAGE='286',
 XY='(-850,-1550)',
 ROT='0',
 VER='1',
 LOCATION='PU27_P1_4',
 SEC='1',
 CDS_LIB='pure_quanta',
 CDS_PART_NAME='ISL99390FRZTR5935-ISL99390FRZ-A',
 SEC_TYPE='',
 PART_TYPE='SMLF',
 MATERIAL='IC',
 VALUE='ISL99390FRZ-TR5935',
 PRIM_FILE='./archive_libs/logical/isl99390frztr5935/chips/chips.prt';

PART_NAME
 PU28_P1_3 'ISL99390FRZTR5935-ISL99390FRZ-A':;

SECTION_NUMBER 1
 '@S9S_MB_2U_LIB.S9S_MB_2U(SCH_1):PAGE272_I66@PURE_QUANTA.ISL99390FRZTR5935(CHIPS)':
 C_PATH='@s9s_mb_2u_lib.s9s_mb_2u(sch_1):page272_i66@pure_quanta.isl99390frztr59~
35(chips)',
 P_PATH='@s9s_mb_2u_lib.s9s_mb_2u(sch_1):page286_i66@pure_quanta.isl99390frztr59~
35(chips)',
 PATH='I66',
 DRAWING='@S9S_MB_2U_LIB.S9S_MB_2U(SCH_1):PAGE272',
 PHYS_PAGE='286',
 XY='(-825,1275)',
 ROT='0',
 VER='1',
 LOCATION='PU28_P1_3',
 CDS_LIB='pure_quanta',
 CDS_PART_NAME='ISL99390FRZTR5935-ISL99390FRZ-A',
 PART_TYPE='SMLF',
 MATERIAL='IC',
 VALUE='ISL99390FRZ-TR5935',
 PRIM_FILE='./archive_libs/logical/isl99390frztr5935/chips/chips.prt';

PART_NAME
 PU29 'RAA229126GNPHA0-RAA229126GNP#HA':;

SECTION_NUMBER 1
 '@S9S_MB_2U_LIB.S9S_MB_2U(SCH_1):PAGE270_I33@PURE_QUANTA.RAA229126GNPHA0(CHIPS)':
 C_PATH='@s9s_mb_2u_lib.s9s_mb_2u(sch_1):page270_i33@pure_quanta.raa229126gnpha0~
(chips)',
 P_PATH='@s9s_mb_2u_lib.s9s_mb_2u(sch_1):page284_i33@pure_quanta.raa229126gnpha0~
(chips)',
 PATH='I33',
 DRAWING='@S9S_MB_2U_LIB.S9S_MB_2U(SCH_1):PAGE270',
 PHYS_PAGE='284',
 XY='(225,275)',
 ROT='0',
 VER='1',
 LOCATION='PU29',
 SEC='1',
 CDS_LIB='pure_quanta',
 CDS_PART_NAME='RAA229126GNPHA0-RAA229126GNP#HA',
 SEC_TYPE='',
 PART_TYPE='SMLF',
 MATERIAL='IC',
 VALUE='RAA229126GNP#HA0',
 PRIM_FILE='./archive_libs/logical/raa229126gnpha0/chips/chips.prt';

PART_NAME
 PU30_P1_2 'ISL99390FRZTR5935-ISL99390FRZ-A':;

SECTION_NUMBER 1
 '@S9S_MB_2U_LIB.S9S_MB_2U(SCH_1):PAGE271_I7@PURE_QUANTA.ISL99390FRZTR5935(CHIPS)':
 C_PATH='@s9s_mb_2u_lib.s9s_mb_2u(sch_1):page271_i7@pure_quanta.isl99390frztr593~
5(chips)',
 P_PATH='@s9s_mb_2u_lib.s9s_mb_2u(sch_1):page285_i7@pure_quanta.isl99390frztr593~
5(chips)',
 PATH='I7',
 DRAWING='@S9S_MB_2U_LIB.S9S_MB_2U(SCH_1):PAGE271',
 PHYS_PAGE='285',
 XY='(-2125,-1700)',
 ROT='0',
 VER='1',
 LOCATION='PU30_P1_2',
 CDS_LIB='pure_quanta',
 CDS_PART_NAME='ISL99390FRZTR5935-ISL99390FRZ-A',
 PART_TYPE='SMLF',
 MATERIAL='IC',
 VALUE='ISL99390FRZ-TR5935',
 PRIM_FILE='./archive_libs/logical/isl99390frztr5935/chips/chips.prt';

PART_NAME
 PU31_P1_1 'ISL99390FRZTR5935-ISL99390FRZ-A':;

SECTION_NUMBER 1
 '@S9S_MB_2U_LIB.S9S_MB_2U(SCH_1):PAGE271_I40@PURE_QUANTA.ISL99390FRZTR5935(CHIPS)':
 C_PATH='@s9s_mb_2u_lib.s9s_mb_2u(sch_1):page271_i40@pure_quanta.isl99390frztr59~
35(chips)',
 P_PATH='@s9s_mb_2u_lib.s9s_mb_2u(sch_1):page285_i40@pure_quanta.isl99390frztr59~
35(chips)',
 PATH='I40',
 DRAWING='@S9S_MB_2U_LIB.S9S_MB_2U(SCH_1):PAGE271',
 PHYS_PAGE='285',
 XY='(-2100,1125)',
 ROT='0',
 VER='1',
 LOCATION='PU31_P1_1',
 CDS_LIB='pure_quanta',
 CDS_PART_NAME='ISL99390FRZTR5935-ISL99390FRZ-A',
 PART_TYPE='SMLF',
 MATERIAL='IC',
 VALUE='ISL99390FRZ-TR5935',
 PRIM_FILE='./archive_libs/logical/isl99390frztr5935/chips/chips.prt';

PART_NAME
 PU35 'ISL69260IRAZT-ISL69260IRAZ-T,SA':;

SECTION_NUMBER 1
 '@S9S_MB_2U_LIB.S9S_MB_2U(SCH_1):PAGE264_I53@PURE_QUANTA.ISL69260IRAZT(CHIPS)':
 C_PATH='@s9s_mb_2u_lib.s9s_mb_2u(sch_1):page264_i53@pure_quanta.isl69260irazt(c~
hips)',
 P_PATH='@s9s_mb_2u_lib.s9s_mb_2u(sch_1):page278_i53@pure_quanta.isl69260irazt(c~
hips)',
 PATH='I53',
 DRAWING='@S9S_MB_2U_LIB.S9S_MB_2U(SCH_1):PAGE264',
 PHYS_PAGE='278',
 XY='(-7475,6200)',
 ROT='0',
 VER='1',
 LOCATION='PU35',
 CDS_LIB='pure_quanta',
 CDS_PART_NAME='ISL69260IRAZT-ISL69260IRAZ-T,SA',
 PART_TYPE='SMLF',
 MATERIAL='IC',
 VALUE='ISL69260IRAZ-T',
 PRIM_FILE='./archive_libs/logical/isl69260irazt/chips/chips.prt';

PART_NAME
 PU36 'ISL99390FRZTR5935-ISL99390FRZ-A':;

SECTION_NUMBER 1
 '@S9S_MB_2U_LIB.S9S_MB_2U(SCH_1):PAGE265_I8@PURE_QUANTA.ISL99390FRZTR5935(CHIPS)':
 C_PATH='@s9s_mb_2u_lib.s9s_mb_2u(sch_1):page265_i8@pure_quanta.isl99390frztr593~
5(chips)',
 P_PATH='@s9s_mb_2u_lib.s9s_mb_2u(sch_1):page279_i8@pure_quanta.isl99390frztr593~
5(chips)',
 PATH='I8',
 DRAWING='@S9S_MB_2U_LIB.S9S_MB_2U(SCH_1):PAGE265',
 PHYS_PAGE='279',
 XY='(-6700,1925)',
 ROT='0',
 VER='1',
 LOCATION='PU36',
 SEC='1',
 CDS_LIB='pure_quanta',
 CDS_PART_NAME='ISL99390FRZTR5935-ISL99390FRZ-A',
 SEC_TYPE='',
 PART_TYPE='SMLF',
 MATERIAL='IC',
 VALUE='ISL99390FRZ-TR5935',
 PRIM_FILE='./archive_libs/logical/isl99390frztr5935/chips/chips.prt';

PART_NAME
 PU42 'RAA2213404GNPHB0-RAA2213404GNPA':;

SECTION_NUMBER 1
 '@S9S_MB_2U_LIB.S9S_MB_2U(SCH_1):PAGE262_I14@PURE_QUANTA.RAA2213404GNPHB0(CHIPS)':
 C_PATH='@s9s_mb_2u_lib.s9s_mb_2u(sch_1):page262_i14@pure_quanta.raa2213404gnphb~
0(chips)',
 P_PATH='@s9s_mb_2u_lib.s9s_mb_2u(sch_1):page276_i14@pure_quanta.raa2213404gnphb~
0(chips)',
 PATH='I14',
 DRAWING='@S9S_MB_2U_LIB.S9S_MB_2U(SCH_1):PAGE262',
 PHYS_PAGE='276',
 XY='(-8100,3575)',
 ROT='0',
 VER='1',
 LOCATION='PU42',
 CDS_LIB='pure_quanta',
 CDS_PART_NAME='RAA2213404GNPHB0-RAA2213404GNPA',
 PART_TYPE='SMLF',
 MATERIAL='IC',
 VALUE='RAA2213404GNP#HB0',
 PRIM_FILE='./archive_libs/logical/raa2213404gnphb0/chips/chips.prt';

PART_NAME
 PU43_P0_1 'ISL99390FRZTR5935-ISL99390FRZ-A':;

SECTION_NUMBER 1
 '@S9S_MB_2U_LIB.S9S_MB_2U(SCH_1):PAGE261_I79@PURE_QUANTA.ISL99390FRZTR5935(CHIPS)':
 C_PATH='@s9s_mb_2u_lib.s9s_mb_2u(sch_1):page261_i79@pure_quanta.isl99390frztr59~
35(chips)',
 P_PATH='@s9s_mb_2u_lib.s9s_mb_2u(sch_1):page275_i79@pure_quanta.isl99390frztr59~
35(chips)',
 PATH='I79',
 DRAWING='@S9S_MB_2U_LIB.S9S_MB_2U(SCH_1):PAGE261',
 PHYS_PAGE='275',
 XY='(-8725,4775)',
 ROT='0',
 VER='1',
 LOCATION='PU43_P0_1',
 SEC='1',
 CDS_LIB='pure_quanta',
 CDS_PART_NAME='ISL99390FRZTR5935-ISL99390FRZ-A',
 SEC_TYPE='',
 PART_TYPE='SMLF',
 MATERIAL='IC',
 VALUE='ISL99390FRZ-TR5935',
 PRIM_FILE='./archive_libs/logical/isl99390frztr5935/chips/chips.prt';

PART_NAME
 PU44_P0_2 'ISL99390FRZTR5935-ISL99390FRZ-A':;

SECTION_NUMBER 1
 '@S9S_MB_2U_LIB.S9S_MB_2U(SCH_1):PAGE261_I12@PURE_QUANTA.ISL99390FRZTR5935(CHIPS)':
 C_PATH='@s9s_mb_2u_lib.s9s_mb_2u(sch_1):page261_i12@pure_quanta.isl99390frztr59~
35(chips)',
 P_PATH='@s9s_mb_2u_lib.s9s_mb_2u(sch_1):page275_i12@pure_quanta.isl99390frztr59~
35(chips)',
 PATH='I12',
 DRAWING='@S9S_MB_2U_LIB.S9S_MB_2U(SCH_1):PAGE261',
 PHYS_PAGE='275',
 XY='(-8875,1975)',
 ROT='0',
 VER='1',
 LOCATION='PU44_P0_2',
 SEC='1',
 CDS_LIB='pure_quanta',
 CDS_PART_NAME='ISL99390FRZTR5935-ISL99390FRZ-A',
 SEC_TYPE='',
 PART_TYPE='SMLF',
 MATERIAL='IC',
 VALUE='ISL99390FRZ-TR5935',
 PRIM_FILE='./archive_libs/logical/isl99390frztr5935/chips/chips.prt';

PART_NAME
 PU49 'RAA2213404GNPHB0-RAA2213404GNPA':;

SECTION_NUMBER 1
 '@S9S_MB_2U_LIB.S9S_MB_2U(SCH_1):PAGE280_I14@PURE_QUANTA.RAA2213404GNPHB0(CHIPS)':
 C_PATH='@s9s_mb_2u_lib.s9s_mb_2u(sch_1):page280_i14@pure_quanta.raa2213404gnphb~
0(chips)',
 P_PATH='@s9s_mb_2u_lib.s9s_mb_2u(sch_1):page294_i14@pure_quanta.raa2213404gnphb~
0(chips)',
 PATH='I14',
 DRAWING='@S9S_MB_2U_LIB.S9S_MB_2U(SCH_1):PAGE280',
 PHYS_PAGE='294',
 XY='(-4600,9225)',
 ROT='0',
 VER='1',
 LOCATION='PU49',
 CDS_LIB='pure_quanta',
 CDS_PART_NAME='RAA2213404GNPHB0-RAA2213404GNPA',
 PART_TYPE='SMLF',
 MATERIAL='IC',
 VALUE='RAA2213404GNP#HB0',
 PRIM_FILE='./archive_libs/logical/raa2213404gnphb0/chips/chips.prt';

PART_NAME
 PU50_P1_1 'ISL99390FRZTR5935-ISL99390FRZ-A':;

SECTION_NUMBER 1
 '@S9S_MB_2U_LIB.S9S_MB_2U(SCH_1):PAGE279_I38@PURE_QUANTA.ISL99390FRZTR5935(CHIPS)':
 C_PATH='@s9s_mb_2u_lib.s9s_mb_2u(sch_1):page279_i38@pure_quanta.isl99390frztr59~
35(chips)',
 P_PATH='@s9s_mb_2u_lib.s9s_mb_2u(sch_1):page293_i38@pure_quanta.isl99390frztr59~
35(chips)',
 PATH='I38',
 DRAWING='@S9S_MB_2U_LIB.S9S_MB_2U(SCH_1):PAGE279',
 PHYS_PAGE='293',
 XY='(-6975,11225)',
 ROT='0',
 VER='1',
 LOCATION='PU50_P1_1',
 SEC='1',
 CDS_LIB='pure_quanta',
 CDS_PART_NAME='ISL99390FRZTR5935-ISL99390FRZ-A',
 SEC_TYPE='',
 PART_TYPE='SMLF',
 MATERIAL='IC',
 VALUE='ISL99390FRZ-TR5935',
 PRIM_FILE='./archive_libs/logical/isl99390frztr5935/chips/chips.prt';

PART_NAME
 PU51_P1_2 'ISL99390FRZTR5935-ISL99390FRZ-A':;

SECTION_NUMBER 1
 '@S9S_MB_2U_LIB.S9S_MB_2U(SCH_1):PAGE279_I29@PURE_QUANTA.ISL99390FRZTR5935(CHIPS)':
 C_PATH='@s9s_mb_2u_lib.s9s_mb_2u(sch_1):page279_i29@pure_quanta.isl99390frztr59~
35(chips)',
 P_PATH='@s9s_mb_2u_lib.s9s_mb_2u(sch_1):page293_i29@pure_quanta.isl99390frztr59~
35(chips)',
 PATH='I29',
 DRAWING='@S9S_MB_2U_LIB.S9S_MB_2U(SCH_1):PAGE279',
 PHYS_PAGE='293',
 XY='(-6975,8425)',
 ROT='0',
 VER='1',
 LOCATION='PU51_P1_2',
 CDS_LIB='pure_quanta',
 CDS_PART_NAME='ISL99390FRZTR5935-ISL99390FRZ-A',
 PART_TYPE='SMLF',
 MATERIAL='IC',
 VALUE='ISL99390FRZ-TR5935',
 PRIM_FILE='./archive_libs/logical/isl99390frztr5935/chips/chips.prt';

PART_NAME
 PU69_P0_1 'ISL99390FRZTR5935-ISL99390FRZ-A':;

SECTION_NUMBER 1
 '@S9S_MB_2U_LIB.S9S_MB_2U(SCH_1):PAGE257_I25@PURE_QUANTA.ISL99390FRZTR5935(CHIPS)':
 C_PATH='@s9s_mb_2u_lib.s9s_mb_2u(sch_1):page257_i25@pure_quanta.isl99390frztr59~
35(chips)',
 P_PATH='@s9s_mb_2u_lib.s9s_mb_2u(sch_1):page271_i25@pure_quanta.isl99390frztr59~
35(chips)',
 PATH='I25',
 DRAWING='@S9S_MB_2U_LIB.S9S_MB_2U(SCH_1):PAGE257',
 PHYS_PAGE='271',
 XY='(-2725,5200)',
 ROT='0',
 VER='1',
 LOCATION='PU69_P0_1',
 CDS_LIB='pure_quanta',
 CDS_PART_NAME='ISL99390FRZTR5935-ISL99390FRZ-A',
 PART_TYPE='SMLF',
 MATERIAL='IC',
 VALUE='ISL99390FRZ-TR5935',
 PRIM_FILE='./archive_libs/logical/isl99390frztr5935/chips/chips.prt';

PART_NAME
 PU70_P0_2 'ISL99390FRZTR5935-ISL99390FRZ-A':;

SECTION_NUMBER 1
 '@S9S_MB_2U_LIB.S9S_MB_2U(SCH_1):PAGE257_I16@PURE_QUANTA.ISL99390FRZTR5935(CHIPS)':
 C_PATH='@s9s_mb_2u_lib.s9s_mb_2u(sch_1):page257_i16@pure_quanta.isl99390frztr59~
35(chips)',
 P_PATH='@s9s_mb_2u_lib.s9s_mb_2u(sch_1):page271_i16@pure_quanta.isl99390frztr59~
35(chips)',
 PATH='I16',
 DRAWING='@S9S_MB_2U_LIB.S9S_MB_2U(SCH_1):PAGE257',
 PHYS_PAGE='271',
 XY='(-2725,2400)',
 ROT='0',
 VER='1',
 LOCATION='PU70_P0_2',
 CDS_LIB='pure_quanta',
 CDS_PART_NAME='ISL99390FRZTR5935-ISL99390FRZ-A',
 PART_TYPE='SMLF',
 MATERIAL='IC',
 VALUE='ISL99390FRZ-TR5935',
 PRIM_FILE='./archive_libs/logical/isl99390frztr5935/chips/chips.prt';

PART_NAME
 PU71_P0_3 'ISL99390FRZTR5935-ISL99390FRZ-A':;

SECTION_NUMBER 1
 '@S9S_MB_2U_LIB.S9S_MB_2U(SCH_1):PAGE258_I82@PURE_QUANTA.ISL99390FRZTR5935(CHIPS)':
 C_PATH='@s9s_mb_2u_lib.s9s_mb_2u(sch_1):page258_i82@pure_quanta.isl99390frztr59~
35(chips)',
 P_PATH='@s9s_mb_2u_lib.s9s_mb_2u(sch_1):page272_i82@pure_quanta.isl99390frztr59~
35(chips)',
 PATH='I82',
 DRAWING='@S9S_MB_2U_LIB.S9S_MB_2U(SCH_1):PAGE258',
 PHYS_PAGE='272',
 XY='(-9175,4900)',
 ROT='0',
 VER='1',
 LOCATION='PU71_P0_3',
 CDS_LIB='pure_quanta',
 CDS_PART_NAME='ISL99390FRZTR5935-ISL99390FRZ-A',
 PART_TYPE='SMLF',
 MATERIAL='IC',
 VALUE='ISL99390FRZ-TR5935',
 PRIM_FILE='./archive_libs/logical/isl99390frztr5935/chips/chips.prt';

PART_NAME
 PU72_P0_4 'ISL99390FRZTR5935-ISL99390FRZ-A':;

SECTION_NUMBER 1
 '@S9S_MB_2U_LIB.S9S_MB_2U(SCH_1):PAGE258_I10@PURE_QUANTA.ISL99390FRZTR5935(CHIPS)':
 C_PATH='@s9s_mb_2u_lib.s9s_mb_2u(sch_1):page258_i10@pure_quanta.isl99390frztr59~
35(chips)',
 P_PATH='@s9s_mb_2u_lib.s9s_mb_2u(sch_1):page272_i10@pure_quanta.isl99390frztr59~
35(chips)',
 PATH='I10',
 DRAWING='@S9S_MB_2U_LIB.S9S_MB_2U(SCH_1):PAGE258',
 PHYS_PAGE='272',
 XY='(-9175,2100)',
 ROT='0',
 VER='1',
 LOCATION='PU72_P0_4',
 CDS_LIB='pure_quanta',
 CDS_PART_NAME='ISL99390FRZTR5935-ISL99390FRZ-A',
 PART_TYPE='SMLF',
 MATERIAL='IC',
 VALUE='ISL99390FRZ-TR5935',
 PRIM_FILE='./archive_libs/logical/isl99390frztr5935/chips/chips.prt';

PART_NAME
 PU73 'RS53319LR-RS53319LR,SMLF,IC,ALA':;

SECTION_NUMBER 1
 '@S9S_MB_2U_LIB.S9S_MB_2U(SCH_1):PAGE248_I11@PURE_QUANTA.RS53319LR(CHIPS)':
 C_PATH='@s9s_mb_2u_lib.s9s_mb_2u(sch_1):page248_i11@pure_quanta.rs53319lr(chips~
)',
 P_PATH='@s9s_mb_2u_lib.s9s_mb_2u(sch_1):page262_i11@pure_quanta.rs53319lr(chips~
)',
 PATH='I11',
 DRAWING='@S9S_MB_2U_LIB.S9S_MB_2U(SCH_1):PAGE248',
 PHYS_PAGE='262',
 XY='(-925,-525)',
 ROT='0',
 VER='1',
 LOCATION='PU73',
 SEC='1',
 CDS_LIB='pure_quanta',
 CDS_PART_NAME='RS53319LR-RS53319LR,SMLF,IC,ALA',
 SEC_TYPE='',
 PART_TYPE='SMLF',
 MATERIAL='IC',
 VALUE='RS53319LR',
 PRIM_FILE='./archive_libs/logical/rs53319lr/chips/chips.prt';

PART_NAME
 PU74 'NB682GDZ-NB682GD-Z,SMLF,IC,AL0A':;

SECTION_NUMBER 1
 '@S9S_MB_2U_LIB.S9S_MB_2U(SCH_1):PAGE249_I26@PURE_QUANTA.NB682GDZ(CHIPS)':
 C_PATH='@s9s_mb_2u_lib.s9s_mb_2u(sch_1):page249_i26@pure_quanta.nb682gdz(chips)~
',
 P_PATH='@s9s_mb_2u_lib.s9s_mb_2u(sch_1):page263_i26@pure_quanta.nb682gdz(chips)~
',
 PATH='I26',
 DRAWING='@S9S_MB_2U_LIB.S9S_MB_2U(SCH_1):PAGE249',
 PHYS_PAGE='263',
 XY='(-3150,6075)',
 ROT='0',
 VER='1',
 LOCATION='PU74',
 SEC='1',
 CDS_LIB='pure_quanta',
 CDS_PART_NAME='NB682GDZ-NB682GD-Z,SMLF,IC,AL0A',
 SEC_TYPE='',
 PART_TYPE='SMLF',
 MATERIAL='IC',
 VALUE='NB682GD-Z',
 PRIM_FILE='./archive_libs/logical/nb682gdz/chips/chips.prt';

PART_NAME
 PU75_P1_1 'ISL99390FRZTR5935-ISL99390FRZ-A':;

SECTION_NUMBER 1
 '@S9S_MB_2U_LIB.S9S_MB_2U(SCH_1):PAGE275_I89@PURE_QUANTA.ISL99390FRZTR5935(CHIPS)':
 C_PATH='@s9s_mb_2u_lib.s9s_mb_2u(sch_1):page275_i89@pure_quanta.isl99390frztr59~
35(chips)',
 P_PATH='@s9s_mb_2u_lib.s9s_mb_2u(sch_1):page289_i89@pure_quanta.isl99390frztr59~
35(chips)',
 PATH='I89',
 DRAWING='@S9S_MB_2U_LIB.S9S_MB_2U(SCH_1):PAGE275',
 PHYS_PAGE='289',
 XY='(-8725,4675)',
 ROT='0',
 VER='1',
 LOCATION='PU75_P1_1',
 CDS_LIB='pure_quanta',
 CDS_PART_NAME='ISL99390FRZTR5935-ISL99390FRZ-A',
 PART_TYPE='SMLF',
 MATERIAL='IC',
 VALUE='ISL99390FRZ-TR5935',
 PRIM_FILE='./archive_libs/logical/isl99390frztr5935/chips/chips.prt';

PART_NAME
 PU76_P1_2 'ISL99390FRZTR5935-ISL99390FRZ-A':;

SECTION_NUMBER 1
 '@S9S_MB_2U_LIB.S9S_MB_2U(SCH_1):PAGE275_I9@PURE_QUANTA.ISL99390FRZTR5935(CHIPS)':
 C_PATH='@s9s_mb_2u_lib.s9s_mb_2u(sch_1):page275_i9@pure_quanta.isl99390frztr593~
5(chips)',
 P_PATH='@s9s_mb_2u_lib.s9s_mb_2u(sch_1):page289_i9@pure_quanta.isl99390frztr593~
5(chips)',
 PATH='I9',
 DRAWING='@S9S_MB_2U_LIB.S9S_MB_2U(SCH_1):PAGE275',
 PHYS_PAGE='289',
 XY='(-8725,1875)',
 ROT='0',
 VER='1',
 LOCATION='PU76_P1_2',
 CDS_LIB='pure_quanta',
 CDS_PART_NAME='ISL99390FRZTR5935-ISL99390FRZ-A',
 PART_TYPE='SMLF',
 MATERIAL='IC',
 VALUE='ISL99390FRZ-TR5935',
 PRIM_FILE='./archive_libs/logical/isl99390frztr5935/chips/chips.prt';

PART_NAME
 PU77_P1_3 'ISL99390FRZTR5935-ISL99390FRZ-A':;

SECTION_NUMBER 1
 '@S9S_MB_2U_LIB.S9S_MB_2U(SCH_1):PAGE276_I24@PURE_QUANTA.ISL99390FRZTR5935(CHIPS)':
 C_PATH='@s9s_mb_2u_lib.s9s_mb_2u(sch_1):page276_i24@pure_quanta.isl99390frztr59~
35(chips)',
 P_PATH='@s9s_mb_2u_lib.s9s_mb_2u(sch_1):page290_i24@pure_quanta.isl99390frztr59~
35(chips)',
 PATH='I24',
 DRAWING='@S9S_MB_2U_LIB.S9S_MB_2U(SCH_1):PAGE276',
 PHYS_PAGE='290',
 XY='(-5800,6625)',
 ROT='0',
 VER='1',
 LOCATION='PU77_P1_3',
 CDS_LIB='pure_quanta',
 CDS_PART_NAME='ISL99390FRZTR5935-ISL99390FRZ-A',
 PART_TYPE='SMLF',
 MATERIAL='IC',
 VALUE='ISL99390FRZ-TR5935',
 PRIM_FILE='./archive_libs/logical/isl99390frztr5935/chips/chips.prt';

PART_NAME
 PU78_P1_4 'ISL99390FRZTR5935-ISL99390FRZ-A':;

SECTION_NUMBER 1
 '@S9S_MB_2U_LIB.S9S_MB_2U(SCH_1):PAGE276_I15@PURE_QUANTA.ISL99390FRZTR5935(CHIPS)':
 C_PATH='@s9s_mb_2u_lib.s9s_mb_2u(sch_1):page276_i15@pure_quanta.isl99390frztr59~
35(chips)',
 P_PATH='@s9s_mb_2u_lib.s9s_mb_2u(sch_1):page290_i15@pure_quanta.isl99390frztr59~
35(chips)',
 PATH='I15',
 DRAWING='@S9S_MB_2U_LIB.S9S_MB_2U(SCH_1):PAGE276',
 PHYS_PAGE='290',
 XY='(-5800,3825)',
 ROT='0',
 VER='1',
 LOCATION='PU78_P1_4',
 CDS_LIB='pure_quanta',
 CDS_PART_NAME='ISL99390FRZTR5935-ISL99390FRZ-A',
 PART_TYPE='SMLF',
 MATERIAL='IC',
 VALUE='ISL99390FRZ-TR5935',
 PRIM_FILE='./archive_libs/logical/isl99390frztr5935/chips/chips.prt';

PART_NAME
 PU79 'RS53318LR-RS53318LR,SMLF,IC,ALA':;

SECTION_NUMBER 1
 '@S9S_MB_2U_LIB.S9S_MB_2U(SCH_1):PAGE267_I19@PURE_QUANTA.RS53318LR(CHIPS)':
 C_PATH='@s9s_mb_2u_lib.s9s_mb_2u(sch_1):page267_i19@pure_quanta.rs53318lr(chips~
)',
 P_PATH='@s9s_mb_2u_lib.s9s_mb_2u(sch_1):page281_i19@pure_quanta.rs53318lr(chips~
)',
 PATH='I19',
 DRAWING='@S9S_MB_2U_LIB.S9S_MB_2U(SCH_1):PAGE267',
 PHYS_PAGE='281',
 XY='(-8625,3450)',
 ROT='0',
 VER='1',
 LOCATION='PU79',
 SEC='1',
 CDS_LIB='pure_quanta',
 CDS_PART_NAME='RS53318LR-RS53318LR,SMLF,IC,ALA',
 SEC_TYPE='',
 PART_TYPE='SMLF',
 MATERIAL='IC',
 VALUE='RS53318LR',
 PRIM_FILE='./archive_libs/logical/rs53318lr/chips/chips.prt';

PART_NAME
 PU80 'RS53318LR-RS53318LR,SMLF,IC,ALA':;

SECTION_NUMBER 1
 '@S9S_MB_2U_LIB.S9S_MB_2U(SCH_1):PAGE285_I25@PURE_QUANTA.RS53318LR(CHIPS)':
 C_PATH='@s9s_mb_2u_lib.s9s_mb_2u(sch_1):page285_i25@pure_quanta.rs53318lr(chips~
)',
 P_PATH='@s9s_mb_2u_lib.s9s_mb_2u(sch_1):page299_i25@pure_quanta.rs53318lr(chips~
)',
 PATH='I25',
 DRAWING='@S9S_MB_2U_LIB.S9S_MB_2U(SCH_1):PAGE285',
 PHYS_PAGE='299',
 XY='(-8000,3000)',
 ROT='0',
 VER='1',
 LOCATION='PU80',
 SEC='1',
 CDS_LIB='pure_quanta',
 CDS_PART_NAME='RS53318LR-RS53318LR,SMLF,IC,ALA',
 SEC_TYPE='',
 PART_TYPE='SMLF',
 MATERIAL='IC',
 VALUE='RS53318LR',
 PRIM_FILE='./archive_libs/logical/rs53318lr/chips/chips.prt';

PART_NAME
 PU81 'RS53317LR-RS53317LR,SMLF,IC,ALA':;

SECTION_NUMBER 1
 '@S9S_MB_2U_LIB.S9S_MB_2U(SCH_1):PAGE268_I22@PURE_QUANTA.RS53317LR(CHIPS)':
 C_PATH='@s9s_mb_2u_lib.s9s_mb_2u(sch_1):page268_i22@pure_quanta.rs53317lr(chips~
)',
 P_PATH='@s9s_mb_2u_lib.s9s_mb_2u(sch_1):page282_i22@pure_quanta.rs53317lr(chips~
)',
 PATH='I22',
 DRAWING='@S9S_MB_2U_LIB.S9S_MB_2U(SCH_1):PAGE268',
 PHYS_PAGE='282',
 XY='(-6900,9675)',
 ROT='0',
 VER='1',
 LOCATION='PU81',
 SEC='1',
 CDS_LIB='pure_quanta',
 CDS_PART_NAME='RS53317LR-RS53317LR,SMLF,IC,ALA',
 SEC_TYPE='',
 PART_TYPE='SMLF',
 MATERIAL='IC',
 VALUE='RS53317LR',
 PRIM_FILE='./archive_libs/logical/rs53317lr/chips/chips.prt';

PART_NAME
 PU82 'RS53317LR-RS53317LR,SMLF,IC,ALA':;

SECTION_NUMBER 1
 '@S9S_MB_2U_LIB.S9S_MB_2U(SCH_1):PAGE286_I20@PURE_QUANTA.RS53317LR(CHIPS)':
 C_PATH='@s9s_mb_2u_lib.s9s_mb_2u(sch_1):page286_i20@pure_quanta.rs53317lr(chips~
)',
 P_PATH='@s9s_mb_2u_lib.s9s_mb_2u(sch_1):page300_i20@pure_quanta.rs53317lr(chips~
)',
 PATH='I20',
 DRAWING='@S9S_MB_2U_LIB.S9S_MB_2U(SCH_1):PAGE286',
 PHYS_PAGE='300',
 XY='(4950,7050)',
 ROT='0',
 VER='1',
 LOCATION='PU82',
 SEC='1',
 CDS_LIB='pure_quanta',
 CDS_PART_NAME='RS53317LR-RS53317LR,SMLF,IC,ALA',
 SEC_TYPE='',
 PART_TYPE='SMLF',
 MATERIAL='IC',
 VALUE='RS53317LR',
 PRIM_FILE='./archive_libs/logical/rs53317lr/chips/chips.prt';

PART_NAME
 PU173 'MOSFET_N_SMLF-BSS138K,BSS138K,B':;

SECTION_NUMBER 1
 '@S9S_MB_2U_LIB.S9S_MB_2U(SCH_1):PAGE267_I31@PURE_QUANTA.MOSFET_N(CHIPS)':
 C_PATH='@s9s_mb_2u_lib.s9s_mb_2u(sch_1):page267_i31@pure_quanta.mosfet_n(chips)~
',
 P_PATH='@s9s_mb_2u_lib.s9s_mb_2u(sch_1):page281_i31@pure_quanta.mosfet_n(chips)~
',
 PATH='I31',
 DRAWING='@S9S_MB_2U_LIB.S9S_MB_2U(SCH_1):PAGE267',
 PHYS_PAGE='281',
 XY='(-6275,2225)',
 ROT='2',
 VER='1',
 PACK_TYPE='SMLF',
 LOCATION='PU173',
 CDS_LIB='pure_quanta',
 CDS_PART_NAME='MOSFET_N_SMLF-BSS138K,BSS138K,B',
 MANUF_PN='BSS138K',
 MATERIAL='EMPTY',
 VALUE='BSS138K',
 PRIM_FILE='./archive_libs/logical/mosfet_n/chips/chips.prt';

PART_NAME
 PU174 'MOSFET_N_SMLF-BSS138K,BSS138K,B':;

SECTION_NUMBER 1
 '@S9S_MB_2U_LIB.S9S_MB_2U(SCH_1):PAGE285_I29@PURE_QUANTA.MOSFET_N(CHIPS)':
 C_PATH='@s9s_mb_2u_lib.s9s_mb_2u(sch_1):page285_i29@pure_quanta.mosfet_n(chips)~
',
 P_PATH='@s9s_mb_2u_lib.s9s_mb_2u(sch_1):page299_i29@pure_quanta.mosfet_n(chips)~
',
 PATH='I29',
 DRAWING='@S9S_MB_2U_LIB.S9S_MB_2U(SCH_1):PAGE285',
 PHYS_PAGE='299',
 XY='(-5625,1800)',
 ROT='2',
 VER='1',
 PACK_TYPE='SMLF',
 LOCATION='PU174',
 CDS_LIB='pure_quanta',
 CDS_PART_NAME='MOSFET_N_SMLF-BSS138K,BSS138K,B',
 MANUF_PN='BSS138K',
 MATERIAL='EMPTY',
 VALUE='BSS138K',
 PRIM_FILE='./archive_libs/logical/mosfet_n/chips/chips.prt';

PART_NAME
 PU181 'RS53318LR-RS53318LR,SMLF,IC,ALA':;

SECTION_NUMBER 1
 '@S9S_MB_2U_LIB.S9S_MB_2U(SCH_1):PAGE244_I20@PURE_QUANTA.RS53318LR(CHIPS)':
 C_PATH='@s9s_mb_2u_lib.s9s_mb_2u(sch_1):page244_i20@pure_quanta.rs53318lr(chips~
)',
 P_PATH='@s9s_mb_2u_lib.s9s_mb_2u(sch_1):page258_i20@pure_quanta.rs53318lr(chips~
)',
 PATH='I20',
 DRAWING='@S9S_MB_2U_LIB.S9S_MB_2U(SCH_1):PAGE244',
 PHYS_PAGE='258',
 XY='(-4575,6025)',
 ROT='0',
 VER='1',
 LOCATION='PU181',
 SEC='1',
 CDS_LIB='pure_quanta',
 CDS_PART_NAME='RS53318LR-RS53318LR,SMLF,IC,ALA',
 SEC_TYPE='',
 PART_TYPE='SMLF',
 MATERIAL='IC',
 VALUE='RS53318LR',
 PRIM_FILE='./archive_libs/logical/rs53318lr/chips/chips.prt';

PART_NAME
 PU200 'MAX15090BEWIT-MAX15090BEWI+T,SB':
 ROOM='NIC1_P3V3_BOM1';

SECTION_NUMBER 1
 '@S9S_MB_2U_LIB.S9S_MB_2U(SCH_1):PAGE131_I90@PURE_QUANTA.MAX15090BEWIT(CHIPS)':
 C_PATH='@s9s_mb_2u_lib.s9s_mb_2u(sch_1):page131_i90@pure_quanta.max15090bewit(c~
hips)',
 P_PATH='@s9s_mb_2u_lib.s9s_mb_2u(sch_1):page162_i90@pure_quanta.max15090bewit(c~
hips)',
 PATH='I90',
 DRAWING='@S9S_MB_2U_LIB.S9S_MB_2U(SCH_1):PAGE131',
 PIN_NAMES_ROTATE='True',
 PHYS_PAGE='162',
 XY='(1550,1800)',
 ROT='0',
 VER='1',
 LOCATION='PU200',
 CDS_LIB='pure_quanta',
 CDS_PART_NAME='MAX15090BEWIT-MAX15090BEWI+T,SB',
 PART_TYPE='SMLF',
 MATERIAL='IC',
 ROOM='NIC1_P3V3_BOM1',
 VALUE='MAX15090BEWI+T',
 PRIM_FILE='./archive_libs/logical/max15090bewit/chips/chips.prt';

PART_NAME
 PU201 'MAX15090BEWIT-MAX15090BEWI+T,SA':
 ROOM='NIC1_P12V_MAM_MAM_BOM1';

SECTION_NUMBER 1
 '@S9S_MB_2U_LIB.S9S_MB_2U(SCH_1):PAGE131_I63@PURE_QUANTA.MAX15090BEWIT(CHIPS)':
 C_PATH='@s9s_mb_2u_lib.s9s_mb_2u(sch_1):page131_i63@pure_quanta.max15090bewit(c~
hips)',
 P_PATH='@s9s_mb_2u_lib.s9s_mb_2u(sch_1):page162_i63@pure_quanta.max15090bewit(c~
hips)',
 PATH='I63',
 DRAWING='@S9S_MB_2U_LIB.S9S_MB_2U(SCH_1):PAGE131',
 ROOM1='NIC1_P12V_MAM_TIC_BOM2',
 PIN_NAMES_ROTATE='True',
 PHYS_PAGE='162',
 XY='(1425,-525)',
 ROT='0',
 VER='1',
 LOCATION='PU201',
 CDS_LIB='pure_quanta',
 CDS_PART_NAME='MAX15090BEWIT-MAX15090BEWI+T,SA',
 PART_TYPE='SMLF',
 MATERIAL='EMPTY',
 ROOM='NIC1_P12V_MAM_MAM_BOM1',
 VALUE='MAX15090BEWI+T',
 PRIM_FILE='./archive_libs/logical/max15090bewit/chips/chips.prt';

PART_NAME
 PU202 'MAX15090BEWIT-MAX15090BEWI+T,SB':
 ROOM='NIC1_P3V3_BOM1';

SECTION_NUMBER 1
 '@S9S_MB_2U_LIB.S9S_MB_2U(SCH_1):PAGE153_I61@PURE_QUANTA.MAX15090BEWIT(CHIPS)':
 C_PATH='@s9s_mb_2u_lib.s9s_mb_2u(sch_1):page153_i61@pure_quanta.max15090bewit(c~
hips)',
 P_PATH='@s9s_mb_2u_lib.s9s_mb_2u(sch_1):page156_i61@pure_quanta.max15090bewit(c~
hips)',
 PATH='I61',
 DRAWING='@S9S_MB_2U_LIB.S9S_MB_2U(SCH_1):PAGE153',
 PIN_NAMES_ROTATE='True',
 PHYS_PAGE='156',
 XY='(7750,12800)',
 ROT='0',
 VER='1',
 LOCATION='PU202',
 CDS_LIB='pure_quanta',
 CDS_PART_NAME='MAX15090BEWIT-MAX15090BEWI+T,SB',
 PART_TYPE='SMLF',
 MATERIAL='IC',
 ROOM='NIC1_P3V3_BOM1',
 VALUE='MAX15090BEWI+T',
 PRIM_FILE='./archive_libs/logical/max15090bewit/chips/chips.prt';

PART_NAME
 PU203 'MAX15090BEWIT-MAX15090BEWI+T,SA':
 ROOM='NIC1_P12V_MAM_MAM_BOM1';

SECTION_NUMBER 1
 '@S9S_MB_2U_LIB.S9S_MB_2U(SCH_1):PAGE153_I51@PURE_QUANTA.MAX15090BEWIT(CHIPS)':
 C_PATH='@s9s_mb_2u_lib.s9s_mb_2u(sch_1):page153_i51@pure_quanta.max15090bewit(c~
hips)',
 P_PATH='@s9s_mb_2u_lib.s9s_mb_2u(sch_1):page156_i51@pure_quanta.max15090bewit(c~
hips)',
 PATH='I51',
 DRAWING='@S9S_MB_2U_LIB.S9S_MB_2U(SCH_1):PAGE153',
 ROOM1='NIC1_P12V_MAM_TIC_BOM2',
 PIN_NAMES_ROTATE='True',
 PHYS_PAGE='156',
 XY='(7525,10700)',
 ROT='0',
 VER='1',
 LOCATION='PU203',
 CDS_LIB='pure_quanta',
 CDS_PART_NAME='MAX15090BEWIT-MAX15090BEWI+T,SA',
 PART_TYPE='SMLF',
 MATERIAL='EMPTY',
 ROOM='NIC1_P12V_MAM_MAM_BOM1',
 VALUE='MAX15090BEWI+T',
 PRIM_FILE='./archive_libs/logical/max15090bewit/chips/chips.prt';

PART_NAME
 PU204 'RS31312R-RS31312R,SMLF,IC,AL03A':
 ROOM='NIC1_P12V_MPS_MAM_BOM3';

SECTION_NUMBER 1
 '@S9S_MB_2U_LIB.S9S_MB_2U(SCH_1):PAGE236_I70@PURE_QUANTA.RS31312R(CHIPS)':
 C_PATH='@s9s_mb_2u_lib.s9s_mb_2u(sch_1):page236_i70@pure_quanta.rs31312r(chips)~
',
 P_PATH='@s9s_mb_2u_lib.s9s_mb_2u(sch_1):page157_i70@pure_quanta.rs31312r(chips)~
',
 PATH='I70',
 DRAWING='@S9S_MB_2U_LIB.S9S_MB_2U(SCH_1):PAGE236',
 ROOM1='NIC1_P12V_MPS_TIC_BOM4',
 PHYS_PAGE='157',
 XY='(-6425,9525)',
 ROT='0',
 VER='1',
 LOCATION='PU204',
 CDS_LIB='pure_quanta',
 CDS_PART_NAME='RS31312R-RS31312R,SMLF,IC,AL03A',
 PART_TYPE='SMLF',
 MATERIAL='IC',
 ROOM='NIC1_P12V_MPS_MAM_BOM3',
 VALUE='RS31312R',
 PRIM_FILE='./archive_libs/logical/rs31312r/chips/chips.prt';

PART_NAME
 PU205 'MP5016GQHLZ-MP5016GQH-L-Z,SMLFA':
 ROOM='NIC1_P3V3_BOM2';

SECTION_NUMBER 1
 '@S9S_MB_2U_LIB.S9S_MB_2U(SCH_1):PAGE236_I50@PURE_QUANTA.MP5016GQHLZ(CHIPS)':
 C_PATH='@s9s_mb_2u_lib.s9s_mb_2u(sch_1):page236_i50@pure_quanta.mp5016gqhlz(chi~
ps)',
 P_PATH='@s9s_mb_2u_lib.s9s_mb_2u(sch_1):page157_i50@pure_quanta.mp5016gqhlz(chi~
ps)',
 PATH='I50',
 DRAWING='@S9S_MB_2U_LIB.S9S_MB_2U(SCH_1):PAGE236',
 PHYS_PAGE='157',
 XY='(-2325,12550)',
 ROT='0',
 VER='1',
 LOCATION='PU205',
 CDS_LIB='pure_quanta',
 CDS_PART_NAME='MP5016GQHLZ-MP5016GQH-L-Z,SMLFA',
 PART_TYPE='SMLF',
 MATERIAL='EMPTY',
 ROOM='NIC1_P3V3_BOM2',
 VALUE='MP5016GQH-L-Z',
 PRIM_FILE='./archive_libs/logical/mp5016gqhlz/chips/chips.prt';

PART_NAME
 PU206 'RS31312R-RS31312R,SMLF,IC,AL03A':
 ROOM='NIC1_P12V_MPS_MAM_BOM3';

SECTION_NUMBER 1
 '@S9S_MB_2U_LIB.S9S_MB_2U(SCH_1):PAGE237_I70@PURE_QUANTA.RS31312R(CHIPS)':
 C_PATH='@s9s_mb_2u_lib.s9s_mb_2u(sch_1):page237_i70@pure_quanta.rs31312r(chips)~
',
 P_PATH='@s9s_mb_2u_lib.s9s_mb_2u(sch_1):page163_i70@pure_quanta.rs31312r(chips)~
',
 PATH='I70',
 DRAWING='@S9S_MB_2U_LIB.S9S_MB_2U(SCH_1):PAGE237',
 ROOM1='NIC1_P12V_MPS_TIC_BOM4',
 PHYS_PAGE='163',
 XY='(-2550,3050)',
 ROT='0',
 VER='1',
 LOCATION='PU206',
 CDS_LIB='pure_quanta',
 CDS_PART_NAME='RS31312R-RS31312R,SMLF,IC,AL03A',
 PART_TYPE='SMLF',
 MATERIAL='IC',
 ROOM='NIC1_P12V_MPS_MAM_BOM3',
 VALUE='RS31312R',
 PRIM_FILE='./archive_libs/logical/rs31312r/chips/chips.prt';

PART_NAME
 PU207 'MP5016GQHLZ-MP5016GQH-L-Z,SMLFA':
 ROOM='NIC1_P3V3_BOM2';

SECTION_NUMBER 1
 '@S9S_MB_2U_LIB.S9S_MB_2U(SCH_1):PAGE237_I51@PURE_QUANTA.MP5016GQHLZ(CHIPS)':
 C_PATH='@s9s_mb_2u_lib.s9s_mb_2u(sch_1):page237_i51@pure_quanta.mp5016gqhlz(chi~
ps)',
 P_PATH='@s9s_mb_2u_lib.s9s_mb_2u(sch_1):page163_i51@pure_quanta.mp5016gqhlz(chi~
ps)',
 PATH='I51',
 DRAWING='@S9S_MB_2U_LIB.S9S_MB_2U(SCH_1):PAGE237',
 PHYS_PAGE='163',
 XY='(1675,6425)',
 ROT='0',
 VER='1',
 LOCATION='PU207',
 CDS_LIB='pure_quanta',
 CDS_PART_NAME='MP5016GQHLZ-MP5016GQH-L-Z,SMLFA',
 PART_TYPE='SMLF',
 MATERIAL='EMPTY',
 ROOM='NIC1_P3V3_BOM2',
 VALUE='MP5016GQH-L-Z',
 PRIM_FILE='./archive_libs/logical/mp5016gqhlz/chips/chips.prt';

PART_NAME
 PU287 'MP5991GLUZ-MP5991GLU-Z,SMLF,ICA':
 ROOM='HSC1_BOM1';

SECTION_NUMBER 1
 '@S9S_MB_2U_LIB.S9S_MB_2U(SCH_1):PAGE301_I35@PURE_QUANTA.MP5991GLUZ(CHIPS)':
 C_PATH='@s9s_mb_2u_lib.s9s_mb_2u(sch_1):page301_i35@pure_quanta.mp5991gluz(chip~
s)',
 P_PATH='@s9s_mb_2u_lib.s9s_mb_2u(sch_1):page302_i35@pure_quanta.mp5991gluz(chip~
s)',
 PATH='I35',
 DRAWING='@S9S_MB_2U_LIB.S9S_MB_2U(SCH_1):PAGE301',
 PHYS_PAGE='302',
 XY='(-225,1525)',
 ROT='0',
 VER='1',
 LOCATION='PU287',
 SEC='1',
 CDS_LIB='pure_quanta',
 CDS_PART_NAME='MP5991GLUZ-MP5991GLU-Z,SMLF,ICA',
 SEC_TYPE='',
 PART_TYPE='SMLF',
 MATERIAL='IC',
 ROOM='HSC1_BOM1',
 VALUE='MP5991GLU-Z',
 PRIM_FILE='./archive_libs/logical/mp5991gluz/chips/chips.prt';

PART_NAME
 PU288 'MP5991GLUZ-MP5991GLU-Z,SMLF,ICA':
 ROOM='HSC1_BOM1';

SECTION_NUMBER 1
 '@S9S_MB_2U_LIB.S9S_MB_2U(SCH_1):PAGE301_I14@PURE_QUANTA.MP5991GLUZ(CHIPS)':
 C_PATH='@s9s_mb_2u_lib.s9s_mb_2u(sch_1):page301_i14@pure_quanta.mp5991gluz(chip~
s)',
 P_PATH='@s9s_mb_2u_lib.s9s_mb_2u(sch_1):page302_i14@pure_quanta.mp5991gluz(chip~
s)',
 PATH='I14',
 DRAWING='@S9S_MB_2U_LIB.S9S_MB_2U(SCH_1):PAGE301',
 PHYS_PAGE='302',
 XY='(-225,-1275)',
 ROT='0',
 VER='1',
 LOCATION='PU288',
 SEC='1',
 CDS_LIB='pure_quanta',
 CDS_PART_NAME='MP5991GLUZ-MP5991GLU-Z,SMLF,ICA',
 SEC_TYPE='',
 PART_TYPE='SMLF',
 MATERIAL='IC',
 ROOM='HSC1_BOM1',
 VALUE='MP5991GLU-Z',
 PRIM_FILE='./archive_libs/logical/mp5991gluz/chips/chips.prt';

PART_NAME
 PU289 'MP5990GMA1111Z-MP5990GMA-1111-A':
 ROOM='HSC1_BOM1';

SECTION_NUMBER 1
 '@S9S_MB_2U_LIB.S9S_MB_2U(SCH_1):PAGE303_I56@PURE_QUANTA.MP5990GMA1111Z(CHIPS)':
 C_PATH='@s9s_mb_2u_lib.s9s_mb_2u(sch_1):page303_i56@pure_quanta.mp5990gma1111z(~
chips)',
 P_PATH='@s9s_mb_2u_lib.s9s_mb_2u(sch_1):page301_i56@pure_quanta.mp5990gma1111z(~
chips)',
 PATH='I56',
 DRAWING='@S9S_MB_2U_LIB.S9S_MB_2U(SCH_1):PAGE303',
 PHYS_PAGE='301',
 XY='(-13125,3750)',
 ROT='0',
 VER='1',
 LOCATION='PU289',
 CDS_LIB='pure_quanta',
 CDS_PART_NAME='MP5990GMA1111Z-MP5990GMA-1111-A',
 PART_TYPE='SMLF',
 MATERIAL='IC',
 ROOM='HSC1_BOM1',
 VALUE='MP5990GMA-1111-Z',
 PRIM_FILE='./archive_libs/logical/mp5990gma1111z/chips/chips.prt';

PART_NAME
 PU292 'RS31312R-RS31312R,SMLF,IC,AL03A':
 ROOM='E1S1_P12V_MPS_MAM_BOM3';

SECTION_NUMBER 1
 '@S9S_MB_2U_LIB.S9S_MB_2U(SCH_1):PAGE323_I49@PURE_QUANTA.RS31312R(CHIPS)':
 C_PATH='@s9s_mb_2u_lib.s9s_mb_2u(sch_1):page323_i49@pure_quanta.rs31312r(chips)~
',
 P_PATH='@s9s_mb_2u_lib.s9s_mb_2u(sch_1):page193_i49@pure_quanta.rs31312r(chips)~
',
 PATH='I49',
 DRAWING='@S9S_MB_2U_LIB.S9S_MB_2U(SCH_1):PAGE323',
 ROOM1='E1S1_P12V_MPS_TIC_BOM4',
 PHYS_PAGE='193',
 XY='(-100,1050)',
 ROT='0',
 VER='1',
 LOCATION='PU292',
 CDS_LIB='pure_quanta',
 CDS_PART_NAME='RS31312R-RS31312R,SMLF,IC,AL03A',
 PART_TYPE='SMLF',
 MATERIAL='IC',
 ROOM='E1S1_P12V_MPS_MAM_BOM3',
 VALUE='RS31312R',
 PRIM_FILE='./archive_libs/logical/rs31312r/chips/chips.prt';

PART_NAME
 PU293 'MP5016GQHLZ-MP5016GQH-L-Z,SMLFA':
 ROOM='E1S1_P3V3_BOM2';

SECTION_NUMBER 1
 '@S9S_MB_2U_LIB.S9S_MB_2U(SCH_1):PAGE323_I31@PURE_QUANTA.MP5016GQHLZ(CHIPS)':
 C_PATH='@s9s_mb_2u_lib.s9s_mb_2u(sch_1):page323_i31@pure_quanta.mp5016gqhlz(chi~
ps)',
 P_PATH='@s9s_mb_2u_lib.s9s_mb_2u(sch_1):page193_i31@pure_quanta.mp5016gqhlz(chi~
ps)',
 PATH='I31',
 DRAWING='@S9S_MB_2U_LIB.S9S_MB_2U(SCH_1):PAGE323',
 PHYS_PAGE='193',
 XY='(775,-1375)',
 ROT='0',
 VER='1',
 LOCATION='PU293',
 CDS_LIB='pure_quanta',
 CDS_PART_NAME='MP5016GQHLZ-MP5016GQH-L-Z,SMLFA',
 PART_TYPE='SMLF',
 MATERIAL='EMPTY',
 ROOM='E1S1_P3V3_BOM2',
 VALUE='MP5016GQH-L-Z',
 PRIM_FILE='./archive_libs/logical/mp5016gqhlz/chips/chips.prt';

PART_NAME
 PU294 'MAX15090BEWIT-MAX15090BEWI+T,SA':
 ROOM='E1S1_P12V_MAM_MAM_BOM1';

SECTION_NUMBER 1
 '@S9S_MB_2U_LIB.S9S_MB_2U(SCH_1):PAGE324_I62@PURE_QUANTA.MAX15090BEWIT(CHIPS)':
 C_PATH='@s9s_mb_2u_lib.s9s_mb_2u(sch_1):page324_i62@pure_quanta.max15090bewit(c~
hips)',
 P_PATH='@s9s_mb_2u_lib.s9s_mb_2u(sch_1):page192_i62@pure_quanta.max15090bewit(c~
hips)',
 PATH='I62',
 DRAWING='@S9S_MB_2U_LIB.S9S_MB_2U(SCH_1):PAGE324',
 ROOM1='E1S1_P12V_MAM_TIC_BOM2',
 PIN_NAMES_ROTATE='TRUE',
 PHYS_PAGE='192',
 XY='(1450,900)',
 ROT='0',
 VER='1',
 LOCATION='PU294',
 CDS_LIB='pure_quanta',
 CDS_PART_NAME='MAX15090BEWIT-MAX15090BEWI+T,SA',
 PART_TYPE='SMLF',
 MATERIAL='EMPTY',
 ROOM='E1S1_P12V_MAM_MAM_BOM1',
 VALUE='MAX15090BEWI+T',
 PRIM_FILE='./archive_libs/logical/max15090bewit/chips/chips.prt';

PART_NAME
 PU295 'MAX15090BEWIT-MAX15090BEWI+T,SB':
 ROOM='E1S1_P3V3_BOM1';

SECTION_NUMBER 1
 '@S9S_MB_2U_LIB.S9S_MB_2U(SCH_1):PAGE324_I35@PURE_QUANTA.MAX15090BEWIT(CHIPS)':
 C_PATH='@s9s_mb_2u_lib.s9s_mb_2u(sch_1):page324_i35@pure_quanta.max15090bewit(c~
hips)',
 P_PATH='@s9s_mb_2u_lib.s9s_mb_2u(sch_1):page192_i35@pure_quanta.max15090bewit(c~
hips)',
 PATH='I35',
 DRAWING='@S9S_MB_2U_LIB.S9S_MB_2U(SCH_1):PAGE324',
 PIN_NAMES_ROTATE='TRUE',
 PHYS_PAGE='192',
 XY='(1475,-1825)',
 ROT='0',
 VER='1',
 LOCATION='PU295',
 CDS_LIB='pure_quanta',
 CDS_PART_NAME='MAX15090BEWIT-MAX15090BEWI+T,SB',
 PART_TYPE='SMLF',
 MATERIAL='IC',
 ROOM='E1S1_P3V3_BOM1',
 VALUE='MAX15090BEWI+T',
 PRIM_FILE='./archive_libs/logical/max15090bewit/chips/chips.prt';

PART_NAME
 PU296 'MP5991GLUZ-MP5991GLU-Z,SMLF,ICA':
 ROOM='HSC1_BOM1';

SECTION_NUMBER 1
 '@S9S_MB_2U_LIB.S9S_MB_2U(SCH_1):PAGE325_I35@PURE_QUANTA.MP5991GLUZ(CHIPS)':
 C_PATH='@s9s_mb_2u_lib.s9s_mb_2u(sch_1):page325_i35@pure_quanta.mp5991gluz(chip~
s)',
 P_PATH='@s9s_mb_2u_lib.s9s_mb_2u(sch_1):page303_i35@pure_quanta.mp5991gluz(chip~
s)',
 PATH='I35',
 DRAWING='@S9S_MB_2U_LIB.S9S_MB_2U(SCH_1):PAGE325',
 PHYS_PAGE='303',
 XY='(850,1700)',
 ROT='0',
 VER='1',
 LOCATION='PU296',
 SEC='1',
 CDS_LIB='pure_quanta',
 CDS_PART_NAME='MP5991GLUZ-MP5991GLU-Z,SMLF,ICA',
 SEC_TYPE='',
 PART_TYPE='SMLF',
 MATERIAL='IC',
 ROOM='HSC1_BOM1',
 VALUE='MP5991GLU-Z',
 PRIM_FILE='./archive_libs/logical/mp5991gluz/chips/chips.prt';

PART_NAME
 PU297 'MP5991GLUZ-MP5991GLU-Z,SMLF,ICA':
 ROOM='HSC1_BOM1';

SECTION_NUMBER 1
 '@S9S_MB_2U_LIB.S9S_MB_2U(SCH_1):PAGE325_I17@PURE_QUANTA.MP5991GLUZ(CHIPS)':
 C_PATH='@s9s_mb_2u_lib.s9s_mb_2u(sch_1):page325_i17@pure_quanta.mp5991gluz(chip~
s)',
 P_PATH='@s9s_mb_2u_lib.s9s_mb_2u(sch_1):page303_i17@pure_quanta.mp5991gluz(chip~
s)',
 PATH='I17',
 DRAWING='@S9S_MB_2U_LIB.S9S_MB_2U(SCH_1):PAGE325',
 PHYS_PAGE='303',
 XY='(850,-1075)',
 ROT='0',
 VER='1',
 LOCATION='PU297',
 SEC='1',
 CDS_LIB='pure_quanta',
 CDS_PART_NAME='MP5991GLUZ-MP5991GLU-Z,SMLF,ICA',
 SEC_TYPE='',
 PART_TYPE='SMLF',
 MATERIAL='IC',
 ROOM='HSC1_BOM1',
 VALUE='MP5991GLU-Z',
 PRIM_FILE='./archive_libs/logical/mp5991gluz/chips/chips.prt';

PART_NAME
 PU299 'RS31312R-RS31312R,SMLF,IC,AL03A':
 ROOM='SCM_P12V_BOM2';

SECTION_NUMBER 1
 '@S9S_MB_2U_LIB.S9S_MB_2U(SCH_1):PAGE229_I90@PURE_QUANTA.RS31312R(CHIPS)':
 C_PATH='@s9s_mb_2u_lib.s9s_mb_2u(sch_1):page229_i90@pure_quanta.rs31312r(chips)~
',
 P_PATH='@s9s_mb_2u_lib.s9s_mb_2u(sch_1):page242_i90@pure_quanta.rs31312r(chips)~
',
 PATH='I90',
 DRAWING='@S9S_MB_2U_LIB.S9S_MB_2U(SCH_1):PAGE229',
 PHYS_PAGE='242',
 XY='(1025,-1375)',
 ROT='0',
 VER='1',
 LOCATION='PU299',
 CDS_LIB='pure_quanta',
 CDS_PART_NAME='RS31312R-RS31312R,SMLF,IC,AL03A',
 PART_TYPE='SMLF',
 MATERIAL='IC',
 ROOM='SCM_P12V_BOM2',
 VALUE='RS31312R',
 PRIM_FILE='./archive_libs/logical/rs31312r/chips/chips.prt';

PART_NAME
 PU300 'MAX15090BEWIT-MAX15090BEWI+T,SA':
 ROOM='SCM_P12V_BOM1';

SECTION_NUMBER 1
 '@S9S_MB_2U_LIB.S9S_MB_2U(SCH_1):PAGE229_I69@PURE_QUANTA.MAX15090BEWIT(CHIPS)':
 C_PATH='@s9s_mb_2u_lib.s9s_mb_2u(sch_1):page229_i69@pure_quanta.max15090bewit(c~
hips)',
 P_PATH='@s9s_mb_2u_lib.s9s_mb_2u(sch_1):page242_i69@pure_quanta.max15090bewit(c~
hips)',
 PATH='I69',
 DRAWING='@S9S_MB_2U_LIB.S9S_MB_2U(SCH_1):PAGE229',
 PIN_NAMES_ROTATE='TRUE',
 PHYS_PAGE='242',
 XY='(1675,1500)',
 ROT='0',
 VER='1',
 LOCATION='PU300',
 CDS_LIB='pure_quanta',
 CDS_PART_NAME='MAX15090BEWIT-MAX15090BEWI+T,SA',
 PART_TYPE='SMLF',
 MATERIAL='EMPTY',
 ROOM='SCM_P12V_BOM1',
 VALUE='MAX15090BEWI+T',
 PRIM_FILE='./archive_libs/logical/max15090bewit/chips/chips.prt';

PART_NAME
 Q15 'MOSFET_NCH_DUAL-PJT138K,SMLF,IA':;

SECTION_NUMBER 1
 '@S9S_MB_2U_LIB.S9S_MB_2U(SCH_1):PAGE223_I104@PURE_QUANTA.MOSFET_NCH_DUAL(CHIPS)':
 C_PATH='@s9s_mb_2u_lib.s9s_mb_2u(sch_1):page223_i104@pure_quanta.mosfet_nch_dua~
l(chips)',
 P_PATH='@s9s_mb_2u_lib.s9s_mb_2u(sch_1):page235_i104@pure_quanta.mosfet_nch_dua~
l(chips)',
 PATH='I104',
 DRAWING='@S9S_MB_2U_LIB.S9S_MB_2U(SCH_1):PAGE223',
 PHYS_PAGE='235',
 XY='(-2550,3800)',
 ROT='0',
 VER='1',
 LOCATION='Q15',
 SEC='1',
 CDS_LIB='pure_quanta',
 CDS_PART_NAME='MOSFET_NCH_DUAL-PJT138K,SMLF,IA',
 SEC_TYPE='',
 PART_TYPE='SMLF',
 MATERIAL='IC',
 VALUE='PJT138K',
 PRIM_FILE='./archive_libs/logical/mosfet_nch_dual/chips/chips.prt';

SECTION_NUMBER 2
 '@S9S_MB_2U_LIB.S9S_MB_2U(SCH_1):PAGE223_I108@PURE_QUANTA.MOSFET_NCH_DUAL(CHIPS)':
 C_PATH='@s9s_mb_2u_lib.s9s_mb_2u(sch_1):page223_i108@pure_quanta.mosfet_nch_dua~
l(chips)',
 P_PATH='@s9s_mb_2u_lib.s9s_mb_2u(sch_1):page235_i108@pure_quanta.mosfet_nch_dua~
l(chips)',
 PATH='I108',
 DRAWING='@S9S_MB_2U_LIB.S9S_MB_2U(SCH_1):PAGE223',
 PHYS_PAGE='235',
 XY='(-1400,3800)',
 ROT='0',
 VER='2',
 LOCATION='Q15',
 CDS_LIB='pure_quanta',
 CDS_PART_NAME='MOSFET_NCH_DUAL-PJT138K,SMLF,IA',
 PART_TYPE='SMLF',
 MATERIAL='IC',
 VALUE='PJT138K',
 PRIM_FILE='./archive_libs/logical/mosfet_nch_dual/chips/chips.prt';

PART_NAME
 Q16 'MOSFET_NCH_DUAL-PJT138K,SMLF,IA':;

SECTION_NUMBER 1
 '@S9S_MB_2U_LIB.S9S_MB_2U(SCH_1):PAGE223_I106@PURE_QUANTA.MOSFET_NCH_DUAL(CHIPS)':
 C_PATH='@s9s_mb_2u_lib.s9s_mb_2u(sch_1):page223_i106@pure_quanta.mosfet_nch_dua~
l(chips)',
 P_PATH='@s9s_mb_2u_lib.s9s_mb_2u(sch_1):page235_i106@pure_quanta.mosfet_nch_dua~
l(chips)',
 PATH='I106',
 DRAWING='@S9S_MB_2U_LIB.S9S_MB_2U(SCH_1):PAGE223',
 PHYS_PAGE='235',
 XY='(-2550,2500)',
 ROT='0',
 VER='1',
 LOCATION='Q16',
 CDS_LIB='pure_quanta',
 CDS_PART_NAME='MOSFET_NCH_DUAL-PJT138K,SMLF,IA',
 PART_TYPE='SMLF',
 MATERIAL='IC',
 VALUE='PJT138K',
 PRIM_FILE='./archive_libs/logical/mosfet_nch_dual/chips/chips.prt';

SECTION_NUMBER 2
 '@S9S_MB_2U_LIB.S9S_MB_2U(SCH_1):PAGE223_I109@PURE_QUANTA.MOSFET_NCH_DUAL(CHIPS)':
 C_PATH='@s9s_mb_2u_lib.s9s_mb_2u(sch_1):page223_i109@pure_quanta.mosfet_nch_dua~
l(chips)',
 P_PATH='@s9s_mb_2u_lib.s9s_mb_2u(sch_1):page235_i109@pure_quanta.mosfet_nch_dua~
l(chips)',
 PATH='I109',
 DRAWING='@S9S_MB_2U_LIB.S9S_MB_2U(SCH_1):PAGE223',
 PHYS_PAGE='235',
 XY='(-1400,2500)',
 ROT='0',
 VER='2',
 LOCATION='Q16',
 CDS_LIB='pure_quanta',
 CDS_PART_NAME='MOSFET_NCH_DUAL-PJT138K,SMLF,IA',
 PART_TYPE='SMLF',
 MATERIAL='IC',
 VALUE='PJT138K',
 PRIM_FILE='./archive_libs/logical/mosfet_nch_dual/chips/chips.prt';

PART_NAME
 Q33 'MOSFET_NCH_GDS_ESD_PROTECTED-2A':;

SECTION_NUMBER 1
 '@S9S_MB_2U_LIB.S9S_MB_2U(SCH_1):PAGE207_I272@PURE_QUANTA.MOSFET_NCH_GDS_ESD_PROTECTED(CHIPS)':
 C_PATH='@s9s_mb_2u_lib.s9s_mb_2u(sch_1):page207_i272@pure_quanta.mosfet_nch_gds~
_esd_protected(chips)',
 P_PATH='@s9s_mb_2u_lib.s9s_mb_2u(sch_1):page218_i272@pure_quanta.mosfet_nch_gds~
_esd_protected(chips)',
 PATH='I272',
 DRAWING='@S9S_MB_2U_LIB.S9S_MB_2U(SCH_1):PAGE207',
 PHYS_PAGE='218',
 XY='(-1450,1325)',
 ROT='0',
 VER='1',
 LOCATION='Q33',
 CDS_LIB='pure_quanta',
 CDS_PART_NAME='MOSFET_NCH_GDS_ESD_PROTECTED-2A',
 PART_TYPE='SMLF',
 MATERIAL='IC',
 VALUE='2N7002K',
 PRIM_FILE='./archive_libs/logical/mosfet_nch_gds_esd_protected/chips/chips.prt';

PART_NAME
 Q34 'MOSFET_NCH_GDS_ESD_PROTECTED-2A':;

SECTION_NUMBER 1
 '@S9S_MB_2U_LIB.S9S_MB_2U(SCH_1):PAGE177_I123@PURE_QUANTA.MOSFET_NCH_GDS_ESD_PROTECTED(CHIPS)':
 C_PATH='@s9s_mb_2u_lib.s9s_mb_2u(sch_1):page177_i123@pure_quanta.mosfet_nch_gds~
_esd_protected(chips)',
 P_PATH='@s9s_mb_2u_lib.s9s_mb_2u(sch_1):page185_i123@pure_quanta.mosfet_nch_gds~
_esd_protected(chips)',
 PATH='I123',
 DRAWING='@S9S_MB_2U_LIB.S9S_MB_2U(SCH_1):PAGE177',
 PHYS_PAGE='185',
 XY='(25,-400)',
 ROT='0',
 VER='1',
 LOCATION='Q34',
 CDS_LIB='pure_quanta',
 CDS_PART_NAME='MOSFET_NCH_GDS_ESD_PROTECTED-2A',
 PART_TYPE='SMLF',
 MATERIAL='IC',
 VALUE='2N7002K',
 PRIM_FILE='./archive_libs/logical/mosfet_nch_gds_esd_protected/chips/chips.prt';

PART_NAME
 Q35 'MOSFET_NCH_GDS_ESD_PROTECTED-2A':;

SECTION_NUMBER 1
 '@S9S_MB_2U_LIB.S9S_MB_2U(SCH_1):PAGE177_I124@PURE_QUANTA.MOSFET_NCH_GDS_ESD_PROTECTED(CHIPS)':
 C_PATH='@s9s_mb_2u_lib.s9s_mb_2u(sch_1):page177_i124@pure_quanta.mosfet_nch_gds~
_esd_protected(chips)',
 P_PATH='@s9s_mb_2u_lib.s9s_mb_2u(sch_1):page185_i124@pure_quanta.mosfet_nch_gds~
_esd_protected(chips)',
 PATH='I124',
 DRAWING='@S9S_MB_2U_LIB.S9S_MB_2U(SCH_1):PAGE177',
 PHYS_PAGE='185',
 XY='(25,-1300)',
 ROT='0',
 VER='1',
 LOCATION='Q35',
 CDS_LIB='pure_quanta',
 CDS_PART_NAME='MOSFET_NCH_GDS_ESD_PROTECTED-2A',
 PART_TYPE='SMLF',
 MATERIAL='IC',
 VALUE='2N7002K',
 PRIM_FILE='./archive_libs/logical/mosfet_nch_gds_esd_protected/chips/chips.prt';

PART_NAME
 Q37 'MOSFET_NCH_DUAL-PJT138K,SMLF,IA':;

SECTION_NUMBER 1
 '@S9S_MB_2U_LIB.S9S_MB_2U(SCH_1):PAGE246_I69@PURE_QUANTA.MOSFET_NCH_DUAL(CHIPS)':
 C_PATH='@s9s_mb_2u_lib.s9s_mb_2u(sch_1):page246_i69@pure_quanta.mosfet_nch_dual~
(chips)',
 P_PATH='@s9s_mb_2u_lib.s9s_mb_2u(sch_1):page260_i69@pure_quanta.mosfet_nch_dual~
(chips)',
 PATH='I69',
 DRAWING='@S9S_MB_2U_LIB.S9S_MB_2U(SCH_1):PAGE246',
 PHYS_PAGE='260',
 XY='(-5175,4975)',
 ROT='0',
 VER='1',
 LOCATION='Q37',
 SEC='1',
 CDS_LIB='pure_quanta',
 CDS_PART_NAME='MOSFET_NCH_DUAL-PJT138K,SMLF,IA',
 SEC_TYPE='',
 PART_TYPE='SMLF',
 MATERIAL='IC',
 VALUE='PJT138K',
 PRIM_FILE='./archive_libs/logical/mosfet_nch_dual/chips/chips.prt';

SECTION_NUMBER 2
 '@S9S_MB_2U_LIB.S9S_MB_2U(SCH_1):PAGE246_I76@PURE_QUANTA.MOSFET_NCH_DUAL(CHIPS)':
 C_PATH='@s9s_mb_2u_lib.s9s_mb_2u(sch_1):page246_i76@pure_quanta.mosfet_nch_dual~
(chips)',
 P_PATH='@s9s_mb_2u_lib.s9s_mb_2u(sch_1):page260_i76@pure_quanta.mosfet_nch_dual~
(chips)',
 PATH='I76',
 DRAWING='@S9S_MB_2U_LIB.S9S_MB_2U(SCH_1):PAGE246',
 PHYS_PAGE='260',
 XY='(-4400,5300)',
 ROT='0',
 VER='2',
 LOCATION='Q37',
 CDS_LIB='pure_quanta',
 CDS_PART_NAME='MOSFET_NCH_DUAL-PJT138K,SMLF,IA',
 PART_TYPE='SMLF',
 MATERIAL='IC',
 VALUE='PJT138K',
 PRIM_FILE='./archive_libs/logical/mosfet_nch_dual/chips/chips.prt';

PART_NAME
 Q39 'MOSFET_NCH_GDS_ESD_PROTECTED-2A':;

SECTION_NUMBER 1
 '@S9S_MB_2U_LIB.S9S_MB_2U(SCH_1):PAGE229_I9@PURE_QUANTA.MOSFET_NCH_GDS_ESD_PROTECTED(CHIPS)':
 C_PATH='@s9s_mb_2u_lib.s9s_mb_2u(sch_1):page229_i9@pure_quanta.mosfet_nch_gds_e~
sd_protected(chips)',
 P_PATH='@s9s_mb_2u_lib.s9s_mb_2u(sch_1):page242_i9@pure_quanta.mosfet_nch_gds_e~
sd_protected(chips)',
 PATH='I9',
 DRAWING='@S9S_MB_2U_LIB.S9S_MB_2U(SCH_1):PAGE229',
 PHYS_PAGE='242',
 XY='(-1375,-225)',
 ROT='0',
 VER='1',
 CDS_LIB='pure_quanta',
 CDS_PART_NAME='MOSFET_NCH_GDS_ESD_PROTECTED-2A',
 PART_TYPE='SMLF',
 MATERIAL='IC',
 VALUE='2N7002K',
 PRIM_FILE='./archive_libs/logical/mosfet_nch_gds_esd_protected/chips/chips.prt';

PART_NAME
 Q46 'MOSFET_NCH_GDS_ESD_PROTECTED-2A':;

SECTION_NUMBER 1
 '@S9S_MB_2U_LIB.S9S_MB_2U(SCH_1):PAGE297_I316@PURE_QUANTA.MOSFET_NCH_GDS_ESD_PROTECTED(CHIPS)':
 C_PATH='@s9s_mb_2u_lib.s9s_mb_2u(sch_1):page297_i316@pure_quanta.mosfet_nch_gds~
_esd_protected(chips)',
 P_PATH='@s9s_mb_2u_lib.s9s_mb_2u(sch_1):page191_i316@pure_quanta.mosfet_nch_gds~
_esd_protected(chips)',
 PATH='I316',
 DRAWING='@S9S_MB_2U_LIB.S9S_MB_2U(SCH_1):PAGE297',
 PHYS_PAGE='191',
 XY='(2650,1225)',
 ROT='0',
 VER='1',
 LOCATION='Q46',
 CDS_LIB='pure_quanta',
 CDS_PART_NAME='MOSFET_NCH_GDS_ESD_PROTECTED-2A',
 PART_TYPE='SMLF',
 MATERIAL='IC',
 VALUE='2N7002K',
 PRIM_FILE='./archive_libs/logical/mosfet_nch_gds_esd_protected/chips/chips.prt';

PART_NAME
 Q50 'MOSFET_NCH_DUAL-PJT138K,SMLF,IA':;

SECTION_NUMBER 1
 '@S9S_MB_2U_LIB.S9S_MB_2U(SCH_1):PAGE314_I43@PURE_QUANTA.MOSFET_NCH_DUAL(CHIPS)':
 C_PATH='@s9s_mb_2u_lib.s9s_mb_2u(sch_1):page314_i43@pure_quanta.mosfet_nch_dual~
(chips)',
 P_PATH='@s9s_mb_2u_lib.s9s_mb_2u(sch_1):page213_i43@pure_quanta.mosfet_nch_dual~
(chips)',
 PATH='I43',
 DRAWING='@S9S_MB_2U_LIB.S9S_MB_2U(SCH_1):PAGE314',
 PHYS_PAGE='213',
 XY='(-2450,525)',
 ROT='0',
 VER='1',
 LOCATION='Q50',
 CDS_LIB='pure_quanta',
 CDS_PART_NAME='MOSFET_NCH_DUAL-PJT138K,SMLF,IA',
 PART_TYPE='SMLF',
 MATERIAL='IC',
 VALUE='PJT138K',
 PRIM_FILE='./archive_libs/logical/mosfet_nch_dual/chips/chips.prt';

SECTION_NUMBER 2
 '@S9S_MB_2U_LIB.S9S_MB_2U(SCH_1):PAGE314_I49@PURE_QUANTA.MOSFET_NCH_DUAL(CHIPS)':
 C_PATH='@s9s_mb_2u_lib.s9s_mb_2u(sch_1):page314_i49@pure_quanta.mosfet_nch_dual~
(chips)',
 P_PATH='@s9s_mb_2u_lib.s9s_mb_2u(sch_1):page213_i49@pure_quanta.mosfet_nch_dual~
(chips)',
 PATH='I49',
 DRAWING='@S9S_MB_2U_LIB.S9S_MB_2U(SCH_1):PAGE314',
 PHYS_PAGE='213',
 XY='(-1300,525)',
 ROT='0',
 VER='2',
 LOCATION='Q50',
 CDS_LIB='pure_quanta',
 CDS_PART_NAME='MOSFET_NCH_DUAL-PJT138K,SMLF,IA',
 PART_TYPE='SMLF',
 MATERIAL='IC',
 VALUE='PJT138K',
 PRIM_FILE='./archive_libs/logical/mosfet_nch_dual/chips/chips.prt';

PART_NAME
 Q52 'MOSFET_NCH_GDS_ESD_PROTECTED-2A':;

SECTION_NUMBER 1
 '@S9S_MB_2U_LIB.S9S_MB_2U(SCH_1):PAGE232_I14@PURE_QUANTA.MOSFET_NCH_GDS_ESD_PROTECTED(CHIPS)':
 C_PATH='@s9s_mb_2u_lib.s9s_mb_2u(sch_1):page232_i14@pure_quanta.mosfet_nch_gds_~
esd_protected(chips)',
 P_PATH='@s9s_mb_2u_lib.s9s_mb_2u(sch_1):page244_i14@pure_quanta.mosfet_nch_gds_~
esd_protected(chips)',
 PATH='I14',
 DRAWING='@S9S_MB_2U_LIB.S9S_MB_2U(SCH_1):PAGE232',
 PHYS_PAGE='244',
 XY='(-150,-225)',
 ROT='2',
 VER='1',
 LOCATION='Q52',
 CDS_LIB='pure_quanta',
 CDS_PART_NAME='MOSFET_NCH_GDS_ESD_PROTECTED-2A',
 PART_TYPE='SMLF',
 MATERIAL='IC',
 VALUE='2N7002K',
 PRIM_FILE='./archive_libs/logical/mosfet_nch_gds_esd_protected/chips/chips.prt';

PART_NAME
 Q53 'MOSFET_NCH_GDS_ESD_PROTECTED-2A':;

SECTION_NUMBER 1
 '@S9S_MB_2U_LIB.S9S_MB_2U(SCH_1):PAGE232_I39@PURE_QUANTA.MOSFET_NCH_GDS_ESD_PROTECTED(CHIPS)':
 C_PATH='@s9s_mb_2u_lib.s9s_mb_2u(sch_1):page232_i39@pure_quanta.mosfet_nch_gds_~
esd_protected(chips)',
 P_PATH='@s9s_mb_2u_lib.s9s_mb_2u(sch_1):page244_i39@pure_quanta.mosfet_nch_gds_~
esd_protected(chips)',
 PATH='I39',
 DRAWING='@S9S_MB_2U_LIB.S9S_MB_2U(SCH_1):PAGE232',
 PHYS_PAGE='244',
 XY='(900,-650)',
 ROT='2',
 VER='1',
 LOCATION='Q53',
 CDS_LIB='pure_quanta',
 CDS_PART_NAME='MOSFET_NCH_GDS_ESD_PROTECTED-2A',
 PART_TYPE='SMLF',
 MATERIAL='IC',
 VALUE='2N7002K',
 PRIM_FILE='./archive_libs/logical/mosfet_nch_gds_esd_protected/chips/chips.prt';

PART_NAME
 Q54 'MOSFET_NCH_GDS_ESD_PROTECTED-2A':;

SECTION_NUMBER 1
 '@S9S_MB_2U_LIB.S9S_MB_2U(SCH_1):PAGE234_I14@PURE_QUANTA.MOSFET_NCH_GDS_ESD_PROTECTED(CHIPS)':
 C_PATH='@s9s_mb_2u_lib.s9s_mb_2u(sch_1):page234_i14@pure_quanta.mosfet_nch_gds_~
esd_protected(chips)',
 P_PATH='@s9s_mb_2u_lib.s9s_mb_2u(sch_1):page247_i14@pure_quanta.mosfet_nch_gds_~
esd_protected(chips)',
 PATH='I14',
 DRAWING='@S9S_MB_2U_LIB.S9S_MB_2U(SCH_1):PAGE234',
 PHYS_PAGE='247',
 XY='(14000,3450)',
 ROT='0',
 VER='1',
 LOCATION='Q54',
 CDS_LIB='pure_quanta',
 CDS_PART_NAME='MOSFET_NCH_GDS_ESD_PROTECTED-2A',
 PART_TYPE='SMLF',
 MATERIAL='IC',
 VALUE='2N7002K',
 PRIM_FILE='./archive_libs/logical/mosfet_nch_gds_esd_protected/chips/chips.prt';

PART_NAME
 Q56 'MOSFET_NCH_1D3S-PSMNR58-30YLH,A':;

SECTION_NUMBER 1
 '@S9S_MB_2U_LIB.S9S_MB_2U(SCH_1):PAGE246_I51@PURE_QUANTA.MOSFET_NCH_1D3S(CHIPS)':
 C_PATH='@s9s_mb_2u_lib.s9s_mb_2u(sch_1):page246_i51@pure_quanta.mosfet_nch_1d3s~
(chips)',
 P_PATH='@s9s_mb_2u_lib.s9s_mb_2u(sch_1):page260_i51@pure_quanta.mosfet_nch_1d3s~
(chips)',
 PATH='I51',
 DRAWING='@S9S_MB_2U_LIB.S9S_MB_2U(SCH_1):PAGE246',
 PHYS_PAGE='260',
 XY='(125,4625)',
 ROT='7',
 VER='1',
 LOCATION='Q56',
 CDS_LIB='pure_quanta',
 CDS_PART_NAME='MOSFET_NCH_1D3S-PSMNR58-30YLH,A',
 PART_TYPE='SMLF',
 MATERIAL='IC',
 VALUE='PSMNR58-30YLH',
 PRIM_FILE='./archive_libs/logical/mosfet_nch_1d3s/chips/chips.prt';

PART_NAME
 Q57 'MOSFET_NCH_1D3S-PSMNR58-30YLH,A':;

SECTION_NUMBER 1
 '@S9S_MB_2U_LIB.S9S_MB_2U(SCH_1):PAGE246_I30@PURE_QUANTA.MOSFET_NCH_1D3S(CHIPS)':
 C_PATH='@s9s_mb_2u_lib.s9s_mb_2u(sch_1):page246_i30@pure_quanta.mosfet_nch_1d3s~
(chips)',
 P_PATH='@s9s_mb_2u_lib.s9s_mb_2u(sch_1):page260_i30@pure_quanta.mosfet_nch_1d3s~
(chips)',
 PATH='I30',
 DRAWING='@S9S_MB_2U_LIB.S9S_MB_2U(SCH_1):PAGE246',
 PHYS_PAGE='260',
 XY='(-4000,6875)',
 ROT='7',
 VER='1',
 LOCATION='Q57',
 CDS_LIB='pure_quanta',
 CDS_PART_NAME='MOSFET_NCH_1D3S-PSMNR58-30YLH,A',
 PART_TYPE='SMLF',
 MATERIAL='IC',
 VALUE='PSMNR58-30YLH',
 PRIM_FILE='./archive_libs/logical/mosfet_nch_1d3s/chips/chips.prt';

PART_NAME
 Q67 'MOSFET_NCH_DUAL-PJT138K,SMLF,IA':;

SECTION_NUMBER 1
 '@S9S_MB_2U_LIB.S9S_MB_2U(SCH_1):PAGE145_I33@PURE_QUANTA.MOSFET_NCH_DUAL(CHIPS)':
 C_PATH='@s9s_mb_2u_lib.s9s_mb_2u(sch_1):page145_i33@pure_quanta.mosfet_nch_dual~
(chips)',
 P_PATH='@s9s_mb_2u_lib.s9s_mb_2u(sch_1):page148_i33@pure_quanta.mosfet_nch_dual~
(chips)',
 PATH='I33',
 DRAWING='@S9S_MB_2U_LIB.S9S_MB_2U(SCH_1):PAGE145',
 PHYS_PAGE='148',
 XY='(-3575,7400)',
 ROT='0',
 VER='1',
 CDS_LIB='pure_quanta',
 CDS_PART_NAME='MOSFET_NCH_DUAL-PJT138K,SMLF,IA',
 PART_TYPE='SMLF',
 MATERIAL='IC',
 VALUE='PJT138K',
 PRIM_FILE='./archive_libs/logical/mosfet_nch_dual/chips/chips.prt';

SECTION_NUMBER 2
 '@S9S_MB_2U_LIB.S9S_MB_2U(SCH_1):PAGE145_I82@PURE_QUANTA.MOSFET_NCH_DUAL(CHIPS)':
 C_PATH='@s9s_mb_2u_lib.s9s_mb_2u(sch_1):page145_i82@pure_quanta.mosfet_nch_dual~
(chips)',
 P_PATH='@s9s_mb_2u_lib.s9s_mb_2u(sch_1):page148_i82@pure_quanta.mosfet_nch_dual~
(chips)',
 PATH='I82',
 DRAWING='@S9S_MB_2U_LIB.S9S_MB_2U(SCH_1):PAGE145',
 PHYS_PAGE='148',
 XY='(-2425,7700)',
 ROT='0',
 VER='2',
 LOCATION='Q67',
 CDS_LIB='pure_quanta',
 CDS_PART_NAME='MOSFET_NCH_DUAL-PJT138K,SMLF,IA',
 PART_TYPE='SMLF',
 MATERIAL='IC',
 VALUE='PJT138K',
 PRIM_FILE='./archive_libs/logical/mosfet_nch_dual/chips/chips.prt';

PART_NAME
 Q69 'MOSFET_NCH_DUAL-PJT138K,SMLF,IA':;

SECTION_NUMBER 1
 '@S9S_MB_2U_LIB.S9S_MB_2U(SCH_1):PAGE145_I117@PURE_QUANTA.MOSFET_NCH_DUAL(CHIPS)':
 C_PATH='@s9s_mb_2u_lib.s9s_mb_2u(sch_1):page145_i117@pure_quanta.mosfet_nch_dua~
l(chips)',
 P_PATH='@s9s_mb_2u_lib.s9s_mb_2u(sch_1):page148_i117@pure_quanta.mosfet_nch_dua~
l(chips)',
 PATH='I117',
 DRAWING='@S9S_MB_2U_LIB.S9S_MB_2U(SCH_1):PAGE145',
 PHYS_PAGE='148',
 XY='(-3525,6000)',
 ROT='0',
 VER='1',
 LOCATION='Q69',
 CDS_LIB='pure_quanta',
 CDS_PART_NAME='MOSFET_NCH_DUAL-PJT138K,SMLF,IA',
 PART_TYPE='SMLF',
 MATERIAL='IC',
 VALUE='PJT138K',
 PRIM_FILE='./archive_libs/logical/mosfet_nch_dual/chips/chips.prt';

SECTION_NUMBER 2
 '@S9S_MB_2U_LIB.S9S_MB_2U(SCH_1):PAGE145_I88@PURE_QUANTA.MOSFET_NCH_DUAL(CHIPS)':
 C_PATH='@s9s_mb_2u_lib.s9s_mb_2u(sch_1):page145_i88@pure_quanta.mosfet_nch_dual~
(chips)',
 P_PATH='@s9s_mb_2u_lib.s9s_mb_2u(sch_1):page148_i88@pure_quanta.mosfet_nch_dual~
(chips)',
 PATH='I88',
 DRAWING='@S9S_MB_2U_LIB.S9S_MB_2U(SCH_1):PAGE145',
 PHYS_PAGE='148',
 XY='(-2525,6300)',
 ROT='0',
 VER='2',
 LOCATION='Q69',
 CDS_LIB='pure_quanta',
 CDS_PART_NAME='MOSFET_NCH_DUAL-PJT138K,SMLF,IA',
 PART_TYPE='SMLF',
 MATERIAL='IC',
 VALUE='PJT138K',
 PRIM_FILE='./archive_libs/logical/mosfet_nch_dual/chips/chips.prt';

PART_NAME
 Q70 'MOSFET_NCH_DUAL-PJT138K,SMLF,IA':;

SECTION_NUMBER 1
 '@S9S_MB_2U_LIB.S9S_MB_2U(SCH_1):PAGE145_I35@PURE_QUANTA.MOSFET_NCH_DUAL(CHIPS)':
 C_PATH='@s9s_mb_2u_lib.s9s_mb_2u(sch_1):page145_i35@pure_quanta.mosfet_nch_dual~
(chips)',
 P_PATH='@s9s_mb_2u_lib.s9s_mb_2u(sch_1):page148_i35@pure_quanta.mosfet_nch_dual~
(chips)',
 PATH='I35',
 DRAWING='@S9S_MB_2U_LIB.S9S_MB_2U(SCH_1):PAGE145',
 PHYS_PAGE='148',
 XY='(-3500,4650)',
 ROT='0',
 VER='1',
 LOCATION='Q70',
 CDS_LIB='pure_quanta',
 CDS_PART_NAME='MOSFET_NCH_DUAL-PJT138K,SMLF,IA',
 PART_TYPE='SMLF',
 MATERIAL='IC',
 VALUE='PJT138K',
 PRIM_FILE='./archive_libs/logical/mosfet_nch_dual/chips/chips.prt';

SECTION_NUMBER 2
 '@S9S_MB_2U_LIB.S9S_MB_2U(SCH_1):PAGE145_I120@PURE_QUANTA.MOSFET_NCH_DUAL(CHIPS)':
 C_PATH='@s9s_mb_2u_lib.s9s_mb_2u(sch_1):page145_i120@pure_quanta.mosfet_nch_dua~
l(chips)',
 P_PATH='@s9s_mb_2u_lib.s9s_mb_2u(sch_1):page148_i120@pure_quanta.mosfet_nch_dua~
l(chips)',
 PATH='I120',
 DRAWING='@S9S_MB_2U_LIB.S9S_MB_2U(SCH_1):PAGE145',
 PHYS_PAGE='148',
 XY='(-2550,4925)',
 ROT='0',
 VER='2',
 LOCATION='Q70',
 CDS_LIB='pure_quanta',
 CDS_PART_NAME='MOSFET_NCH_DUAL-PJT138K,SMLF,IA',
 PART_TYPE='SMLF',
 MATERIAL='IC',
 VALUE='PJT138K',
 PRIM_FILE='./archive_libs/logical/mosfet_nch_dual/chips/chips.prt';

PART_NAME
 Q71 'MOSFET_NCH_DUAL-PJT138K,SMLF,IA':;

SECTION_NUMBER 1
 '@S9S_MB_2U_LIB.S9S_MB_2U(SCH_1):PAGE145_I118@PURE_QUANTA.MOSFET_NCH_DUAL(CHIPS)':
 C_PATH='@s9s_mb_2u_lib.s9s_mb_2u(sch_1):page145_i118@pure_quanta.mosfet_nch_dua~
l(chips)',
 P_PATH='@s9s_mb_2u_lib.s9s_mb_2u(sch_1):page148_i118@pure_quanta.mosfet_nch_dua~
l(chips)',
 PATH='I118',
 DRAWING='@S9S_MB_2U_LIB.S9S_MB_2U(SCH_1):PAGE145',
 PHYS_PAGE='148',
 XY='(1050,7525)',
 ROT='0',
 VER='1',
 LOCATION='Q71',
 CDS_LIB='pure_quanta',
 CDS_PART_NAME='MOSFET_NCH_DUAL-PJT138K,SMLF,IA',
 PART_TYPE='SMLF',
 MATERIAL='IC',
 VALUE='PJT138K',
 PRIM_FILE='./archive_libs/logical/mosfet_nch_dual/chips/chips.prt';

SECTION_NUMBER 2
 '@S9S_MB_2U_LIB.S9S_MB_2U(SCH_1):PAGE145_I100@PURE_QUANTA.MOSFET_NCH_DUAL(CHIPS)':
 C_PATH='@s9s_mb_2u_lib.s9s_mb_2u(sch_1):page145_i100@pure_quanta.mosfet_nch_dua~
l(chips)',
 P_PATH='@s9s_mb_2u_lib.s9s_mb_2u(sch_1):page148_i100@pure_quanta.mosfet_nch_dua~
l(chips)',
 PATH='I100',
 DRAWING='@S9S_MB_2U_LIB.S9S_MB_2U(SCH_1):PAGE145',
 PHYS_PAGE='148',
 XY='(1875,7800)',
 ROT='0',
 VER='2',
 LOCATION='Q71',
 CDS_LIB='pure_quanta',
 CDS_PART_NAME='MOSFET_NCH_DUAL-PJT138K,SMLF,IA',
 PART_TYPE='SMLF',
 MATERIAL='IC',
 VALUE='PJT138K',
 PRIM_FILE='./archive_libs/logical/mosfet_nch_dual/chips/chips.prt';

PART_NAME
 Q72 'MOSFET_NCH_DUAL-PJT138K,SMLF,IA':;

SECTION_NUMBER 1
 '@S9S_MB_2U_LIB.S9S_MB_2U(SCH_1):PAGE145_I37@PURE_QUANTA.MOSFET_NCH_DUAL(CHIPS)':
 C_PATH='@s9s_mb_2u_lib.s9s_mb_2u(sch_1):page145_i37@pure_quanta.mosfet_nch_dual~
(chips)',
 P_PATH='@s9s_mb_2u_lib.s9s_mb_2u(sch_1):page148_i37@pure_quanta.mosfet_nch_dual~
(chips)',
 PATH='I37',
 DRAWING='@S9S_MB_2U_LIB.S9S_MB_2U(SCH_1):PAGE145',
 PHYS_PAGE='148',
 XY='(1050,6150)',
 ROT='0',
 VER='1',
 LOCATION='Q72',
 CDS_LIB='pure_quanta',
 CDS_PART_NAME='MOSFET_NCH_DUAL-PJT138K,SMLF,IA',
 PART_TYPE='SMLF',
 MATERIAL='IC',
 VALUE='PJT138K',
 PRIM_FILE='./archive_libs/logical/mosfet_nch_dual/chips/chips.prt';

SECTION_NUMBER 2
 '@S9S_MB_2U_LIB.S9S_MB_2U(SCH_1):PAGE145_I119@PURE_QUANTA.MOSFET_NCH_DUAL(CHIPS)':
 C_PATH='@s9s_mb_2u_lib.s9s_mb_2u(sch_1):page145_i119@pure_quanta.mosfet_nch_dua~
l(chips)',
 P_PATH='@s9s_mb_2u_lib.s9s_mb_2u(sch_1):page148_i119@pure_quanta.mosfet_nch_dua~
l(chips)',
 PATH='I119',
 DRAWING='@S9S_MB_2U_LIB.S9S_MB_2U(SCH_1):PAGE145',
 PHYS_PAGE='148',
 XY='(1975,6425)',
 ROT='0',
 VER='2',
 LOCATION='Q72',
 SEC='2',
 CDS_LIB='pure_quanta',
 CDS_PART_NAME='MOSFET_NCH_DUAL-PJT138K,SMLF,IA',
 SEC_TYPE='',
 PART_TYPE='SMLF',
 MATERIAL='IC',
 VALUE='PJT138K',
 PRIM_FILE='./archive_libs/logical/mosfet_nch_dual/chips/chips.prt';

PART_NAME
 Q74 'MOSFET_NCH_DUAL-PJT138K,SMLF,IA':;

SECTION_NUMBER 1
 '@S9S_MB_2U_LIB.S9S_MB_2U(SCH_1):PAGE145_I121@PURE_QUANTA.MOSFET_NCH_DUAL(CHIPS)':
 C_PATH='@s9s_mb_2u_lib.s9s_mb_2u(sch_1):page145_i121@pure_quanta.mosfet_nch_dua~
l(chips)',
 P_PATH='@s9s_mb_2u_lib.s9s_mb_2u(sch_1):page148_i121@pure_quanta.mosfet_nch_dua~
l(chips)',
 PATH='I121',
 DRAWING='@S9S_MB_2U_LIB.S9S_MB_2U(SCH_1):PAGE145',
 PHYS_PAGE='148',
 XY='(1075,4775)',
 ROT='0',
 VER='1',
 LOCATION='Q74',
 SEC='1',
 CDS_LIB='pure_quanta',
 CDS_PART_NAME='MOSFET_NCH_DUAL-PJT138K,SMLF,IA',
 SEC_TYPE='',
 PART_TYPE='SMLF',
 MATERIAL='IC',
 VALUE='PJT138K',
 PRIM_FILE='./archive_libs/logical/mosfet_nch_dual/chips/chips.prt';

SECTION_NUMBER 2
 '@S9S_MB_2U_LIB.S9S_MB_2U(SCH_1):PAGE145_I122@PURE_QUANTA.MOSFET_NCH_DUAL(CHIPS)':
 C_PATH='@s9s_mb_2u_lib.s9s_mb_2u(sch_1):page145_i122@pure_quanta.mosfet_nch_dua~
l(chips)',
 P_PATH='@s9s_mb_2u_lib.s9s_mb_2u(sch_1):page148_i122@pure_quanta.mosfet_nch_dua~
l(chips)',
 PATH='I122',
 DRAWING='@S9S_MB_2U_LIB.S9S_MB_2U(SCH_1):PAGE145',
 PHYS_PAGE='148',
 XY='(2000,5050)',
 ROT='0',
 VER='2',
 LOCATION='Q74',
 SEC='2',
 CDS_LIB='pure_quanta',
 CDS_PART_NAME='MOSFET_NCH_DUAL-PJT138K,SMLF,IA',
 SEC_TYPE='',
 PART_TYPE='SMLF',
 MATERIAL='IC',
 VALUE='PJT138K',
 PRIM_FILE='./archive_libs/logical/mosfet_nch_dual/chips/chips.prt';

PART_NAME
 Q75 'MOSFET_NCH_DUAL-PJT138K,SMLF,IA':;

SECTION_NUMBER 1
 '@S9S_MB_2U_LIB.S9S_MB_2U(SCH_1):PAGE145_I152@PURE_QUANTA.MOSFET_NCH_DUAL(CHIPS)':
 C_PATH='@s9s_mb_2u_lib.s9s_mb_2u(sch_1):page145_i152@pure_quanta.mosfet_nch_dua~
l(chips)',
 P_PATH='@s9s_mb_2u_lib.s9s_mb_2u(sch_1):page148_i152@pure_quanta.mosfet_nch_dua~
l(chips)',
 PATH='I152',
 DRAWING='@S9S_MB_2U_LIB.S9S_MB_2U(SCH_1):PAGE145',
 PHYS_PAGE='148',
 XY='(-3475,3075)',
 ROT='0',
 VER='1',
 LOCATION='Q75',
 CDS_LIB='pure_quanta',
 CDS_PART_NAME='MOSFET_NCH_DUAL-PJT138K,SMLF,IA',
 PART_TYPE='SMLF',
 MATERIAL='IC',
 VALUE='PJT138K',
 PRIM_FILE='./archive_libs/logical/mosfet_nch_dual/chips/chips.prt';

SECTION_NUMBER 2
 '@S9S_MB_2U_LIB.S9S_MB_2U(SCH_1):PAGE145_I151@PURE_QUANTA.MOSFET_NCH_DUAL(CHIPS)':
 C_PATH='@s9s_mb_2u_lib.s9s_mb_2u(sch_1):page145_i151@pure_quanta.mosfet_nch_dua~
l(chips)',
 P_PATH='@s9s_mb_2u_lib.s9s_mb_2u(sch_1):page148_i151@pure_quanta.mosfet_nch_dua~
l(chips)',
 PATH='I151',
 DRAWING='@S9S_MB_2U_LIB.S9S_MB_2U(SCH_1):PAGE145',
 PHYS_PAGE='148',
 XY='(-2550,3350)',
 ROT='0',
 VER='2',
 LOCATION='Q75',
 CDS_LIB='pure_quanta',
 CDS_PART_NAME='MOSFET_NCH_DUAL-PJT138K,SMLF,IA',
 PART_TYPE='SMLF',
 MATERIAL='IC',
 VALUE='PJT138K',
 PRIM_FILE='./archive_libs/logical/mosfet_nch_dual/chips/chips.prt';

PART_NAME
 Q76 'MOSFET_NCH_DUAL-PJT138K,SMLF,IA':;

SECTION_NUMBER 1
 '@S9S_MB_2U_LIB.S9S_MB_2U(SCH_1):PAGE242_I17@PURE_QUANTA.MOSFET_NCH_DUAL(CHIPS)':
 C_PATH='@s9s_mb_2u_lib.s9s_mb_2u(sch_1):page242_i17@pure_quanta.mosfet_nch_dual~
(chips)',
 P_PATH='@s9s_mb_2u_lib.s9s_mb_2u(sch_1):page252_i17@pure_quanta.mosfet_nch_dual~
(chips)',
 PATH='I17',
 DRAWING='@S9S_MB_2U_LIB.S9S_MB_2U(SCH_1):PAGE242',
 PHYS_PAGE='252',
 XY='(-5825,8175)',
 ROT='0',
 VER='1',
 LOCATION='Q76',
 CDS_LIB='pure_quanta',
 CDS_PART_NAME='MOSFET_NCH_DUAL-PJT138K,SMLF,IA',
 PART_TYPE='SMLF',
 MATERIAL='IC',
 VALUE='PJT138K',
 PRIM_FILE='./archive_libs/logical/mosfet_nch_dual/chips/chips.prt';

SECTION_NUMBER 2
 '@S9S_MB_2U_LIB.S9S_MB_2U(SCH_1):PAGE242_I8@PURE_QUANTA.MOSFET_NCH_DUAL(CHIPS)':
 C_PATH='@s9s_mb_2u_lib.s9s_mb_2u(sch_1):page242_i8@pure_quanta.mosfet_nch_dual(~
chips)',
 P_PATH='@s9s_mb_2u_lib.s9s_mb_2u(sch_1):page252_i8@pure_quanta.mosfet_nch_dual(~
chips)',
 PATH='I8',
 DRAWING='@S9S_MB_2U_LIB.S9S_MB_2U(SCH_1):PAGE242',
 PHYS_PAGE='252',
 XY='(-5825,6850)',
 ROT='0',
 VER='2',
 LOCATION='Q76',
 SEC='2',
 CDS_LIB='pure_quanta',
 CDS_PART_NAME='MOSFET_NCH_DUAL-PJT138K,SMLF,IA',
 SEC_TYPE='',
 PART_TYPE='SMLF',
 MATERIAL='IC',
 VALUE='PJT138K',
 PRIM_FILE='./archive_libs/logical/mosfet_nch_dual/chips/chips.prt';

PART_NAME
 Q77 'MOSFET_NCH_DUAL-PJT138K,SMLF,IA':;

SECTION_NUMBER 1
 '@S9S_MB_2U_LIB.S9S_MB_2U(SCH_1):PAGE242_I6@PURE_QUANTA.MOSFET_NCH_DUAL(CHIPS)':
 C_PATH='@s9s_mb_2u_lib.s9s_mb_2u(sch_1):page242_i6@pure_quanta.mosfet_nch_dual(~
chips)',
 P_PATH='@s9s_mb_2u_lib.s9s_mb_2u(sch_1):page252_i6@pure_quanta.mosfet_nch_dual(~
chips)',
 PATH='I6',
 DRAWING='@S9S_MB_2U_LIB.S9S_MB_2U(SCH_1):PAGE242',
 PHYS_PAGE='252',
 XY='(-5825,5625)',
 ROT='0',
 VER='1',
 LOCATION='Q77',
 CDS_LIB='pure_quanta',
 CDS_PART_NAME='MOSFET_NCH_DUAL-PJT138K,SMLF,IA',
 PART_TYPE='SMLF',
 MATERIAL='IC',
 VALUE='PJT138K',
 PRIM_FILE='./archive_libs/logical/mosfet_nch_dual/chips/chips.prt';

SECTION_NUMBER 2
 '@S9S_MB_2U_LIB.S9S_MB_2U(SCH_1):PAGE242_I3@PURE_QUANTA.MOSFET_NCH_DUAL(CHIPS)':
 C_PATH='@s9s_mb_2u_lib.s9s_mb_2u(sch_1):page242_i3@pure_quanta.mosfet_nch_dual(~
chips)',
 P_PATH='@s9s_mb_2u_lib.s9s_mb_2u(sch_1):page252_i3@pure_quanta.mosfet_nch_dual(~
chips)',
 PATH='I3',
 DRAWING='@S9S_MB_2U_LIB.S9S_MB_2U(SCH_1):PAGE242',
 PHYS_PAGE='252',
 XY='(-5825,4300)',
 ROT='0',
 VER='2',
 LOCATION='Q77',
 SEC='2',
 CDS_LIB='pure_quanta',
 CDS_PART_NAME='MOSFET_NCH_DUAL-PJT138K,SMLF,IA',
 SEC_TYPE='',
 PART_TYPE='SMLF',
 MATERIAL='IC',
 VALUE='PJT138K',
 PRIM_FILE='./archive_libs/logical/mosfet_nch_dual/chips/chips.prt';

PART_NAME
 Q78 'MOSFET_NCH_DUAL-PJT138K,SMLF,IA':;

SECTION_NUMBER 1
 '@S9S_MB_2U_LIB.S9S_MB_2U(SCH_1):PAGE242_I34@PURE_QUANTA.MOSFET_NCH_DUAL(CHIPS)':
 C_PATH='@s9s_mb_2u_lib.s9s_mb_2u(sch_1):page242_i34@pure_quanta.mosfet_nch_dual~
(chips)',
 P_PATH='@s9s_mb_2u_lib.s9s_mb_2u(sch_1):page252_i34@pure_quanta.mosfet_nch_dual~
(chips)',
 PATH='I34',
 DRAWING='@S9S_MB_2U_LIB.S9S_MB_2U(SCH_1):PAGE242',
 PHYS_PAGE='252',
 XY='(-1050,8175)',
 ROT='0',
 VER='1',
 LOCATION='Q78',
 CDS_LIB='pure_quanta',
 CDS_PART_NAME='MOSFET_NCH_DUAL-PJT138K,SMLF,IA',
 PART_TYPE='SMLF',
 MATERIAL='IC',
 VALUE='PJT138K',
 PRIM_FILE='./archive_libs/logical/mosfet_nch_dual/chips/chips.prt';

SECTION_NUMBER 2
 '@S9S_MB_2U_LIB.S9S_MB_2U(SCH_1):PAGE242_I26@PURE_QUANTA.MOSFET_NCH_DUAL(CHIPS)':
 C_PATH='@s9s_mb_2u_lib.s9s_mb_2u(sch_1):page242_i26@pure_quanta.mosfet_nch_dual~
(chips)',
 P_PATH='@s9s_mb_2u_lib.s9s_mb_2u(sch_1):page252_i26@pure_quanta.mosfet_nch_dual~
(chips)',
 PATH='I26',
 DRAWING='@S9S_MB_2U_LIB.S9S_MB_2U(SCH_1):PAGE242',
 PHYS_PAGE='252',
 XY='(-1050,6850)',
 ROT='0',
 VER='2',
 LOCATION='Q78',
 SEC='2',
 CDS_LIB='pure_quanta',
 CDS_PART_NAME='MOSFET_NCH_DUAL-PJT138K,SMLF,IA',
 SEC_TYPE='',
 PART_TYPE='SMLF',
 MATERIAL='IC',
 VALUE='PJT138K',
 PRIM_FILE='./archive_libs/logical/mosfet_nch_dual/chips/chips.prt';

PART_NAME
 Q79 'MOSFET_NCH_DUAL-PJT138K,SMLF,IA':;

SECTION_NUMBER 1
 '@S9S_MB_2U_LIB.S9S_MB_2U(SCH_1):PAGE305_I8@PURE_QUANTA.MOSFET_NCH_DUAL(CHIPS)':
 C_PATH='@s9s_mb_2u_lib.s9s_mb_2u(sch_1):page305_i8@pure_quanta.mosfet_nch_dual(~
chips)',
 P_PATH='@s9s_mb_2u_lib.s9s_mb_2u(sch_1):page253_i8@pure_quanta.mosfet_nch_dual(~
chips)',
 PATH='I8',
 DRAWING='@S9S_MB_2U_LIB.S9S_MB_2U(SCH_1):PAGE305',
 PHYS_PAGE='253',
 XY='(-2650,4425)',
 ROT='0',
 VER='1',
 LOCATION='Q79',
 CDS_LIB='pure_quanta',
 CDS_PART_NAME='MOSFET_NCH_DUAL-PJT138K,SMLF,IA',
 PART_TYPE='SMLF',
 MATERIAL='IC',
 VALUE='PJT138K',
 PRIM_FILE='./archive_libs/logical/mosfet_nch_dual/chips/chips.prt';

SECTION_NUMBER 2
 '@S9S_MB_2U_LIB.S9S_MB_2U(SCH_1):PAGE305_I7@PURE_QUANTA.MOSFET_NCH_DUAL(CHIPS)':
 C_PATH='@s9s_mb_2u_lib.s9s_mb_2u(sch_1):page305_i7@pure_quanta.mosfet_nch_dual(~
chips)',
 P_PATH='@s9s_mb_2u_lib.s9s_mb_2u(sch_1):page253_i7@pure_quanta.mosfet_nch_dual(~
chips)',
 PATH='I7',
 DRAWING='@S9S_MB_2U_LIB.S9S_MB_2U(SCH_1):PAGE305',
 PHYS_PAGE='253',
 XY='(-2650,3100)',
 ROT='0',
 VER='2',
 LOCATION='Q79',
 SEC='2',
 CDS_LIB='pure_quanta',
 CDS_PART_NAME='MOSFET_NCH_DUAL-PJT138K,SMLF,IA',
 SEC_TYPE='',
 PART_TYPE='SMLF',
 MATERIAL='IC',
 VALUE='PJT138K',
 PRIM_FILE='./archive_libs/logical/mosfet_nch_dual/chips/chips.prt';

PART_NAME
 Q80 'MOSFET_NCH_DUAL-PJT138K,SMLF,IA':;

SECTION_NUMBER 1
 '@S9S_MB_2U_LIB.S9S_MB_2U(SCH_1):PAGE305_I4@PURE_QUANTA.MOSFET_NCH_DUAL(CHIPS)':
 C_PATH='@s9s_mb_2u_lib.s9s_mb_2u(sch_1):page305_i4@pure_quanta.mosfet_nch_dual(~
chips)',
 P_PATH='@s9s_mb_2u_lib.s9s_mb_2u(sch_1):page253_i4@pure_quanta.mosfet_nch_dual(~
chips)',
 PATH='I4',
 DRAWING='@S9S_MB_2U_LIB.S9S_MB_2U(SCH_1):PAGE305',
 PHYS_PAGE='253',
 XY='(-2650,1875)',
 ROT='0',
 VER='1',
 LOCATION='Q80',
 CDS_LIB='pure_quanta',
 CDS_PART_NAME='MOSFET_NCH_DUAL-PJT138K,SMLF,IA',
 PART_TYPE='SMLF',
 MATERIAL='IC',
 VALUE='PJT138K',
 PRIM_FILE='./archive_libs/logical/mosfet_nch_dual/chips/chips.prt';

SECTION_NUMBER 2
 '@S9S_MB_2U_LIB.S9S_MB_2U(SCH_1):PAGE305_I2@PURE_QUANTA.MOSFET_NCH_DUAL(CHIPS)':
 C_PATH='@s9s_mb_2u_lib.s9s_mb_2u(sch_1):page305_i2@pure_quanta.mosfet_nch_dual(~
chips)',
 P_PATH='@s9s_mb_2u_lib.s9s_mb_2u(sch_1):page253_i2@pure_quanta.mosfet_nch_dual(~
chips)',
 PATH='I2',
 DRAWING='@S9S_MB_2U_LIB.S9S_MB_2U(SCH_1):PAGE305',
 PHYS_PAGE='253',
 XY='(-2650,550)',
 ROT='0',
 VER='2',
 LOCATION='Q80',
 SEC='2',
 CDS_LIB='pure_quanta',
 CDS_PART_NAME='MOSFET_NCH_DUAL-PJT138K,SMLF,IA',
 SEC_TYPE='',
 PART_TYPE='SMLF',
 MATERIAL='IC',
 VALUE='PJT138K',
 PRIM_FILE='./archive_libs/logical/mosfet_nch_dual/chips/chips.prt';

PART_NAME
 Q81 'MOSFET_NCH_DUAL-PJT138K,SMLF,IA':;

SECTION_NUMBER 1
 '@S9S_MB_2U_LIB.S9S_MB_2U(SCH_1):PAGE305_I41@PURE_QUANTA.MOSFET_NCH_DUAL(CHIPS)':
 C_PATH='@s9s_mb_2u_lib.s9s_mb_2u(sch_1):page305_i41@pure_quanta.mosfet_nch_dual~
(chips)',
 P_PATH='@s9s_mb_2u_lib.s9s_mb_2u(sch_1):page253_i41@pure_quanta.mosfet_nch_dual~
(chips)',
 PATH='I41',
 DRAWING='@S9S_MB_2U_LIB.S9S_MB_2U(SCH_1):PAGE305',
 PHYS_PAGE='253',
 XY='(2125,4425)',
 ROT='0',
 VER='1',
 LOCATION='Q81',
 CDS_LIB='pure_quanta',
 CDS_PART_NAME='MOSFET_NCH_DUAL-PJT138K,SMLF,IA',
 PART_TYPE='SMLF',
 MATERIAL='IC',
 VALUE='PJT138K',
 PRIM_FILE='./archive_libs/logical/mosfet_nch_dual/chips/chips.prt';

SECTION_NUMBER 2
 '@S9S_MB_2U_LIB.S9S_MB_2U(SCH_1):PAGE305_I40@PURE_QUANTA.MOSFET_NCH_DUAL(CHIPS)':
 C_PATH='@s9s_mb_2u_lib.s9s_mb_2u(sch_1):page305_i40@pure_quanta.mosfet_nch_dual~
(chips)',
 P_PATH='@s9s_mb_2u_lib.s9s_mb_2u(sch_1):page253_i40@pure_quanta.mosfet_nch_dual~
(chips)',
 PATH='I40',
 DRAWING='@S9S_MB_2U_LIB.S9S_MB_2U(SCH_1):PAGE305',
 PHYS_PAGE='253',
 XY='(2125,3100)',
 ROT='0',
 VER='2',
 LOCATION='Q81',
 SEC='2',
 CDS_LIB='pure_quanta',
 CDS_PART_NAME='MOSFET_NCH_DUAL-PJT138K,SMLF,IA',
 SEC_TYPE='',
 PART_TYPE='SMLF',
 MATERIAL='IC',
 VALUE='PJT138K',
 PRIM_FILE='./archive_libs/logical/mosfet_nch_dual/chips/chips.prt';

PART_NAME
 Q83 'MOSFET_NCH_DUAL-PJT138K,SMLF,IA':;

SECTION_NUMBER 1
 '@S9S_MB_2U_LIB.S9S_MB_2U(SCH_1):PAGE305_I32@PURE_QUANTA.MOSFET_NCH_DUAL(CHIPS)':
 C_PATH='@s9s_mb_2u_lib.s9s_mb_2u(sch_1):page305_i32@pure_quanta.mosfet_nch_dual~
(chips)',
 P_PATH='@s9s_mb_2u_lib.s9s_mb_2u(sch_1):page253_i32@pure_quanta.mosfet_nch_dual~
(chips)',
 PATH='I32',
 DRAWING='@S9S_MB_2U_LIB.S9S_MB_2U(SCH_1):PAGE305',
 PHYS_PAGE='253',
 XY='(2125,1850)',
 ROT='0',
 VER='1',
 LOCATION='Q83',
 CDS_LIB='pure_quanta',
 CDS_PART_NAME='MOSFET_NCH_DUAL-PJT138K,SMLF,IA',
 PART_TYPE='SMLF',
 MATERIAL='IC',
 VALUE='PJT138K',
 PRIM_FILE='./archive_libs/logical/mosfet_nch_dual/chips/chips.prt';

SECTION_NUMBER 2
 '@S9S_MB_2U_LIB.S9S_MB_2U(SCH_1):PAGE306_I43@PURE_QUANTA.MOSFET_NCH_DUAL(CHIPS)':
 C_PATH='@s9s_mb_2u_lib.s9s_mb_2u(sch_1):page306_i43@pure_quanta.mosfet_nch_dual~
(chips)',
 P_PATH='@s9s_mb_2u_lib.s9s_mb_2u(sch_1):page254_i43@pure_quanta.mosfet_nch_dual~
(chips)',
 PATH='I43',
 DRAWING='@S9S_MB_2U_LIB.S9S_MB_2U(SCH_1):PAGE306',
 PHYS_PAGE='254',
 XY='(1925,1500)',
 ROT='0',
 VER='2',
 LOCATION='Q83',
 CDS_LIB='pure_quanta',
 CDS_PART_NAME='MOSFET_NCH_DUAL-PJT138K,SMLF,IA',
 PART_TYPE='SMLF',
 MATERIAL='IC',
 VALUE='PJT138K',
 PRIM_FILE='./archive_libs/logical/mosfet_nch_dual/chips/chips.prt';

PART_NAME
 Q84 'MOSFET_NCH_DUAL-PJT138K,SMLF,IA':;

SECTION_NUMBER 1
 '@S9S_MB_2U_LIB.S9S_MB_2U(SCH_1):PAGE306_I18@PURE_QUANTA.MOSFET_NCH_DUAL(CHIPS)':
 C_PATH='@s9s_mb_2u_lib.s9s_mb_2u(sch_1):page306_i18@pure_quanta.mosfet_nch_dual~
(chips)',
 P_PATH='@s9s_mb_2u_lib.s9s_mb_2u(sch_1):page254_i18@pure_quanta.mosfet_nch_dual~
(chips)',
 PATH='I18',
 DRAWING='@S9S_MB_2U_LIB.S9S_MB_2U(SCH_1):PAGE306',
 PHYS_PAGE='254',
 XY='(-2850,4075)',
 ROT='0',
 VER='1',
 LOCATION='Q84',
 CDS_LIB='pure_quanta',
 CDS_PART_NAME='MOSFET_NCH_DUAL-PJT138K,SMLF,IA',
 PART_TYPE='SMLF',
 MATERIAL='IC',
 VALUE='PJT138K',
 PRIM_FILE='./archive_libs/logical/mosfet_nch_dual/chips/chips.prt';

SECTION_NUMBER 2
 '@S9S_MB_2U_LIB.S9S_MB_2U(SCH_1):PAGE306_I8@PURE_QUANTA.MOSFET_NCH_DUAL(CHIPS)':
 C_PATH='@s9s_mb_2u_lib.s9s_mb_2u(sch_1):page306_i8@pure_quanta.mosfet_nch_dual(~
chips)',
 P_PATH='@s9s_mb_2u_lib.s9s_mb_2u(sch_1):page254_i8@pure_quanta.mosfet_nch_dual(~
chips)',
 PATH='I8',
 DRAWING='@S9S_MB_2U_LIB.S9S_MB_2U(SCH_1):PAGE306',
 PHYS_PAGE='254',
 XY='(-2850,2750)',
 ROT='0',
 VER='2',
 LOCATION='Q84',
 SEC='2',
 CDS_LIB='pure_quanta',
 CDS_PART_NAME='MOSFET_NCH_DUAL-PJT138K,SMLF,IA',
 SEC_TYPE='',
 PART_TYPE='SMLF',
 MATERIAL='IC',
 VALUE='PJT138K',
 PRIM_FILE='./archive_libs/logical/mosfet_nch_dual/chips/chips.prt';

PART_NAME
 Q85 'MOSFET_NCH_DUAL-PJT138K,SMLF,IA':;

SECTION_NUMBER 1
 '@S9S_MB_2U_LIB.S9S_MB_2U(SCH_1):PAGE306_I6@PURE_QUANTA.MOSFET_NCH_DUAL(CHIPS)':
 C_PATH='@s9s_mb_2u_lib.s9s_mb_2u(sch_1):page306_i6@pure_quanta.mosfet_nch_dual(~
chips)',
 P_PATH='@s9s_mb_2u_lib.s9s_mb_2u(sch_1):page254_i6@pure_quanta.mosfet_nch_dual(~
chips)',
 PATH='I6',
 DRAWING='@S9S_MB_2U_LIB.S9S_MB_2U(SCH_1):PAGE306',
 PHYS_PAGE='254',
 XY='(-2850,1525)',
 ROT='0',
 VER='1',
 LOCATION='Q85',
 CDS_LIB='pure_quanta',
 CDS_PART_NAME='MOSFET_NCH_DUAL-PJT138K,SMLF,IA',
 PART_TYPE='SMLF',
 MATERIAL='IC',
 VALUE='PJT138K',
 PRIM_FILE='./archive_libs/logical/mosfet_nch_dual/chips/chips.prt';

SECTION_NUMBER 2
 '@S9S_MB_2U_LIB.S9S_MB_2U(SCH_1):PAGE306_I3@PURE_QUANTA.MOSFET_NCH_DUAL(CHIPS)':
 C_PATH='@s9s_mb_2u_lib.s9s_mb_2u(sch_1):page306_i3@pure_quanta.mosfet_nch_dual(~
chips)',
 P_PATH='@s9s_mb_2u_lib.s9s_mb_2u(sch_1):page254_i3@pure_quanta.mosfet_nch_dual(~
chips)',
 PATH='I3',
 DRAWING='@S9S_MB_2U_LIB.S9S_MB_2U(SCH_1):PAGE306',
 PHYS_PAGE='254',
 XY='(-2850,200)',
 ROT='0',
 VER='2',
 LOCATION='Q85',
 SEC='2',
 CDS_LIB='pure_quanta',
 CDS_PART_NAME='MOSFET_NCH_DUAL-PJT138K,SMLF,IA',
 SEC_TYPE='',
 PART_TYPE='SMLF',
 MATERIAL='IC',
 VALUE='PJT138K',
 PRIM_FILE='./archive_libs/logical/mosfet_nch_dual/chips/chips.prt';

PART_NAME
 Q86 'MOSFET_NCH_DUAL-PJT138K,SMLF,IA':;

SECTION_NUMBER 1
 '@S9S_MB_2U_LIB.S9S_MB_2U(SCH_1):PAGE306_I35@PURE_QUANTA.MOSFET_NCH_DUAL(CHIPS)':
 C_PATH='@s9s_mb_2u_lib.s9s_mb_2u(sch_1):page306_i35@pure_quanta.mosfet_nch_dual~
(chips)',
 P_PATH='@s9s_mb_2u_lib.s9s_mb_2u(sch_1):page254_i35@pure_quanta.mosfet_nch_dual~
(chips)',
 PATH='I35',
 DRAWING='@S9S_MB_2U_LIB.S9S_MB_2U(SCH_1):PAGE306',
 PHYS_PAGE='254',
 XY='(1925,4075)',
 ROT='0',
 VER='1',
 LOCATION='Q86',
 CDS_LIB='pure_quanta',
 CDS_PART_NAME='MOSFET_NCH_DUAL-PJT138K,SMLF,IA',
 PART_TYPE='SMLF',
 MATERIAL='IC',
 VALUE='PJT138K',
 PRIM_FILE='./archive_libs/logical/mosfet_nch_dual/chips/chips.prt';

SECTION_NUMBER 2
 '@S9S_MB_2U_LIB.S9S_MB_2U(SCH_1):PAGE306_I27@PURE_QUANTA.MOSFET_NCH_DUAL(CHIPS)':
 C_PATH='@s9s_mb_2u_lib.s9s_mb_2u(sch_1):page306_i27@pure_quanta.mosfet_nch_dual~
(chips)',
 P_PATH='@s9s_mb_2u_lib.s9s_mb_2u(sch_1):page254_i27@pure_quanta.mosfet_nch_dual~
(chips)',
 PATH='I27',
 DRAWING='@S9S_MB_2U_LIB.S9S_MB_2U(SCH_1):PAGE306',
 PHYS_PAGE='254',
 XY='(1925,2750)',
 ROT='0',
 VER='2',
 LOCATION='Q86',
 SEC='2',
 CDS_LIB='pure_quanta',
 CDS_PART_NAME='MOSFET_NCH_DUAL-PJT138K,SMLF,IA',
 SEC_TYPE='',
 PART_TYPE='SMLF',
 MATERIAL='IC',
 VALUE='PJT138K',
 PRIM_FILE='./archive_libs/logical/mosfet_nch_dual/chips/chips.prt';

PART_NAME
 Q87 'MOSFET_NCH_DUAL-PJT138K,SMLF,IA':;

SECTION_NUMBER 1
 '@S9S_MB_2U_LIB.S9S_MB_2U(SCH_1):PAGE241_I17@PURE_QUANTA.MOSFET_NCH_DUAL(CHIPS)':
 C_PATH='@s9s_mb_2u_lib.s9s_mb_2u(sch_1):page241_i17@pure_quanta.mosfet_nch_dual~
(chips)',
 P_PATH='@s9s_mb_2u_lib.s9s_mb_2u(sch_1):page255_i17@pure_quanta.mosfet_nch_dual~
(chips)',
 PATH='I17',
 DRAWING='@S9S_MB_2U_LIB.S9S_MB_2U(SCH_1):PAGE241',
 PHYS_PAGE='255',
 XY='(-13500,3075)',
 ROT='0',
 VER='1',
 LOCATION='Q87',
 CDS_LIB='pure_quanta',
 CDS_PART_NAME='MOSFET_NCH_DUAL-PJT138K,SMLF,IA',
 PART_TYPE='SMLF',
 MATERIAL='IC',
 VALUE='PJT138K',
 PRIM_FILE='./archive_libs/logical/mosfet_nch_dual/chips/chips.prt';

SECTION_NUMBER 2
 '@S9S_MB_2U_LIB.S9S_MB_2U(SCH_1):PAGE241_I16@PURE_QUANTA.MOSFET_NCH_DUAL(CHIPS)':
 C_PATH='@s9s_mb_2u_lib.s9s_mb_2u(sch_1):page241_i16@pure_quanta.mosfet_nch_dual~
(chips)',
 P_PATH='@s9s_mb_2u_lib.s9s_mb_2u(sch_1):page255_i16@pure_quanta.mosfet_nch_dual~
(chips)',
 PATH='I16',
 DRAWING='@S9S_MB_2U_LIB.S9S_MB_2U(SCH_1):PAGE241',
 PHYS_PAGE='255',
 XY='(-13500,1800)',
 ROT='0',
 VER='2',
 LOCATION='Q87',
 SEC='2',
 CDS_LIB='pure_quanta',
 CDS_PART_NAME='MOSFET_NCH_DUAL-PJT138K,SMLF,IA',
 SEC_TYPE='',
 PART_TYPE='SMLF',
 MATERIAL='IC',
 VALUE='PJT138K',
 PRIM_FILE='./archive_libs/logical/mosfet_nch_dual/chips/chips.prt';

PART_NAME
 Q88 'MOSFET_NCH_DUAL-PJT138K,SMLF,IA':;

SECTION_NUMBER 1
 '@S9S_MB_2U_LIB.S9S_MB_2U(SCH_1):PAGE241_I8@PURE_QUANTA.MOSFET_NCH_DUAL(CHIPS)':
 C_PATH='@s9s_mb_2u_lib.s9s_mb_2u(sch_1):page241_i8@pure_quanta.mosfet_nch_dual(~
chips)',
 P_PATH='@s9s_mb_2u_lib.s9s_mb_2u(sch_1):page255_i8@pure_quanta.mosfet_nch_dual(~
chips)',
 PATH='I8',
 DRAWING='@S9S_MB_2U_LIB.S9S_MB_2U(SCH_1):PAGE241',
 PHYS_PAGE='255',
 XY='(-13450,425)',
 ROT='0',
 VER='1',
 LOCATION='Q88',
 CDS_LIB='pure_quanta',
 CDS_PART_NAME='MOSFET_NCH_DUAL-PJT138K,SMLF,IA',
 PART_TYPE='SMLF',
 MATERIAL='IC',
 VALUE='PJT138K',
 PRIM_FILE='./archive_libs/logical/mosfet_nch_dual/chips/chips.prt';

SECTION_NUMBER 2
 '@S9S_MB_2U_LIB.S9S_MB_2U(SCH_1):PAGE241_I42@PURE_QUANTA.MOSFET_NCH_DUAL(CHIPS)':
 C_PATH='@s9s_mb_2u_lib.s9s_mb_2u(sch_1):page241_i42@pure_quanta.mosfet_nch_dual~
(chips)',
 P_PATH='@s9s_mb_2u_lib.s9s_mb_2u(sch_1):page255_i42@pure_quanta.mosfet_nch_dual~
(chips)',
 PATH='I42',
 DRAWING='@S9S_MB_2U_LIB.S9S_MB_2U(SCH_1):PAGE241',
 PHYS_PAGE='255',
 XY='(-13425,-1025)',
 ROT='0',
 VER='2',
 LOCATION='Q88',
 CDS_LIB='pure_quanta',
 CDS_PART_NAME='MOSFET_NCH_DUAL-PJT138K,SMLF,IA',
 PART_TYPE='SMLF',
 MATERIAL='IC',
 VALUE='PJT138K',
 PRIM_FILE='./archive_libs/logical/mosfet_nch_dual/chips/chips.prt';

PART_NAME
 Q95 'MOSFET_NCH_DUAL-PJT138K,SMLF,IA':;

SECTION_NUMBER 1
 '@S9S_MB_2U_LIB.S9S_MB_2U(SCH_1):PAGE182_I342@PURE_QUANTA.MOSFET_NCH_DUAL(CHIPS)':
 C_PATH='@s9s_mb_2u_lib.s9s_mb_2u(sch_1):page182_i342@pure_quanta.mosfet_nch_dua~
l(chips)',
 P_PATH='@s9s_mb_2u_lib.s9s_mb_2u(sch_1):page190_i342@pure_quanta.mosfet_nch_dua~
l(chips)',
 PATH='I342',
 DRAWING='@S9S_MB_2U_LIB.S9S_MB_2U(SCH_1):PAGE182',
 PHYS_PAGE='190',
 XY='(9800,-50)',
 ROT='0',
 VER='1',
 LOCATION='Q95',
 CDS_LIB='pure_quanta',
 CDS_PART_NAME='MOSFET_NCH_DUAL-PJT138K,SMLF,IA',
 PART_TYPE='SMLF',
 MATERIAL='IC',
 VALUE='PJT138K',
 PRIM_FILE='./archive_libs/logical/mosfet_nch_dual/chips/chips.prt';

SECTION_NUMBER 2
 '@S9S_MB_2U_LIB.S9S_MB_2U(SCH_1):PAGE182_I343@PURE_QUANTA.MOSFET_NCH_DUAL(CHIPS)':
 C_PATH='@s9s_mb_2u_lib.s9s_mb_2u(sch_1):page182_i343@pure_quanta.mosfet_nch_dua~
l(chips)',
 P_PATH='@s9s_mb_2u_lib.s9s_mb_2u(sch_1):page190_i343@pure_quanta.mosfet_nch_dua~
l(chips)',
 PATH='I343',
 DRAWING='@S9S_MB_2U_LIB.S9S_MB_2U(SCH_1):PAGE182',
 PHYS_PAGE='190',
 XY='(10100,-775)',
 ROT='0',
 VER='2',
 LOCATION='Q95',
 CDS_LIB='pure_quanta',
 CDS_PART_NAME='MOSFET_NCH_DUAL-PJT138K,SMLF,IA',
 PART_TYPE='SMLF',
 MATERIAL='IC',
 VALUE='PJT138K',
 PRIM_FILE='./archive_libs/logical/mosfet_nch_dual/chips/chips.prt';

PART_NAME
 Q96 'MOSFET_NCH_DUAL-PJT138K,SMLF,IA':;

SECTION_NUMBER 1
 '@S9S_MB_2U_LIB.S9S_MB_2U(SCH_1):PAGE145_I154@PURE_QUANTA.MOSFET_NCH_DUAL(CHIPS)':
 C_PATH='@s9s_mb_2u_lib.s9s_mb_2u(sch_1):page145_i154@pure_quanta.mosfet_nch_dua~
l(chips)',
 P_PATH='@s9s_mb_2u_lib.s9s_mb_2u(sch_1):page148_i154@pure_quanta.mosfet_nch_dua~
l(chips)',
 PATH='I154',
 DRAWING='@S9S_MB_2U_LIB.S9S_MB_2U(SCH_1):PAGE145',
 PHYS_PAGE='148',
 XY='(1025,3225)',
 ROT='0',
 VER='1',
 CDS_LIB='pure_quanta',
 CDS_PART_NAME='MOSFET_NCH_DUAL-PJT138K,SMLF,IA',
 PART_TYPE='SMLF',
 MATERIAL='IC',
 VALUE='PJT138K',
 PRIM_FILE='./archive_libs/logical/mosfet_nch_dual/chips/chips.prt';

SECTION_NUMBER 2
 '@S9S_MB_2U_LIB.S9S_MB_2U(SCH_1):PAGE145_I159@PURE_QUANTA.MOSFET_NCH_DUAL(CHIPS)':
 C_PATH='@s9s_mb_2u_lib.s9s_mb_2u(sch_1):page145_i159@pure_quanta.mosfet_nch_dua~
l(chips)',
 P_PATH='@s9s_mb_2u_lib.s9s_mb_2u(sch_1):page148_i159@pure_quanta.mosfet_nch_dua~
l(chips)',
 PATH='I159',
 DRAWING='@S9S_MB_2U_LIB.S9S_MB_2U(SCH_1):PAGE145',
 PHYS_PAGE='148',
 XY='(1950,3500)',
 ROT='0',
 VER='2',
 LOCATION='Q96',
 CDS_LIB='pure_quanta',
 CDS_PART_NAME='MOSFET_NCH_DUAL-PJT138K,SMLF,IA',
 PART_TYPE='SMLF',
 MATERIAL='IC',
 VALUE='PJT138K',
 PRIM_FILE='./archive_libs/logical/mosfet_nch_dual/chips/chips.prt';

PART_NAME
 Q97 'MOSFET_NCH_DUAL-NX6008NBKS,SMLA':;

SECTION_NUMBER 1
 '@S9S_MB_2U_LIB.S9S_MB_2U(SCH_1):PAGE304_I71@PURE_QUANTA.MOSFET_NCH_DUAL(CHIPS)':
 C_PATH='@s9s_mb_2u_lib.s9s_mb_2u(sch_1):page304_i71@pure_quanta.mosfet_nch_dual~
(chips)',
 P_PATH='@s9s_mb_2u_lib.s9s_mb_2u(sch_1):page256_i71@pure_quanta.mosfet_nch_dual~
(chips)',
 PATH='I71',
 DRAWING='@S9S_MB_2U_LIB.S9S_MB_2U(SCH_1):PAGE304',
 PHYS_PAGE='256',
 XY='(-2875,900)',
 ROT='0',
 VER='1',
 CDS_LIB='pure_quanta',
 CDS_PART_NAME='MOSFET_NCH_DUAL-NX6008NBKS,SMLA',
 PART_TYPE='SMLF',
 MATERIAL='IC',
 VALUE='NX6008NBKS',
 PRIM_FILE='./archive_libs/logical/mosfet_nch_dual/chips/chips.prt';

SECTION_NUMBER 2
 '@S9S_MB_2U_LIB.S9S_MB_2U(SCH_1):PAGE304_I70@PURE_QUANTA.MOSFET_NCH_DUAL(CHIPS)':
 C_PATH='@s9s_mb_2u_lib.s9s_mb_2u(sch_1):page304_i70@pure_quanta.mosfet_nch_dual~
(chips)',
 P_PATH='@s9s_mb_2u_lib.s9s_mb_2u(sch_1):page256_i70@pure_quanta.mosfet_nch_dual~
(chips)',
 PATH='I70',
 DRAWING='@S9S_MB_2U_LIB.S9S_MB_2U(SCH_1):PAGE304',
 PHYS_PAGE='256',
 XY='(-2675,-450)',
 ROT='0',
 VER='2',
 CDS_LIB='pure_quanta',
 CDS_PART_NAME='MOSFET_NCH_DUAL-NX6008NBKS,SMLA',
 PART_TYPE='SMLF',
 MATERIAL='IC',
 VALUE='NX6008NBKS',
 PRIM_FILE='./archive_libs/logical/mosfet_nch_dual/chips/chips.prt';

PART_NAME
 Q98 'MOSFET_NCH_DUAL-NX6008NBKS,SMLA':;

SECTION_NUMBER 1
 '@S9S_MB_2U_LIB.S9S_MB_2U(SCH_1):PAGE304_I68@PURE_QUANTA.MOSFET_NCH_DUAL(CHIPS)':
 C_PATH='@s9s_mb_2u_lib.s9s_mb_2u(sch_1):page304_i68@pure_quanta.mosfet_nch_dual~
(chips)',
 P_PATH='@s9s_mb_2u_lib.s9s_mb_2u(sch_1):page256_i68@pure_quanta.mosfet_nch_dual~
(chips)',
 PATH='I68',
 DRAWING='@S9S_MB_2U_LIB.S9S_MB_2U(SCH_1):PAGE304',
 PHYS_PAGE='256',
 XY='(-2850,4175)',
 ROT='0',
 VER='1',
 CDS_LIB='pure_quanta',
 CDS_PART_NAME='MOSFET_NCH_DUAL-NX6008NBKS,SMLA',
 PART_TYPE='SMLF',
 MATERIAL='IC',
 VALUE='NX6008NBKS',
 PRIM_FILE='./archive_libs/logical/mosfet_nch_dual/chips/chips.prt';

SECTION_NUMBER 2
 '@S9S_MB_2U_LIB.S9S_MB_2U(SCH_1):PAGE304_I69@PURE_QUANTA.MOSFET_NCH_DUAL(CHIPS)':
 C_PATH='@s9s_mb_2u_lib.s9s_mb_2u(sch_1):page304_i69@pure_quanta.mosfet_nch_dual~
(chips)',
 P_PATH='@s9s_mb_2u_lib.s9s_mb_2u(sch_1):page256_i69@pure_quanta.mosfet_nch_dual~
(chips)',
 PATH='I69',
 DRAWING='@S9S_MB_2U_LIB.S9S_MB_2U(SCH_1):PAGE304',
 PHYS_PAGE='256',
 XY='(-2850,2575)',
 ROT='0',
 VER='2',
 CDS_LIB='pure_quanta',
 CDS_PART_NAME='MOSFET_NCH_DUAL-NX6008NBKS,SMLA',
 PART_TYPE='SMLF',
 MATERIAL='IC',
 VALUE='NX6008NBKS',
 PRIM_FILE='./archive_libs/logical/mosfet_nch_dual/chips/chips.prt';

PART_NAME
 Q99 'MOSFET_NCH_DUAL-NX6008NBKS,SMLA':;

SECTION_NUMBER 1
 '@S9S_MB_2U_LIB.S9S_MB_2U(SCH_1):PAGE304_I72@PURE_QUANTA.MOSFET_NCH_DUAL(CHIPS)':
 C_PATH='@s9s_mb_2u_lib.s9s_mb_2u(sch_1):page304_i72@pure_quanta.mosfet_nch_dual~
(chips)',
 P_PATH='@s9s_mb_2u_lib.s9s_mb_2u(sch_1):page256_i72@pure_quanta.mosfet_nch_dual~
(chips)',
 PATH='I72',
 DRAWING='@S9S_MB_2U_LIB.S9S_MB_2U(SCH_1):PAGE304',
 PHYS_PAGE='256',
 XY='(1625,2725)',
 ROT='0',
 VER='1',
 CDS_LIB='pure_quanta',
 CDS_PART_NAME='MOSFET_NCH_DUAL-NX6008NBKS,SMLA',
 PART_TYPE='SMLF',
 MATERIAL='IC',
 VALUE='NX6008NBKS',
 PRIM_FILE='./archive_libs/logical/mosfet_nch_dual/chips/chips.prt';

PART_NAME
 Q100 'MOSFET_NCH_DUAL-NX6008NBKS,SMLA':;

SECTION_NUMBER 1
 '@S9S_MB_2U_LIB.S9S_MB_2U(SCH_1):PAGE304_I74@PURE_QUANTA.MOSFET_NCH_DUAL(CHIPS)':
 C_PATH='@s9s_mb_2u_lib.s9s_mb_2u(sch_1):page304_i74@pure_quanta.mosfet_nch_dual~
(chips)',
 P_PATH='@s9s_mb_2u_lib.s9s_mb_2u(sch_1):page256_i74@pure_quanta.mosfet_nch_dual~
(chips)',
 PATH='I74',
 DRAWING='@S9S_MB_2U_LIB.S9S_MB_2U(SCH_1):PAGE304',
 PHYS_PAGE='256',
 XY='(1650,975)',
 ROT='0',
 VER='1',
 CDS_LIB='pure_quanta',
 CDS_PART_NAME='MOSFET_NCH_DUAL-NX6008NBKS,SMLA',
 PART_TYPE='SMLF',
 MATERIAL='IC',
 VALUE='NX6008NBKS',
 PRIM_FILE='./archive_libs/logical/mosfet_nch_dual/chips/chips.prt';

SECTION_NUMBER 2
 '@S9S_MB_2U_LIB.S9S_MB_2U(SCH_1):PAGE304_I75@PURE_QUANTA.MOSFET_NCH_DUAL(CHIPS)':
 C_PATH='@s9s_mb_2u_lib.s9s_mb_2u(sch_1):page304_i75@pure_quanta.mosfet_nch_dual~
(chips)',
 P_PATH='@s9s_mb_2u_lib.s9s_mb_2u(sch_1):page256_i75@pure_quanta.mosfet_nch_dual~
(chips)',
 PATH='I75',
 DRAWING='@S9S_MB_2U_LIB.S9S_MB_2U(SCH_1):PAGE304',
 PHYS_PAGE='256',
 XY='(1850,-375)',
 ROT='0',
 VER='2',
 CDS_LIB='pure_quanta',
 CDS_PART_NAME='MOSFET_NCH_DUAL-NX6008NBKS,SMLA',
 PART_TYPE='SMLF',
 MATERIAL='IC',
 VALUE='NX6008NBKS',
 PRIM_FILE='./archive_libs/logical/mosfet_nch_dual/chips/chips.prt';

PART_NAME
 Q101 'MOSFET_NCH_DUAL-PJT138K,SMLF,IA':;

SECTION_NUMBER 1
 '@S9S_MB_2U_LIB.S9S_MB_2U(SCH_1):PAGE299_I52@PURE_QUANTA.MOSFET_NCH_DUAL(CHIPS)':
 C_PATH='@s9s_mb_2u_lib.s9s_mb_2u(sch_1):page299_i52@pure_quanta.mosfet_nch_dual~
(chips)',
 P_PATH='@s9s_mb_2u_lib.s9s_mb_2u(sch_1):page147_i52@pure_quanta.mosfet_nch_dual~
(chips)',
 PATH='I52',
 DRAWING='@S9S_MB_2U_LIB.S9S_MB_2U(SCH_1):PAGE299',
 PHYS_PAGE='147',
 XY='(-1875,3775)',
 ROT='0',
 VER='1',
 CDS_LIB='pure_quanta',
 CDS_PART_NAME='MOSFET_NCH_DUAL-PJT138K,SMLF,IA',
 PART_TYPE='SMLF',
 MATERIAL='IC',
 VALUE='PJT138K',
 PRIM_FILE='./archive_libs/logical/mosfet_nch_dual/chips/chips.prt';

SECTION_NUMBER 2
 '@S9S_MB_2U_LIB.S9S_MB_2U(SCH_1):PAGE299_I57@PURE_QUANTA.MOSFET_NCH_DUAL(CHIPS)':
 C_PATH='@s9s_mb_2u_lib.s9s_mb_2u(sch_1):page299_i57@pure_quanta.mosfet_nch_dual~
(chips)',
 P_PATH='@s9s_mb_2u_lib.s9s_mb_2u(sch_1):page147_i57@pure_quanta.mosfet_nch_dual~
(chips)',
 PATH='I57',
 DRAWING='@S9S_MB_2U_LIB.S9S_MB_2U(SCH_1):PAGE299',
 PHYS_PAGE='147',
 XY='(-725,4075)',
 ROT='0',
 VER='2',
 CDS_LIB='pure_quanta',
 CDS_PART_NAME='MOSFET_NCH_DUAL-PJT138K,SMLF,IA',
 PART_TYPE='SMLF',
 MATERIAL='IC',
 VALUE='PJT138K',
 PRIM_FILE='./archive_libs/logical/mosfet_nch_dual/chips/chips.prt';

PART_NAME
 Q102 'MOSFET_NCH_DUAL-PJT138K,SMLF,IA':;

SECTION_NUMBER 1
 '@S9S_MB_2U_LIB.S9S_MB_2U(SCH_1):PAGE299_I40@PURE_QUANTA.MOSFET_NCH_DUAL(CHIPS)':
 C_PATH='@s9s_mb_2u_lib.s9s_mb_2u(sch_1):page299_i40@pure_quanta.mosfet_nch_dual~
(chips)',
 P_PATH='@s9s_mb_2u_lib.s9s_mb_2u(sch_1):page147_i40@pure_quanta.mosfet_nch_dual~
(chips)',
 PATH='I40',
 DRAWING='@S9S_MB_2U_LIB.S9S_MB_2U(SCH_1):PAGE299',
 PHYS_PAGE='147',
 XY='(-1800,2375)',
 ROT='0',
 VER='1',
 CDS_LIB='pure_quanta',
 CDS_PART_NAME='MOSFET_NCH_DUAL-PJT138K,SMLF,IA',
 PART_TYPE='SMLF',
 MATERIAL='IC',
 VALUE='PJT138K',
 PRIM_FILE='./archive_libs/logical/mosfet_nch_dual/chips/chips.prt';

SECTION_NUMBER 2
 '@S9S_MB_2U_LIB.S9S_MB_2U(SCH_1):PAGE299_I48@PURE_QUANTA.MOSFET_NCH_DUAL(CHIPS)':
 C_PATH='@s9s_mb_2u_lib.s9s_mb_2u(sch_1):page299_i48@pure_quanta.mosfet_nch_dual~
(chips)',
 P_PATH='@s9s_mb_2u_lib.s9s_mb_2u(sch_1):page147_i48@pure_quanta.mosfet_nch_dual~
(chips)',
 PATH='I48',
 DRAWING='@S9S_MB_2U_LIB.S9S_MB_2U(SCH_1):PAGE299',
 PHYS_PAGE='147',
 XY='(-825,2675)',
 ROT='0',
 VER='2',
 CDS_LIB='pure_quanta',
 CDS_PART_NAME='MOSFET_NCH_DUAL-PJT138K,SMLF,IA',
 PART_TYPE='SMLF',
 MATERIAL='IC',
 VALUE='PJT138K',
 PRIM_FILE='./archive_libs/logical/mosfet_nch_dual/chips/chips.prt';

PART_NAME
 Q103 'MOSFET_NCH_DUAL-PJT138K,SMLF,IA':;

SECTION_NUMBER 1
 '@S9S_MB_2U_LIB.S9S_MB_2U(SCH_1):PAGE299_I37@PURE_QUANTA.MOSFET_NCH_DUAL(CHIPS)':
 C_PATH='@s9s_mb_2u_lib.s9s_mb_2u(sch_1):page299_i37@pure_quanta.mosfet_nch_dual~
(chips)',
 P_PATH='@s9s_mb_2u_lib.s9s_mb_2u(sch_1):page147_i37@pure_quanta.mosfet_nch_dual~
(chips)',
 PATH='I37',
 DRAWING='@S9S_MB_2U_LIB.S9S_MB_2U(SCH_1):PAGE299',
 PHYS_PAGE='147',
 XY='(-1800,1025)',
 ROT='0',
 VER='1',
 CDS_LIB='pure_quanta',
 CDS_PART_NAME='MOSFET_NCH_DUAL-PJT138K,SMLF,IA',
 PART_TYPE='SMLF',
 MATERIAL='IC',
 VALUE='PJT138K',
 PRIM_FILE='./archive_libs/logical/mosfet_nch_dual/chips/chips.prt';

SECTION_NUMBER 2
 '@S9S_MB_2U_LIB.S9S_MB_2U(SCH_1):PAGE299_I43@PURE_QUANTA.MOSFET_NCH_DUAL(CHIPS)':
 C_PATH='@s9s_mb_2u_lib.s9s_mb_2u(sch_1):page299_i43@pure_quanta.mosfet_nch_dual~
(chips)',
 P_PATH='@s9s_mb_2u_lib.s9s_mb_2u(sch_1):page147_i43@pure_quanta.mosfet_nch_dual~
(chips)',
 PATH='I43',
 DRAWING='@S9S_MB_2U_LIB.S9S_MB_2U(SCH_1):PAGE299',
 PHYS_PAGE='147',
 XY='(-850,1300)',
 ROT='0',
 VER='2',
 LOCATION='Q103',
 CDS_LIB='pure_quanta',
 CDS_PART_NAME='MOSFET_NCH_DUAL-PJT138K,SMLF,IA',
 PART_TYPE='SMLF',
 MATERIAL='IC',
 VALUE='PJT138K',
 PRIM_FILE='./archive_libs/logical/mosfet_nch_dual/chips/chips.prt';

PART_NAME
 Q104 'MOSFET_NCH_DUAL-PJT138K,SMLF,IA':;

SECTION_NUMBER 1
 '@S9S_MB_2U_LIB.S9S_MB_2U(SCH_1):PAGE299_I21@PURE_QUANTA.MOSFET_NCH_DUAL(CHIPS)':
 C_PATH='@s9s_mb_2u_lib.s9s_mb_2u(sch_1):page299_i21@pure_quanta.mosfet_nch_dual~
(chips)',
 P_PATH='@s9s_mb_2u_lib.s9s_mb_2u(sch_1):page147_i21@pure_quanta.mosfet_nch_dual~
(chips)',
 PATH='I21',
 DRAWING='@S9S_MB_2U_LIB.S9S_MB_2U(SCH_1):PAGE299',
 PHYS_PAGE='147',
 XY='(-1775,-550)',
 ROT='0',
 VER='1',
 CDS_LIB='pure_quanta',
 CDS_PART_NAME='MOSFET_NCH_DUAL-PJT138K,SMLF,IA',
 PART_TYPE='SMLF',
 MATERIAL='IC',
 VALUE='PJT138K',
 PRIM_FILE='./archive_libs/logical/mosfet_nch_dual/chips/chips.prt';

SECTION_NUMBER 2
 '@S9S_MB_2U_LIB.S9S_MB_2U(SCH_1):PAGE299_I26@PURE_QUANTA.MOSFET_NCH_DUAL(CHIPS)':
 C_PATH='@s9s_mb_2u_lib.s9s_mb_2u(sch_1):page299_i26@pure_quanta.mosfet_nch_dual~
(chips)',
 P_PATH='@s9s_mb_2u_lib.s9s_mb_2u(sch_1):page147_i26@pure_quanta.mosfet_nch_dual~
(chips)',
 PATH='I26',
 DRAWING='@S9S_MB_2U_LIB.S9S_MB_2U(SCH_1):PAGE299',
 PHYS_PAGE='147',
 XY='(-850,-275)',
 ROT='0',
 VER='2',
 LOCATION='Q104',
 CDS_LIB='pure_quanta',
 CDS_PART_NAME='MOSFET_NCH_DUAL-PJT138K,SMLF,IA',
 PART_TYPE='SMLF',
 MATERIAL='IC',
 VALUE='PJT138K',
 PRIM_FILE='./archive_libs/logical/mosfet_nch_dual/chips/chips.prt';

PART_NAME
 Q105 'MOSFET_NCH_DUAL-NX6008NBKS,SMLA':;

SECTION_NUMBER 1
 '@S9S_MB_2U_LIB.S9S_MB_2U(SCH_1):PAGE304_I76@PURE_QUANTA.MOSFET_NCH_DUAL(CHIPS)':
 C_PATH='@s9s_mb_2u_lib.s9s_mb_2u(sch_1):page304_i76@pure_quanta.mosfet_nch_dual~
(chips)',
 P_PATH='@s9s_mb_2u_lib.s9s_mb_2u(sch_1):page256_i76@pure_quanta.mosfet_nch_dual~
(chips)',
 PATH='I76',
 DRAWING='@S9S_MB_2U_LIB.S9S_MB_2U(SCH_1):PAGE304',
 PHYS_PAGE='256',
 XY='(1625,4150)',
 ROT='0',
 VER='1',
 CDS_LIB='pure_quanta',
 CDS_PART_NAME='MOSFET_NCH_DUAL-NX6008NBKS,SMLA',
 PART_TYPE='SMLF',
 MATERIAL='IC',
 VALUE='NX6008NBKS',
 PRIM_FILE='./archive_libs/logical/mosfet_nch_dual/chips/chips.prt';

PART_NAME
 Q106 'MOSFET_NCH_DUAL-PJT138K,SMLF,IA':;

SECTION_NUMBER 1
 '@S9S_MB_2U_LIB.S9S_MB_2U(SCH_1):PAGE299_I135@PURE_QUANTA.MOSFET_NCH_DUAL(CHIPS)':
 C_PATH='@s9s_mb_2u_lib.s9s_mb_2u(sch_1):page299_i135@pure_quanta.mosfet_nch_dua~
l(chips)',
 P_PATH='@s9s_mb_2u_lib.s9s_mb_2u(sch_1):page147_i135@pure_quanta.mosfet_nch_dua~
l(chips)',
 PATH='I135',
 DRAWING='@S9S_MB_2U_LIB.S9S_MB_2U(SCH_1):PAGE299',
 PHYS_PAGE='147',
 XY='(3300,4225)',
 ROT='0',
 VER='1',
 CDS_LIB='pure_quanta',
 CDS_PART_NAME='MOSFET_NCH_DUAL-PJT138K,SMLF,IA',
 PART_TYPE='SMLF',
 MATERIAL='IC',
 VALUE='PJT138K',
 PRIM_FILE='./archive_libs/logical/mosfet_nch_dual/chips/chips.prt';

PART_NAME
 Q107 'MOSFET_NCH_DUAL-PJT138K,SMLF,IA':;

SECTION_NUMBER 1
 '@S9S_MB_2U_LIB.S9S_MB_2U(SCH_1):PAGE299_I160@PURE_QUANTA.MOSFET_NCH_DUAL(CHIPS)':
 C_PATH='@s9s_mb_2u_lib.s9s_mb_2u(sch_1):page299_i160@pure_quanta.mosfet_nch_dua~
l(chips)',
 P_PATH='@s9s_mb_2u_lib.s9s_mb_2u(sch_1):page147_i160@pure_quanta.mosfet_nch_dua~
l(chips)',
 PATH='I160',
 DRAWING='@S9S_MB_2U_LIB.S9S_MB_2U(SCH_1):PAGE299',
 PHYS_PAGE='147',
 XY='(2925,2550)',
 ROT='0',
 VER='1',
 CDS_LIB='pure_quanta',
 CDS_PART_NAME='MOSFET_NCH_DUAL-PJT138K,SMLF,IA',
 PART_TYPE='SMLF',
 MATERIAL='IC',
 VALUE='PJT138K',
 PRIM_FILE='./archive_libs/logical/mosfet_nch_dual/chips/chips.prt';

SECTION_NUMBER 2
 '@S9S_MB_2U_LIB.S9S_MB_2U(SCH_1):PAGE299_I157@PURE_QUANTA.MOSFET_NCH_DUAL(CHIPS)':
 C_PATH='@s9s_mb_2u_lib.s9s_mb_2u(sch_1):page299_i157@pure_quanta.mosfet_nch_dua~
l(chips)',
 P_PATH='@s9s_mb_2u_lib.s9s_mb_2u(sch_1):page147_i157@pure_quanta.mosfet_nch_dua~
l(chips)',
 PATH='I157',
 DRAWING='@S9S_MB_2U_LIB.S9S_MB_2U(SCH_1):PAGE299',
 PHYS_PAGE='147',
 XY='(3850,2825)',
 ROT='0',
 VER='2',
 LOCATION='Q107',
 CDS_LIB='pure_quanta',
 CDS_PART_NAME='MOSFET_NCH_DUAL-PJT138K,SMLF,IA',
 PART_TYPE='SMLF',
 MATERIAL='IC',
 VALUE='PJT138K',
 PRIM_FILE='./archive_libs/logical/mosfet_nch_dual/chips/chips.prt';

PART_NAME
 Q108 'MOSFET_NCH_DUAL-PJT138K,SMLF,IA':;

SECTION_NUMBER 1
 '@S9S_MB_2U_LIB.S9S_MB_2U(SCH_1):PAGE299_I169@PURE_QUANTA.MOSFET_NCH_DUAL(CHIPS)':
 C_PATH='@s9s_mb_2u_lib.s9s_mb_2u(sch_1):page299_i169@pure_quanta.mosfet_nch_dua~
l(chips)',
 P_PATH='@s9s_mb_2u_lib.s9s_mb_2u(sch_1):page147_i169@pure_quanta.mosfet_nch_dua~
l(chips)',
 PATH='I169',
 DRAWING='@S9S_MB_2U_LIB.S9S_MB_2U(SCH_1):PAGE299',
 PHYS_PAGE='147',
 XY='(2900,925)',
 ROT='0',
 VER='1',
 CDS_LIB='pure_quanta',
 CDS_PART_NAME='MOSFET_NCH_DUAL-PJT138K,SMLF,IA',
 PART_TYPE='SMLF',
 MATERIAL='IC',
 VALUE='PJT138K',
 PRIM_FILE='./archive_libs/logical/mosfet_nch_dual/chips/chips.prt';

SECTION_NUMBER 2
 '@S9S_MB_2U_LIB.S9S_MB_2U(SCH_1):PAGE299_I168@PURE_QUANTA.MOSFET_NCH_DUAL(CHIPS)':
 C_PATH='@s9s_mb_2u_lib.s9s_mb_2u(sch_1):page299_i168@pure_quanta.mosfet_nch_dua~
l(chips)',
 P_PATH='@s9s_mb_2u_lib.s9s_mb_2u(sch_1):page147_i168@pure_quanta.mosfet_nch_dua~
l(chips)',
 PATH='I168',
 DRAWING='@S9S_MB_2U_LIB.S9S_MB_2U(SCH_1):PAGE299',
 PHYS_PAGE='147',
 XY='(3825,1200)',
 ROT='0',
 VER='2',
 LOCATION='Q108',
 CDS_LIB='pure_quanta',
 CDS_PART_NAME='MOSFET_NCH_DUAL-PJT138K,SMLF,IA',
 PART_TYPE='SMLF',
 MATERIAL='IC',
 VALUE='PJT138K',
 PRIM_FILE='./archive_libs/logical/mosfet_nch_dual/chips/chips.prt';

PART_NAME
 Q118 'MOSFET_NCH_DUAL-PJT138K,SMLF,EA':
 ROOM='NIC1_P12V_MAM_MAM_BOM1';

SECTION_NUMBER 1
 '@S9S_MB_2U_LIB.S9S_MB_2U(SCH_1):PAGE131_I7@PURE_QUANTA.MOSFET_NCH_DUAL(CHIPS)':
 C_PATH='@s9s_mb_2u_lib.s9s_mb_2u(sch_1):page131_i7@pure_quanta.mosfet_nch_dual(~
chips)',
 P_PATH='@s9s_mb_2u_lib.s9s_mb_2u(sch_1):page162_i7@pure_quanta.mosfet_nch_dual(~
chips)',
 PATH='I7',
 DRAWING='@S9S_MB_2U_LIB.S9S_MB_2U(SCH_1):PAGE131',
 ROOM1='NIC1_P12V_MAM_TIC_BOM2',
 PHYS_PAGE='162',
 XY='(-3025,-950)',
 ROT='0',
 VER='1',
 CDS_LIB='pure_quanta',
 CDS_PART_NAME='MOSFET_NCH_DUAL-PJT138K,SMLF,EA',
 PART_TYPE='SMLF',
 MATERIAL='EMPTY',
 ROOM='NIC1_P12V_MAM_MAM_BOM1',
 VALUE='PJT138K',
 PRIM_FILE='./archive_libs/logical/mosfet_nch_dual/chips/chips.prt';

SECTION_NUMBER 2
 '@S9S_MB_2U_LIB.S9S_MB_2U(SCH_1):PAGE131_I16@PURE_QUANTA.MOSFET_NCH_DUAL(CHIPS)':
 C_PATH='@s9s_mb_2u_lib.s9s_mb_2u(sch_1):page131_i16@pure_quanta.mosfet_nch_dual~
(chips)',
 P_PATH='@s9s_mb_2u_lib.s9s_mb_2u(sch_1):page162_i16@pure_quanta.mosfet_nch_dual~
(chips)',
 PATH='I16',
 DRAWING='@S9S_MB_2U_LIB.S9S_MB_2U(SCH_1):PAGE131',
 ROOM1='NIC1_P12V_MAM_TIC_BOM2',
 PHYS_PAGE='162',
 XY='(-2350,-625)',
 ROT='0',
 VER='2',
 CDS_LIB='pure_quanta',
 CDS_PART_NAME='MOSFET_NCH_DUAL-PJT138K,SMLF,EA',
 PART_TYPE='SMLF',
 MATERIAL='EMPTY',
 ROOM='NIC1_P12V_MAM_MAM_BOM1',
 VALUE='PJT138K',
 PRIM_FILE='./archive_libs/logical/mosfet_nch_dual/chips/chips.prt';

PART_NAME
 Q119 'MOSFET_NCH_DUAL-PJT138K,SMLF,IA':
 ROOM='NIC1_P3V3_BOM1';

SECTION_NUMBER 1
 '@S9S_MB_2U_LIB.S9S_MB_2U(SCH_1):PAGE131_I38@PURE_QUANTA.MOSFET_NCH_DUAL(CHIPS)':
 C_PATH='@s9s_mb_2u_lib.s9s_mb_2u(sch_1):page131_i38@pure_quanta.mosfet_nch_dual~
(chips)',
 P_PATH='@s9s_mb_2u_lib.s9s_mb_2u(sch_1):page162_i38@pure_quanta.mosfet_nch_dual~
(chips)',
 PATH='I38',
 DRAWING='@S9S_MB_2U_LIB.S9S_MB_2U(SCH_1):PAGE131',
 PHYS_PAGE='162',
 XY='(-2375,1350)',
 ROT='0',
 VER='1',
 CDS_LIB='pure_quanta',
 CDS_PART_NAME='MOSFET_NCH_DUAL-PJT138K,SMLF,IA',
 PART_TYPE='SMLF',
 MATERIAL='IC',
 ROOM='NIC1_P3V3_BOM1',
 VALUE='PJT138K',
 PRIM_FILE='./archive_libs/logical/mosfet_nch_dual/chips/chips.prt';

SECTION_NUMBER 2
 '@S9S_MB_2U_LIB.S9S_MB_2U(SCH_1):PAGE131_I42@PURE_QUANTA.MOSFET_NCH_DUAL(CHIPS)':
 C_PATH='@s9s_mb_2u_lib.s9s_mb_2u(sch_1):page131_i42@pure_quanta.mosfet_nch_dual~
(chips)',
 P_PATH='@s9s_mb_2u_lib.s9s_mb_2u(sch_1):page162_i42@pure_quanta.mosfet_nch_dual~
(chips)',
 PATH='I42',
 DRAWING='@S9S_MB_2U_LIB.S9S_MB_2U(SCH_1):PAGE131',
 PHYS_PAGE='162',
 XY='(-1600,1425)',
 ROT='0',
 VER='2',
 CDS_LIB='pure_quanta',
 CDS_PART_NAME='MOSFET_NCH_DUAL-PJT138K,SMLF,IA',
 PART_TYPE='SMLF',
 MATERIAL='IC',
 ROOM='NIC1_P3V3_BOM1',
 VALUE='PJT138K',
 PRIM_FILE='./archive_libs/logical/mosfet_nch_dual/chips/chips.prt';

PART_NAME
 Q123 'MOSFET_NCH_DUAL-PJT138K,SMLF,EA':
 ROOM='NIC1_P12V_MAM_MAM_BOM1';

SECTION_NUMBER 1
 '@S9S_MB_2U_LIB.S9S_MB_2U(SCH_1):PAGE153_I9@PURE_QUANTA.MOSFET_NCH_DUAL(CHIPS)':
 C_PATH='@s9s_mb_2u_lib.s9s_mb_2u(sch_1):page153_i9@pure_quanta.mosfet_nch_dual(~
chips)',
 P_PATH='@s9s_mb_2u_lib.s9s_mb_2u(sch_1):page156_i9@pure_quanta.mosfet_nch_dual(~
chips)',
 PATH='I9',
 DRAWING='@S9S_MB_2U_LIB.S9S_MB_2U(SCH_1):PAGE153',
 ROOM1='NIC1_P12V_MAM_TIC_BOM2',
 PHYS_PAGE='156',
 XY='(3325,10250)',
 ROT='0',
 VER='1',
 CDS_LIB='pure_quanta',
 CDS_PART_NAME='MOSFET_NCH_DUAL-PJT138K,SMLF,EA',
 PART_TYPE='SMLF',
 MATERIAL='EMPTY',
 ROOM='NIC1_P12V_MAM_MAM_BOM1',
 VALUE='PJT138K',
 PRIM_FILE='./archive_libs/logical/mosfet_nch_dual/chips/chips.prt';

SECTION_NUMBER 2
 '@S9S_MB_2U_LIB.S9S_MB_2U(SCH_1):PAGE153_I17@PURE_QUANTA.MOSFET_NCH_DUAL(CHIPS)':
 C_PATH='@s9s_mb_2u_lib.s9s_mb_2u(sch_1):page153_i17@pure_quanta.mosfet_nch_dual~
(chips)',
 P_PATH='@s9s_mb_2u_lib.s9s_mb_2u(sch_1):page156_i17@pure_quanta.mosfet_nch_dual~
(chips)',
 PATH='I17',
 DRAWING='@S9S_MB_2U_LIB.S9S_MB_2U(SCH_1):PAGE153',
 ROOM1='NIC1_P12V_MAM_TIC_BOM2',
 PHYS_PAGE='156',
 XY='(4075,10575)',
 ROT='0',
 VER='2',
 CDS_LIB='pure_quanta',
 CDS_PART_NAME='MOSFET_NCH_DUAL-PJT138K,SMLF,EA',
 PART_TYPE='SMLF',
 MATERIAL='EMPTY',
 ROOM='NIC1_P12V_MAM_MAM_BOM1',
 VALUE='PJT138K',
 PRIM_FILE='./archive_libs/logical/mosfet_nch_dual/chips/chips.prt';

PART_NAME
 Q124 'MOSFET_NCH_DUAL-PJT138K,SMLF,IA':
 ROOM='NIC1_P3V3_BOM1';

SECTION_NUMBER 1
 '@S9S_MB_2U_LIB.S9S_MB_2U(SCH_1):PAGE153_I21@PURE_QUANTA.MOSFET_NCH_DUAL(CHIPS)':
 C_PATH='@s9s_mb_2u_lib.s9s_mb_2u(sch_1):page153_i21@pure_quanta.mosfet_nch_dual~
(chips)',
 P_PATH='@s9s_mb_2u_lib.s9s_mb_2u(sch_1):page156_i21@pure_quanta.mosfet_nch_dual~
(chips)',
 PATH='I21',
 DRAWING='@S9S_MB_2U_LIB.S9S_MB_2U(SCH_1):PAGE153',
 PHYS_PAGE='156',
 XY='(4075,11900)',
 ROT='0',
 VER='1',
 CDS_LIB='pure_quanta',
 CDS_PART_NAME='MOSFET_NCH_DUAL-PJT138K,SMLF,IA',
 PART_TYPE='SMLF',
 MATERIAL='IC',
 ROOM='NIC1_P3V3_BOM1',
 VALUE='PJT138K',
 PRIM_FILE='./archive_libs/logical/mosfet_nch_dual/chips/chips.prt';

SECTION_NUMBER 2
 '@S9S_MB_2U_LIB.S9S_MB_2U(SCH_1):PAGE153_I36@PURE_QUANTA.MOSFET_NCH_DUAL(CHIPS)':
 C_PATH='@s9s_mb_2u_lib.s9s_mb_2u(sch_1):page153_i36@pure_quanta.mosfet_nch_dual~
(chips)',
 P_PATH='@s9s_mb_2u_lib.s9s_mb_2u(sch_1):page156_i36@pure_quanta.mosfet_nch_dual~
(chips)',
 PATH='I36',
 DRAWING='@S9S_MB_2U_LIB.S9S_MB_2U(SCH_1):PAGE153',
 PHYS_PAGE='156',
 XY='(4825,12275)',
 ROT='0',
 VER='2',
 LOCATION='Q124',
 CDS_LIB='pure_quanta',
 CDS_PART_NAME='MOSFET_NCH_DUAL-PJT138K,SMLF,IA',
 PART_TYPE='SMLF',
 MATERIAL='IC',
 ROOM='NIC1_P3V3_BOM1',
 VALUE='PJT138K',
 PRIM_FILE='./archive_libs/logical/mosfet_nch_dual/chips/chips.prt';

PART_NAME
 Q125 'MOSFET_NCH_DUAL-PJT138K,SMLF,EA':
 ROOM='SCM_P12V_BOM1';

SECTION_NUMBER 1
 '@S9S_MB_2U_LIB.S9S_MB_2U(SCH_1):PAGE229_I21@PURE_QUANTA.MOSFET_NCH_DUAL(CHIPS)':
 C_PATH='@s9s_mb_2u_lib.s9s_mb_2u(sch_1):page229_i21@pure_quanta.mosfet_nch_dual~
(chips)',
 P_PATH='@s9s_mb_2u_lib.s9s_mb_2u(sch_1):page242_i21@pure_quanta.mosfet_nch_dual~
(chips)',
 PATH='I21',
 DRAWING='@S9S_MB_2U_LIB.S9S_MB_2U(SCH_1):PAGE229',
 PHYS_PAGE='242',
 XY='(-1775,925)',
 ROT='0',
 VER='1',
 CDS_LIB='pure_quanta',
 CDS_PART_NAME='MOSFET_NCH_DUAL-PJT138K,SMLF,EA',
 PART_TYPE='SMLF',
 MATERIAL='EMPTY',
 ROOM='SCM_P12V_BOM1',
 VALUE='PJT138K',
 PRIM_FILE='./archive_libs/logical/mosfet_nch_dual/chips/chips.prt';

SECTION_NUMBER 2
 '@S9S_MB_2U_LIB.S9S_MB_2U(SCH_1):PAGE229_I26@PURE_QUANTA.MOSFET_NCH_DUAL(CHIPS)':
 C_PATH='@s9s_mb_2u_lib.s9s_mb_2u(sch_1):page229_i26@pure_quanta.mosfet_nch_dual~
(chips)',
 P_PATH='@s9s_mb_2u_lib.s9s_mb_2u(sch_1):page242_i26@pure_quanta.mosfet_nch_dual~
(chips)',
 PATH='I26',
 DRAWING='@S9S_MB_2U_LIB.S9S_MB_2U(SCH_1):PAGE229',
 PHYS_PAGE='242',
 XY='(-1100,1275)',
 ROT='0',
 VER='2',
 CDS_LIB='pure_quanta',
 CDS_PART_NAME='MOSFET_NCH_DUAL-PJT138K,SMLF,EA',
 PART_TYPE='SMLF',
 MATERIAL='EMPTY',
 ROOM='SCM_P12V_BOM1',
 VALUE='PJT138K',
 PRIM_FILE='./archive_libs/logical/mosfet_nch_dual/chips/chips.prt';

PART_NAME
 Q126 'MOSFET_NCH_DUAL-PJT138K,SMLF,IA':
 ROOM='E1S1_P3V3_BOM1';

SECTION_NUMBER 1
 '@S9S_MB_2U_LIB.S9S_MB_2U(SCH_1):PAGE324_I3@PURE_QUANTA.MOSFET_NCH_DUAL(CHIPS)':
 C_PATH='@s9s_mb_2u_lib.s9s_mb_2u(sch_1):page324_i3@pure_quanta.mosfet_nch_dual(~
chips)',
 P_PATH='@s9s_mb_2u_lib.s9s_mb_2u(sch_1):page192_i3@pure_quanta.mosfet_nch_dual(~
chips)',
 PATH='I3',
 DRAWING='@S9S_MB_2U_LIB.S9S_MB_2U(SCH_1):PAGE324',
 PHYS_PAGE='192',
 XY='(-3200,-2375)',
 ROT='0',
 VER='1',
 CDS_LIB='pure_quanta',
 CDS_PART_NAME='MOSFET_NCH_DUAL-PJT138K,SMLF,IA',
 PART_TYPE='SMLF',
 MATERIAL='IC',
 ROOM='E1S1_P3V3_BOM1',
 VALUE='PJT138K',
 PRIM_FILE='./archive_libs/logical/mosfet_nch_dual/chips/chips.prt';

SECTION_NUMBER 2
 '@S9S_MB_2U_LIB.S9S_MB_2U(SCH_1):PAGE324_I4@PURE_QUANTA.MOSFET_NCH_DUAL(CHIPS)':
 C_PATH='@s9s_mb_2u_lib.s9s_mb_2u(sch_1):page324_i4@pure_quanta.mosfet_nch_dual(~
chips)',
 P_PATH='@s9s_mb_2u_lib.s9s_mb_2u(sch_1):page192_i4@pure_quanta.mosfet_nch_dual(~
chips)',
 PATH='I4',
 DRAWING='@S9S_MB_2U_LIB.S9S_MB_2U(SCH_1):PAGE324',
 PHYS_PAGE='192',
 XY='(-2525,-2050)',
 ROT='0',
 VER='2',
 CDS_LIB='pure_quanta',
 CDS_PART_NAME='MOSFET_NCH_DUAL-PJT138K,SMLF,IA',
 PART_TYPE='SMLF',
 MATERIAL='IC',
 ROOM='E1S1_P3V3_BOM1',
 VALUE='PJT138K',
 PRIM_FILE='./archive_libs/logical/mosfet_nch_dual/chips/chips.prt';

PART_NAME
 Q127 'MOSFET_NCH_DUAL-PJT138K,SMLF,EA':
 ROOM='E1S1_P12V_MAM_MAM_BOM1';

SECTION_NUMBER 1
 '@S9S_MB_2U_LIB.S9S_MB_2U(SCH_1):PAGE324_I10@PURE_QUANTA.MOSFET_NCH_DUAL(CHIPS)':
 C_PATH='@s9s_mb_2u_lib.s9s_mb_2u(sch_1):page324_i10@pure_quanta.mosfet_nch_dual~
(chips)',
 P_PATH='@s9s_mb_2u_lib.s9s_mb_2u(sch_1):page192_i10@pure_quanta.mosfet_nch_dual~
(chips)',
 PATH='I10',
 DRAWING='@S9S_MB_2U_LIB.S9S_MB_2U(SCH_1):PAGE324',
 ROOM1='E1S1_P12V_MAM_TIC_BOM2',
 PHYS_PAGE='192',
 XY='(-2575,150)',
 ROT='0',
 VER='1',
 CDS_LIB='pure_quanta',
 CDS_PART_NAME='MOSFET_NCH_DUAL-PJT138K,SMLF,EA',
 PART_TYPE='SMLF',
 MATERIAL='EMPTY',
 ROOM='E1S1_P12V_MAM_MAM_BOM1',
 VALUE='PJT138K',
 PRIM_FILE='./archive_libs/logical/mosfet_nch_dual/chips/chips.prt';

SECTION_NUMBER 2
 '@S9S_MB_2U_LIB.S9S_MB_2U(SCH_1):PAGE324_I24@PURE_QUANTA.MOSFET_NCH_DUAL(CHIPS)':
 C_PATH='@s9s_mb_2u_lib.s9s_mb_2u(sch_1):page324_i24@pure_quanta.mosfet_nch_dual~
(chips)',
 P_PATH='@s9s_mb_2u_lib.s9s_mb_2u(sch_1):page192_i24@pure_quanta.mosfet_nch_dual~
(chips)',
 PATH='I24',
 DRAWING='@S9S_MB_2U_LIB.S9S_MB_2U(SCH_1):PAGE324',
 ROOM1='E1S1_P12V_MAM_TIC_BOM2',
 PHYS_PAGE='192',
 XY='(-1875,525)',
 ROT='0',
 VER='2',
 CDS_LIB='pure_quanta',
 CDS_PART_NAME='MOSFET_NCH_DUAL-PJT138K,SMLF,EA',
 PART_TYPE='SMLF',
 MATERIAL='EMPTY',
 ROOM='E1S1_P12V_MAM_MAM_BOM1',
 VALUE='PJT138K',
 PRIM_FILE='./archive_libs/logical/mosfet_nch_dual/chips/chips.prt';

PART_NAME
 Q128 'MOSFET_NCH_DUAL-PJT138K,SMLF,IA':;

SECTION_NUMBER 1
 '@S9S_MB_2U_LIB.S9S_MB_2U(SCH_1):PAGE143_I11@PURE_QUANTA.MOSFET_NCH_DUAL(CHIPS)':
 C_PATH='@s9s_mb_2u_lib.s9s_mb_2u(sch_1):page143_i11@pure_quanta.mosfet_nch_dual~
(chips)',
 P_PATH='@s9s_mb_2u_lib.s9s_mb_2u(sch_1):page146_i11@pure_quanta.mosfet_nch_dual~
(chips)',
 PATH='I11',
 DRAWING='@S9S_MB_2U_LIB.S9S_MB_2U(SCH_1):PAGE143',
 PHYS_PAGE='146',
 XY='(-1175,3500)',
 ROT='0',
 VER='1',
 CDS_LIB='pure_quanta',
 CDS_PART_NAME='MOSFET_NCH_DUAL-PJT138K,SMLF,IA',
 PART_TYPE='SMLF',
 MATERIAL='IC',
 VALUE='PJT138K',
 PRIM_FILE='./archive_libs/logical/mosfet_nch_dual/chips/chips.prt';

SECTION_NUMBER 2
 '@S9S_MB_2U_LIB.S9S_MB_2U(SCH_1):PAGE143_I6@PURE_QUANTA.MOSFET_NCH_DUAL(CHIPS)':
 C_PATH='@s9s_mb_2u_lib.s9s_mb_2u(sch_1):page143_i6@pure_quanta.mosfet_nch_dual(~
chips)',
 P_PATH='@s9s_mb_2u_lib.s9s_mb_2u(sch_1):page146_i6@pure_quanta.mosfet_nch_dual(~
chips)',
 PATH='I6',
 DRAWING='@S9S_MB_2U_LIB.S9S_MB_2U(SCH_1):PAGE143',
 PHYS_PAGE='146',
 XY='(-25,3800)',
 ROT='0',
 VER='2',
 LOCATION='Q128',
 CDS_LIB='pure_quanta',
 CDS_PART_NAME='MOSFET_NCH_DUAL-PJT138K,SMLF,IA',
 PART_TYPE='SMLF',
 MATERIAL='IC',
 VALUE='PJT138K',
 PRIM_FILE='./archive_libs/logical/mosfet_nch_dual/chips/chips.prt';

PART_NAME
 Q129 'MOSFET_NCH_DUAL-PJT138K,SMLF,IA':;

SECTION_NUMBER 1
 '@S9S_MB_2U_LIB.S9S_MB_2U(SCH_1):PAGE143_I83@PURE_QUANTA.MOSFET_NCH_DUAL(CHIPS)':
 C_PATH='@s9s_mb_2u_lib.s9s_mb_2u(sch_1):page143_i83@pure_quanta.mosfet_nch_dual~
(chips)',
 P_PATH='@s9s_mb_2u_lib.s9s_mb_2u(sch_1):page146_i83@pure_quanta.mosfet_nch_dual~
(chips)',
 PATH='I83',
 DRAWING='@S9S_MB_2U_LIB.S9S_MB_2U(SCH_1):PAGE143',
 PHYS_PAGE='146',
 XY='(3450,975)',
 ROT='0',
 VER='1',
 LOCATION='Q129',
 CDS_LIB='pure_quanta',
 CDS_PART_NAME='MOSFET_NCH_DUAL-PJT138K,SMLF,IA',
 PART_TYPE='SMLF',
 MATERIAL='IC',
 VALUE='PJT138K',
 PRIM_FILE='./archive_libs/logical/mosfet_nch_dual/chips/chips.prt';

SECTION_NUMBER 2
 '@S9S_MB_2U_LIB.S9S_MB_2U(SCH_1):PAGE143_I77@PURE_QUANTA.MOSFET_NCH_DUAL(CHIPS)':
 C_PATH='@s9s_mb_2u_lib.s9s_mb_2u(sch_1):page143_i77@pure_quanta.mosfet_nch_dual~
(chips)',
 P_PATH='@s9s_mb_2u_lib.s9s_mb_2u(sch_1):page146_i77@pure_quanta.mosfet_nch_dual~
(chips)',
 PATH='I77',
 DRAWING='@S9S_MB_2U_LIB.S9S_MB_2U(SCH_1):PAGE143',
 PHYS_PAGE='146',
 XY='(4600,1275)',
 ROT='0',
 VER='2',
 CDS_LIB='pure_quanta',
 CDS_PART_NAME='MOSFET_NCH_DUAL-PJT138K,SMLF,IA',
 PART_TYPE='SMLF',
 MATERIAL='IC',
 VALUE='PJT138K',
 PRIM_FILE='./archive_libs/logical/mosfet_nch_dual/chips/chips.prt';

PART_NAME
 Q130 'MOSFET_NCH_DUAL-PJT138K,SMLF,IA':;

SECTION_NUMBER 1
 '@S9S_MB_2U_LIB.S9S_MB_2U(SCH_1):PAGE143_I74@PURE_QUANTA.MOSFET_NCH_DUAL(CHIPS)':
 C_PATH='@s9s_mb_2u_lib.s9s_mb_2u(sch_1):page143_i74@pure_quanta.mosfet_nch_dual~
(chips)',
 P_PATH='@s9s_mb_2u_lib.s9s_mb_2u(sch_1):page146_i74@pure_quanta.mosfet_nch_dual~
(chips)',
 PATH='I74',
 DRAWING='@S9S_MB_2U_LIB.S9S_MB_2U(SCH_1):PAGE143',
 PHYS_PAGE='146',
 XY='(3450,3800)',
 ROT='0',
 VER='1',
 LOCATION='Q130',
 CDS_LIB='pure_quanta',
 CDS_PART_NAME='MOSFET_NCH_DUAL-PJT138K,SMLF,IA',
 PART_TYPE='SMLF',
 MATERIAL='IC',
 VALUE='PJT138K',
 PRIM_FILE='./archive_libs/logical/mosfet_nch_dual/chips/chips.prt';

SECTION_NUMBER 2
 '@S9S_MB_2U_LIB.S9S_MB_2U(SCH_1):PAGE143_I70@PURE_QUANTA.MOSFET_NCH_DUAL(CHIPS)':
 C_PATH='@s9s_mb_2u_lib.s9s_mb_2u(sch_1):page143_i70@pure_quanta.mosfet_nch_dual~
(chips)',
 P_PATH='@s9s_mb_2u_lib.s9s_mb_2u(sch_1):page146_i70@pure_quanta.mosfet_nch_dual~
(chips)',
 PATH='I70',
 DRAWING='@S9S_MB_2U_LIB.S9S_MB_2U(SCH_1):PAGE143',
 PHYS_PAGE='146',
 XY='(4600,4100)',
 ROT='0',
 VER='2',
 CDS_LIB='pure_quanta',
 CDS_PART_NAME='MOSFET_NCH_DUAL-PJT138K,SMLF,IA',
 PART_TYPE='SMLF',
 MATERIAL='IC',
 VALUE='PJT138K',
 PRIM_FILE='./archive_libs/logical/mosfet_nch_dual/chips/chips.prt';

PART_NAME
 Q131 'MOSFET_NCH_DUAL-PJT138K,SMLF,IA':;

SECTION_NUMBER 1
 '@S9S_MB_2U_LIB.S9S_MB_2U(SCH_1):PAGE143_I29@PURE_QUANTA.MOSFET_NCH_DUAL(CHIPS)':
 C_PATH='@s9s_mb_2u_lib.s9s_mb_2u(sch_1):page143_i29@pure_quanta.mosfet_nch_dual~
(chips)',
 P_PATH='@s9s_mb_2u_lib.s9s_mb_2u(sch_1):page146_i29@pure_quanta.mosfet_nch_dual~
(chips)',
 PATH='I29',
 DRAWING='@S9S_MB_2U_LIB.S9S_MB_2U(SCH_1):PAGE143',
 PHYS_PAGE='146',
 XY='(-1150,2125)',
 ROT='0',
 VER='1',
 LOCATION='Q131',
 CDS_LIB='pure_quanta',
 CDS_PART_NAME='MOSFET_NCH_DUAL-PJT138K,SMLF,IA',
 PART_TYPE='SMLF',
 MATERIAL='IC',
 VALUE='PJT138K',
 PRIM_FILE='./archive_libs/logical/mosfet_nch_dual/chips/chips.prt';

SECTION_NUMBER 2
 '@S9S_MB_2U_LIB.S9S_MB_2U(SCH_1):PAGE143_I19@PURE_QUANTA.MOSFET_NCH_DUAL(CHIPS)':
 C_PATH='@s9s_mb_2u_lib.s9s_mb_2u(sch_1):page143_i19@pure_quanta.mosfet_nch_dual~
(chips)',
 P_PATH='@s9s_mb_2u_lib.s9s_mb_2u(sch_1):page146_i19@pure_quanta.mosfet_nch_dual~
(chips)',
 PATH='I19',
 DRAWING='@S9S_MB_2U_LIB.S9S_MB_2U(SCH_1):PAGE143',
 PHYS_PAGE='146',
 XY='(0,2425)',
 ROT='0',
 VER='2',
 CDS_LIB='pure_quanta',
 CDS_PART_NAME='MOSFET_NCH_DUAL-PJT138K,SMLF,IA',
 PART_TYPE='SMLF',
 MATERIAL='IC',
 VALUE='PJT138K',
 PRIM_FILE='./archive_libs/logical/mosfet_nch_dual/chips/chips.prt';

PART_NAME
 Q132 'MOSFET_NCH_DUAL-PJT138K,SMLF,IA':;

SECTION_NUMBER 1
 '@S9S_MB_2U_LIB.S9S_MB_2U(SCH_1):PAGE143_I44@PURE_QUANTA.MOSFET_NCH_DUAL(CHIPS)':
 C_PATH='@s9s_mb_2u_lib.s9s_mb_2u(sch_1):page143_i44@pure_quanta.mosfet_nch_dual~
(chips)',
 P_PATH='@s9s_mb_2u_lib.s9s_mb_2u(sch_1):page146_i44@pure_quanta.mosfet_nch_dual~
(chips)',
 PATH='I44',
 DRAWING='@S9S_MB_2U_LIB.S9S_MB_2U(SCH_1):PAGE143',
 PHYS_PAGE='146',
 XY='(-1175,675)',
 ROT='0',
 VER='1',
 LOCATION='Q132',
 CDS_LIB='pure_quanta',
 CDS_PART_NAME='MOSFET_NCH_DUAL-PJT138K,SMLF,IA',
 PART_TYPE='SMLF',
 MATERIAL='IC',
 VALUE='PJT138K',
 PRIM_FILE='./archive_libs/logical/mosfet_nch_dual/chips/chips.prt';

SECTION_NUMBER 2
 '@S9S_MB_2U_LIB.S9S_MB_2U(SCH_1):PAGE143_I35@PURE_QUANTA.MOSFET_NCH_DUAL(CHIPS)':
 C_PATH='@s9s_mb_2u_lib.s9s_mb_2u(sch_1):page143_i35@pure_quanta.mosfet_nch_dual~
(chips)',
 P_PATH='@s9s_mb_2u_lib.s9s_mb_2u(sch_1):page146_i35@pure_quanta.mosfet_nch_dual~
(chips)',
 PATH='I35',
 DRAWING='@S9S_MB_2U_LIB.S9S_MB_2U(SCH_1):PAGE143',
 PHYS_PAGE='146',
 XY='(-25,975)',
 ROT='0',
 VER='2',
 CDS_LIB='pure_quanta',
 CDS_PART_NAME='MOSFET_NCH_DUAL-PJT138K,SMLF,IA',
 PART_TYPE='SMLF',
 MATERIAL='IC',
 VALUE='PJT138K',
 PRIM_FILE='./archive_libs/logical/mosfet_nch_dual/chips/chips.prt';

PART_NAME
 Q133 'MOSFET_NCH_DUAL-PJT138K,SMLF,IA':;

SECTION_NUMBER 1
 '@S9S_MB_2U_LIB.S9S_MB_2U(SCH_1):PAGE143_I78@PURE_QUANTA.MOSFET_NCH_DUAL(CHIPS)':
 C_PATH='@s9s_mb_2u_lib.s9s_mb_2u(sch_1):page143_i78@pure_quanta.mosfet_nch_dual~
(chips)',
 P_PATH='@s9s_mb_2u_lib.s9s_mb_2u(sch_1):page146_i78@pure_quanta.mosfet_nch_dual~
(chips)',
 PATH='I78',
 DRAWING='@S9S_MB_2U_LIB.S9S_MB_2U(SCH_1):PAGE143',
 PHYS_PAGE='146',
 XY='(3475,2425)',
 ROT='0',
 VER='1',
 CDS_LIB='pure_quanta',
 CDS_PART_NAME='MOSFET_NCH_DUAL-PJT138K,SMLF,IA',
 PART_TYPE='SMLF',
 MATERIAL='IC',
 VALUE='PJT138K',
 PRIM_FILE='./archive_libs/logical/mosfet_nch_dual/chips/chips.prt';

SECTION_NUMBER 2
 '@S9S_MB_2U_LIB.S9S_MB_2U(SCH_1):PAGE143_I71@PURE_QUANTA.MOSFET_NCH_DUAL(CHIPS)':
 C_PATH='@s9s_mb_2u_lib.s9s_mb_2u(sch_1):page143_i71@pure_quanta.mosfet_nch_dual~
(chips)',
 P_PATH='@s9s_mb_2u_lib.s9s_mb_2u(sch_1):page146_i71@pure_quanta.mosfet_nch_dual~
(chips)',
 PATH='I71',
 DRAWING='@S9S_MB_2U_LIB.S9S_MB_2U(SCH_1):PAGE143',
 PHYS_PAGE='146',
 XY='(4625,2725)',
 ROT='0',
 VER='2',
 LOCATION='Q133',
 CDS_LIB='pure_quanta',
 CDS_PART_NAME='MOSFET_NCH_DUAL-PJT138K,SMLF,IA',
 PART_TYPE='SMLF',
 MATERIAL='IC',
 VALUE='PJT138K',
 PRIM_FILE='./archive_libs/logical/mosfet_nch_dual/chips/chips.prt';

PART_NAME
 Q134 'MOSFET_NCH_DUAL-PJT138K,SMLF,IA':;

SECTION_NUMBER 1
 '@S9S_MB_2U_LIB.S9S_MB_2U(SCH_1):PAGE143_I99@PURE_QUANTA.MOSFET_NCH_DUAL(CHIPS)':
 C_PATH='@s9s_mb_2u_lib.s9s_mb_2u(sch_1):page143_i99@pure_quanta.mosfet_nch_dual~
(chips)',
 P_PATH='@s9s_mb_2u_lib.s9s_mb_2u(sch_1):page146_i99@pure_quanta.mosfet_nch_dual~
(chips)',
 PATH='I99',
 DRAWING='@S9S_MB_2U_LIB.S9S_MB_2U(SCH_1):PAGE143',
 PHYS_PAGE='146',
 XY='(-1100,-875)',
 ROT='0',
 VER='1',
 CDS_LIB='pure_quanta',
 CDS_PART_NAME='MOSFET_NCH_DUAL-PJT138K,SMLF,IA',
 PART_TYPE='SMLF',
 MATERIAL='IC',
 VALUE='PJT138K',
 PRIM_FILE='./archive_libs/logical/mosfet_nch_dual/chips/chips.prt';

SECTION_NUMBER 2
 '@S9S_MB_2U_LIB.S9S_MB_2U(SCH_1):PAGE143_I107@PURE_QUANTA.MOSFET_NCH_DUAL(CHIPS)':
 C_PATH='@s9s_mb_2u_lib.s9s_mb_2u(sch_1):page143_i107@pure_quanta.mosfet_nch_dua~
l(chips)',
 P_PATH='@s9s_mb_2u_lib.s9s_mb_2u(sch_1):page146_i107@pure_quanta.mosfet_nch_dua~
l(chips)',
 PATH='I107',
 DRAWING='@S9S_MB_2U_LIB.S9S_MB_2U(SCH_1):PAGE143',
 PHYS_PAGE='146',
 XY='(50,-575)',
 ROT='0',
 VER='2',
 CDS_LIB='pure_quanta',
 CDS_PART_NAME='MOSFET_NCH_DUAL-PJT138K,SMLF,IA',
 PART_TYPE='SMLF',
 MATERIAL='IC',
 VALUE='PJT138K',
 PRIM_FILE='./archive_libs/logical/mosfet_nch_dual/chips/chips.prt';

PART_NAME
 Q135 'MOSFET_NCH_DUAL-PJT138K,SMLF,IA':;

SECTION_NUMBER 1
 '@S9S_MB_2U_LIB.S9S_MB_2U(SCH_1):PAGE139_I25@PURE_QUANTA.MOSFET_NCH_DUAL(CHIPS)':
 C_PATH='@s9s_mb_2u_lib.s9s_mb_2u(sch_1):page139_i25@pure_quanta.mosfet_nch_dual~
(chips)',
 P_PATH='@s9s_mb_2u_lib.s9s_mb_2u(sch_1):page145_i25@pure_quanta.mosfet_nch_dual~
(chips)',
 PATH='I25',
 DRAWING='@S9S_MB_2U_LIB.S9S_MB_2U(SCH_1):PAGE139',
 PHYS_PAGE='145',
 XY='(-875,4975)',
 ROT='0',
 VER='1',
 CDS_LIB='pure_quanta',
 CDS_PART_NAME='MOSFET_NCH_DUAL-PJT138K,SMLF,IA',
 PART_TYPE='SMLF',
 MATERIAL='IC',
 VALUE='PJT138K',
 PRIM_FILE='./archive_libs/logical/mosfet_nch_dual/chips/chips.prt';

SECTION_NUMBER 2
 '@S9S_MB_2U_LIB.S9S_MB_2U(SCH_1):PAGE139_I29@PURE_QUANTA.MOSFET_NCH_DUAL(CHIPS)':
 C_PATH='@s9s_mb_2u_lib.s9s_mb_2u(sch_1):page139_i29@pure_quanta.mosfet_nch_dual~
(chips)',
 P_PATH='@s9s_mb_2u_lib.s9s_mb_2u(sch_1):page145_i29@pure_quanta.mosfet_nch_dual~
(chips)',
 PATH='I29',
 DRAWING='@S9S_MB_2U_LIB.S9S_MB_2U(SCH_1):PAGE139',
 PHYS_PAGE='145',
 XY='(275,5275)',
 ROT='0',
 VER='2',
 LOCATION='Q135',
 CDS_LIB='pure_quanta',
 CDS_PART_NAME='MOSFET_NCH_DUAL-PJT138K,SMLF,IA',
 PART_TYPE='SMLF',
 MATERIAL='IC',
 VALUE='PJT138K',
 PRIM_FILE='./archive_libs/logical/mosfet_nch_dual/chips/chips.prt';

PART_NAME
 Q136 'MOSFET_NCH_DUAL-PJT138K,SMLF,IA':;

SECTION_NUMBER 1
 '@S9S_MB_2U_LIB.S9S_MB_2U(SCH_1):PAGE139_I17@PURE_QUANTA.MOSFET_NCH_DUAL(CHIPS)':
 C_PATH='@s9s_mb_2u_lib.s9s_mb_2u(sch_1):page139_i17@pure_quanta.mosfet_nch_dual~
(chips)',
 P_PATH='@s9s_mb_2u_lib.s9s_mb_2u(sch_1):page145_i17@pure_quanta.mosfet_nch_dual~
(chips)',
 PATH='I17',
 DRAWING='@S9S_MB_2U_LIB.S9S_MB_2U(SCH_1):PAGE139',
 PHYS_PAGE='145',
 XY='(-875,2150)',
 ROT='0',
 VER='1',
 CDS_LIB='pure_quanta',
 CDS_PART_NAME='MOSFET_NCH_DUAL-PJT138K,SMLF,IA',
 PART_TYPE='SMLF',
 MATERIAL='IC',
 VALUE='PJT138K',
 PRIM_FILE='./archive_libs/logical/mosfet_nch_dual/chips/chips.prt';

SECTION_NUMBER 2
 '@S9S_MB_2U_LIB.S9S_MB_2U(SCH_1):PAGE139_I22@PURE_QUANTA.MOSFET_NCH_DUAL(CHIPS)':
 C_PATH='@s9s_mb_2u_lib.s9s_mb_2u(sch_1):page139_i22@pure_quanta.mosfet_nch_dual~
(chips)',
 P_PATH='@s9s_mb_2u_lib.s9s_mb_2u(sch_1):page145_i22@pure_quanta.mosfet_nch_dual~
(chips)',
 PATH='I22',
 DRAWING='@S9S_MB_2U_LIB.S9S_MB_2U(SCH_1):PAGE139',
 PHYS_PAGE='145',
 XY='(275,2450)',
 ROT='0',
 VER='2',
 CDS_LIB='pure_quanta',
 CDS_PART_NAME='MOSFET_NCH_DUAL-PJT138K,SMLF,IA',
 PART_TYPE='SMLF',
 MATERIAL='IC',
 VALUE='PJT138K',
 PRIM_FILE='./archive_libs/logical/mosfet_nch_dual/chips/chips.prt';

PART_NAME
 Q137 'MOSFET_NCH_DUAL-PJT138K,SMLF,IA':;

SECTION_NUMBER 1
 '@S9S_MB_2U_LIB.S9S_MB_2U(SCH_1):PAGE139_I21@PURE_QUANTA.MOSFET_NCH_DUAL(CHIPS)':
 C_PATH='@s9s_mb_2u_lib.s9s_mb_2u(sch_1):page139_i21@pure_quanta.mosfet_nch_dual~
(chips)',
 P_PATH='@s9s_mb_2u_lib.s9s_mb_2u(sch_1):page145_i21@pure_quanta.mosfet_nch_dual~
(chips)',
 PATH='I21',
 DRAWING='@S9S_MB_2U_LIB.S9S_MB_2U(SCH_1):PAGE139',
 PHYS_PAGE='145',
 XY='(-850,3600)',
 ROT='0',
 VER='1',
 CDS_LIB='pure_quanta',
 CDS_PART_NAME='MOSFET_NCH_DUAL-PJT138K,SMLF,IA',
 PART_TYPE='SMLF',
 MATERIAL='IC',
 VALUE='PJT138K',
 PRIM_FILE='./archive_libs/logical/mosfet_nch_dual/chips/chips.prt';

SECTION_NUMBER 2
 '@S9S_MB_2U_LIB.S9S_MB_2U(SCH_1):PAGE139_I28@PURE_QUANTA.MOSFET_NCH_DUAL(CHIPS)':
 C_PATH='@s9s_mb_2u_lib.s9s_mb_2u(sch_1):page139_i28@pure_quanta.mosfet_nch_dual~
(chips)',
 P_PATH='@s9s_mb_2u_lib.s9s_mb_2u(sch_1):page145_i28@pure_quanta.mosfet_nch_dual~
(chips)',
 PATH='I28',
 DRAWING='@S9S_MB_2U_LIB.S9S_MB_2U(SCH_1):PAGE139',
 PHYS_PAGE='145',
 XY='(300,3900)',
 ROT='0',
 VER='2',
 LOCATION='Q137',
 CDS_LIB='pure_quanta',
 CDS_PART_NAME='MOSFET_NCH_DUAL-PJT138K,SMLF,IA',
 PART_TYPE='SMLF',
 MATERIAL='IC',
 VALUE='PJT138K',
 PRIM_FILE='./archive_libs/logical/mosfet_nch_dual/chips/chips.prt';

PART_NAME
 Q138 'BC847BPN-BC847BPN,SMLF,IC,BA00A':;

SECTION_NUMBER 1
 '@S9S_MB_2U_LIB.S9S_MB_2U(SCH_1):PAGE121_I31@PURE_QUANTA.BC847BPN(CHIPS)':
 C_PATH='@s9s_mb_2u_lib.s9s_mb_2u(sch_1):page121_i31@pure_quanta.bc847bpn(chips)~
',
 P_PATH='@s9s_mb_2u_lib.s9s_mb_2u(sch_1):page121_i31@pure_quanta.bc847bpn(chips)~
',
 PATH='I31',
 DRAWING='@S9S_MB_2U_LIB.S9S_MB_2U(SCH_1):PAGE121',
 PHYS_PAGE='121',
 XY='(875,1950)',
 ROT='0',
 VER='1',
 LOCATION='Q138',
 CDS_LIB='pure_quanta',
 CDS_PART_NAME='BC847BPN-BC847BPN,SMLF,IC,BA00A',
 PART_TYPE='SMLF',
 MATERIAL='IC',
 VALUE='BC847BPN',
 PRIM_FILE='./archive_libs/logical/bc847bpn/chips/chips.prt';

SECTION_NUMBER 2
 '@S9S_MB_2U_LIB.S9S_MB_2U(SCH_1):PAGE121_I17@PURE_QUANTA.BC847BPN(CHIPS)':
 C_PATH='@s9s_mb_2u_lib.s9s_mb_2u(sch_1):page121_i17@pure_quanta.bc847bpn(chips)~
',
 P_PATH='@s9s_mb_2u_lib.s9s_mb_2u(sch_1):page121_i17@pure_quanta.bc847bpn(chips)~
',
 PATH='I17',
 DRAWING='@S9S_MB_2U_LIB.S9S_MB_2U(SCH_1):PAGE121',
 PHYS_PAGE='121',
 XY='(-675,2200)',
 ROT='0',
 VER='2',
 LOCATION='Q138',
 CDS_LIB='pure_quanta',
 CDS_PART_NAME='BC847BPN-BC847BPN,SMLF,IC,BA00A',
 PART_TYPE='SMLF',
 MATERIAL='IC',
 VALUE='BC847BPN',
 PRIM_FILE='./archive_libs/logical/bc847bpn/chips/chips.prt';

PART_NAME
 Q139 'BC847BPN-BC847BPN,SMLF,IC,BA00A':;

SECTION_NUMBER 1
 '@S9S_MB_2U_LIB.S9S_MB_2U(SCH_1):PAGE121_I21@PURE_QUANTA.BC847BPN(CHIPS)':
 C_PATH='@s9s_mb_2u_lib.s9s_mb_2u(sch_1):page121_i21@pure_quanta.bc847bpn(chips)~
',
 P_PATH='@s9s_mb_2u_lib.s9s_mb_2u(sch_1):page121_i21@pure_quanta.bc847bpn(chips)~
',
 PATH='I21',
 DRAWING='@S9S_MB_2U_LIB.S9S_MB_2U(SCH_1):PAGE121',
 PHYS_PAGE='121',
 XY='(875,600)',
 ROT='0',
 VER='1',
 LOCATION='Q139',
 CDS_LIB='pure_quanta',
 CDS_PART_NAME='BC847BPN-BC847BPN,SMLF,IC,BA00A',
 PART_TYPE='SMLF',
 MATERIAL='IC',
 VALUE='BC847BPN',
 PRIM_FILE='./archive_libs/logical/bc847bpn/chips/chips.prt';

SECTION_NUMBER 2
 '@S9S_MB_2U_LIB.S9S_MB_2U(SCH_1):PAGE121_I8@PURE_QUANTA.BC847BPN(CHIPS)':
 C_PATH='@s9s_mb_2u_lib.s9s_mb_2u(sch_1):page121_i8@pure_quanta.bc847bpn(chips)',
 P_PATH='@s9s_mb_2u_lib.s9s_mb_2u(sch_1):page121_i8@pure_quanta.bc847bpn(chips)',
 PATH='I8',
 DRAWING='@S9S_MB_2U_LIB.S9S_MB_2U(SCH_1):PAGE121',
 PHYS_PAGE='121',
 XY='(-675,850)',
 ROT='0',
 VER='2',
 LOCATION='Q139',
 CDS_LIB='pure_quanta',
 CDS_PART_NAME='BC847BPN-BC847BPN,SMLF,IC,BA00A',
 PART_TYPE='SMLF',
 MATERIAL='IC',
 VALUE='BC847BPN',
 PRIM_FILE='./archive_libs/logical/bc847bpn/chips/chips.prt';

PART_NAME
 Q140 'BC847BPN-BC847BPN,SMLF,IC,BA00A':;

SECTION_NUMBER 1
 '@S9S_MB_2U_LIB.S9S_MB_2U(SCH_1):PAGE123_I16@PURE_QUANTA.BC847BPN(CHIPS)':
 C_PATH='@s9s_mb_2u_lib.s9s_mb_2u(sch_1):page123_i16@pure_quanta.bc847bpn(chips)~
',
 P_PATH='@s9s_mb_2u_lib.s9s_mb_2u(sch_1):page123_i16@pure_quanta.bc847bpn(chips)~
',
 PATH='I16',
 DRAWING='@S9S_MB_2U_LIB.S9S_MB_2U(SCH_1):PAGE123',
 PHYS_PAGE='123',
 XY='(-475,-2375)',
 ROT='0',
 VER='1',
 LOCATION='Q140',
 CDS_LIB='pure_quanta',
 CDS_PART_NAME='BC847BPN-BC847BPN,SMLF,IC,BA00A',
 PART_TYPE='SMLF',
 MATERIAL='IC',
 VALUE='BC847BPN',
 PRIM_FILE='./archive_libs/logical/bc847bpn/chips/chips.prt';

SECTION_NUMBER 2
 '@S9S_MB_2U_LIB.S9S_MB_2U(SCH_1):PAGE123_I11@PURE_QUANTA.BC847BPN(CHIPS)':
 C_PATH='@s9s_mb_2u_lib.s9s_mb_2u(sch_1):page123_i11@pure_quanta.bc847bpn(chips)~
',
 P_PATH='@s9s_mb_2u_lib.s9s_mb_2u(sch_1):page123_i11@pure_quanta.bc847bpn(chips)~
',
 PATH='I11',
 DRAWING='@S9S_MB_2U_LIB.S9S_MB_2U(SCH_1):PAGE123',
 PHYS_PAGE='123',
 XY='(-2025,-2125)',
 ROT='0',
 VER='2',
 LOCATION='Q140',
 CDS_LIB='pure_quanta',
 CDS_PART_NAME='BC847BPN-BC847BPN,SMLF,IC,BA00A',
 PART_TYPE='SMLF',
 MATERIAL='IC',
 VALUE='BC847BPN',
 PRIM_FILE='./archive_libs/logical/bc847bpn/chips/chips.prt';

PART_NAME
 Q141 'BC847BPN-BC847BPN,SMLF,IC,BA00A':;

SECTION_NUMBER 1
 '@S9S_MB_2U_LIB.S9S_MB_2U(SCH_1):PAGE123_I18@PURE_QUANTA.BC847BPN(CHIPS)':
 C_PATH='@s9s_mb_2u_lib.s9s_mb_2u(sch_1):page123_i18@pure_quanta.bc847bpn(chips)~
',
 P_PATH='@s9s_mb_2u_lib.s9s_mb_2u(sch_1):page123_i18@pure_quanta.bc847bpn(chips)~
',
 PATH='I18',
 DRAWING='@S9S_MB_2U_LIB.S9S_MB_2U(SCH_1):PAGE123',
 PHYS_PAGE='123',
 XY='(-475,-1025)',
 ROT='0',
 VER='1',
 LOCATION='Q141',
 CDS_LIB='pure_quanta',
 CDS_PART_NAME='BC847BPN-BC847BPN,SMLF,IC,BA00A',
 PART_TYPE='SMLF',
 MATERIAL='IC',
 VALUE='BC847BPN',
 PRIM_FILE='./archive_libs/logical/bc847bpn/chips/chips.prt';

SECTION_NUMBER 2
 '@S9S_MB_2U_LIB.S9S_MB_2U(SCH_1):PAGE123_I12@PURE_QUANTA.BC847BPN(CHIPS)':
 C_PATH='@s9s_mb_2u_lib.s9s_mb_2u(sch_1):page123_i12@pure_quanta.bc847bpn(chips)~
',
 P_PATH='@s9s_mb_2u_lib.s9s_mb_2u(sch_1):page123_i12@pure_quanta.bc847bpn(chips)~
',
 PATH='I12',
 DRAWING='@S9S_MB_2U_LIB.S9S_MB_2U(SCH_1):PAGE123',
 PHYS_PAGE='123',
 XY='(-2025,-775)',
 ROT='0',
 VER='2',
 LOCATION='Q141',
 CDS_LIB='pure_quanta',
 CDS_PART_NAME='BC847BPN-BC847BPN,SMLF,IC,BA00A',
 PART_TYPE='SMLF',
 MATERIAL='IC',
 VALUE='BC847BPN',
 PRIM_FILE='./archive_libs/logical/bc847bpn/chips/chips.prt';

PART_NAME
 Q142 'BC847BPN-BC847BPN,SMLF,IC,BA00A':;

SECTION_NUMBER 1
 '@S9S_MB_2U_LIB.S9S_MB_2U(SCH_1):PAGE122_I17@PURE_QUANTA.BC847BPN(CHIPS)':
 C_PATH='@s9s_mb_2u_lib.s9s_mb_2u(sch_1):page122_i17@pure_quanta.bc847bpn(chips)~
',
 P_PATH='@s9s_mb_2u_lib.s9s_mb_2u(sch_1):page122_i17@pure_quanta.bc847bpn(chips)~
',
 PATH='I17',
 DRAWING='@S9S_MB_2U_LIB.S9S_MB_2U(SCH_1):PAGE122',
 PHYS_PAGE='122',
 XY='(900,575)',
 ROT='0',
 VER='1',
 LOCATION='Q142',
 CDS_LIB='pure_quanta',
 CDS_PART_NAME='BC847BPN-BC847BPN,SMLF,IC,BA00A',
 PART_TYPE='SMLF',
 MATERIAL='IC',
 VALUE='BC847BPN',
 PRIM_FILE='./archive_libs/logical/bc847bpn/chips/chips.prt';

SECTION_NUMBER 2
 '@S9S_MB_2U_LIB.S9S_MB_2U(SCH_1):PAGE122_I10@PURE_QUANTA.BC847BPN(CHIPS)':
 C_PATH='@s9s_mb_2u_lib.s9s_mb_2u(sch_1):page122_i10@pure_quanta.bc847bpn(chips)~
',
 P_PATH='@s9s_mb_2u_lib.s9s_mb_2u(sch_1):page122_i10@pure_quanta.bc847bpn(chips)~
',
 PATH='I10',
 DRAWING='@S9S_MB_2U_LIB.S9S_MB_2U(SCH_1):PAGE122',
 PHYS_PAGE='122',
 XY='(-650,825)',
 ROT='0',
 VER='2',
 LOCATION='Q142',
 CDS_LIB='pure_quanta',
 CDS_PART_NAME='BC847BPN-BC847BPN,SMLF,IC,BA00A',
 PART_TYPE='SMLF',
 MATERIAL='IC',
 VALUE='BC847BPN',
 PRIM_FILE='./archive_libs/logical/bc847bpn/chips/chips.prt';

PART_NAME
 Q143 'BC847BPN-BC847BPN,SMLF,IC,BA00A':;

SECTION_NUMBER 1
 '@S9S_MB_2U_LIB.S9S_MB_2U(SCH_1):PAGE122_I22@PURE_QUANTA.BC847BPN(CHIPS)':
 C_PATH='@s9s_mb_2u_lib.s9s_mb_2u(sch_1):page122_i22@pure_quanta.bc847bpn(chips)~
',
 P_PATH='@s9s_mb_2u_lib.s9s_mb_2u(sch_1):page122_i22@pure_quanta.bc847bpn(chips)~
',
 PATH='I22',
 DRAWING='@S9S_MB_2U_LIB.S9S_MB_2U(SCH_1):PAGE122',
 PHYS_PAGE='122',
 XY='(900,1925)',
 ROT='0',
 VER='1',
 LOCATION='Q143',
 CDS_LIB='pure_quanta',
 CDS_PART_NAME='BC847BPN-BC847BPN,SMLF,IC,BA00A',
 PART_TYPE='SMLF',
 MATERIAL='IC',
 VALUE='BC847BPN',
 PRIM_FILE='./archive_libs/logical/bc847bpn/chips/chips.prt';

SECTION_NUMBER 2
 '@S9S_MB_2U_LIB.S9S_MB_2U(SCH_1):PAGE122_I12@PURE_QUANTA.BC847BPN(CHIPS)':
 C_PATH='@s9s_mb_2u_lib.s9s_mb_2u(sch_1):page122_i12@pure_quanta.bc847bpn(chips)~
',
 P_PATH='@s9s_mb_2u_lib.s9s_mb_2u(sch_1):page122_i12@pure_quanta.bc847bpn(chips)~
',
 PATH='I12',
 DRAWING='@S9S_MB_2U_LIB.S9S_MB_2U(SCH_1):PAGE122',
 PHYS_PAGE='122',
 XY='(-650,2175)',
 ROT='0',
 VER='2',
 LOCATION='Q143',
 CDS_LIB='pure_quanta',
 CDS_PART_NAME='BC847BPN-BC847BPN,SMLF,IC,BA00A',
 PART_TYPE='SMLF',
 MATERIAL='IC',
 VALUE='BC847BPN',
 PRIM_FILE='./archive_libs/logical/bc847bpn/chips/chips.prt';

PART_NAME
 Q144 'MOSFET_NCH_DUAL-PJT138K,SMLF,IA':;

SECTION_NUMBER 1
 '@S9S_MB_2U_LIB.S9S_MB_2U(SCH_1):PAGE213_I27@PURE_QUANTA.MOSFET_NCH_DUAL(CHIPS)':
 C_PATH='@s9s_mb_2u_lib.s9s_mb_2u(sch_1):page213_i27@pure_quanta.mosfet_nch_dual~
(chips)',
 P_PATH='@s9s_mb_2u_lib.s9s_mb_2u(sch_1):page224_i27@pure_quanta.mosfet_nch_dual~
(chips)',
 PATH='I27',
 DRAWING='@S9S_MB_2U_LIB.S9S_MB_2U(SCH_1):PAGE213',
 PHYS_PAGE='224',
 XY='(-8325,2350)',
 ROT='0',
 VER='1',
 LOCATION='Q144',
 CDS_LIB='pure_quanta',
 CDS_PART_NAME='MOSFET_NCH_DUAL-PJT138K,SMLF,IA',
 PART_TYPE='SMLF',
 MATERIAL='IC',
 VALUE='PJT138K',
 PRIM_FILE='./archive_libs/logical/mosfet_nch_dual/chips/chips.prt';

SECTION_NUMBER 2
 '@S9S_MB_2U_LIB.S9S_MB_2U(SCH_1):PAGE213_I21@PURE_QUANTA.MOSFET_NCH_DUAL(CHIPS)':
 C_PATH='@s9s_mb_2u_lib.s9s_mb_2u(sch_1):page213_i21@pure_quanta.mosfet_nch_dual~
(chips)',
 P_PATH='@s9s_mb_2u_lib.s9s_mb_2u(sch_1):page224_i21@pure_quanta.mosfet_nch_dual~
(chips)',
 PATH='I21',
 DRAWING='@S9S_MB_2U_LIB.S9S_MB_2U(SCH_1):PAGE213',
 PHYS_PAGE='224',
 XY='(-7175,2650)',
 ROT='0',
 VER='2',
 CDS_LIB='pure_quanta',
 CDS_PART_NAME='MOSFET_NCH_DUAL-PJT138K,SMLF,IA',
 PART_TYPE='SMLF',
 MATERIAL='IC',
 VALUE='PJT138K',
 PRIM_FILE='./archive_libs/logical/mosfet_nch_dual/chips/chips.prt';

PART_NAME
 Q145 'MOSFET_NCH_DUAL-PJT138K,SMLF,IA':;

SECTION_NUMBER 1
 '@S9S_MB_2U_LIB.S9S_MB_2U(SCH_1):PAGE230_I53@PURE_QUANTA.MOSFET_NCH_DUAL(CHIPS)':
 C_PATH='@s9s_mb_2u_lib.s9s_mb_2u(sch_1):page230_i53@pure_quanta.mosfet_nch_dual~
(chips)',
 P_PATH='@s9s_mb_2u_lib.s9s_mb_2u(sch_1):page246_i53@pure_quanta.mosfet_nch_dual~
(chips)',
 PATH='I53',
 DRAWING='@S9S_MB_2U_LIB.S9S_MB_2U(SCH_1):PAGE230',
 PHYS_PAGE='246',
 XY='(0,-2025)',
 ROT='0',
 VER='1',
 CDS_LIB='pure_quanta',
 CDS_PART_NAME='MOSFET_NCH_DUAL-PJT138K,SMLF,IA',
 PART_TYPE='SMLF',
 MATERIAL='IC',
 VALUE='PJT138K',
 PRIM_FILE='./archive_libs/logical/mosfet_nch_dual/chips/chips.prt';

SECTION_NUMBER 2
 '@S9S_MB_2U_LIB.S9S_MB_2U(SCH_1):PAGE230_I58@PURE_QUANTA.MOSFET_NCH_DUAL(CHIPS)':
 C_PATH='@s9s_mb_2u_lib.s9s_mb_2u(sch_1):page230_i58@pure_quanta.mosfet_nch_dual~
(chips)',
 P_PATH='@s9s_mb_2u_lib.s9s_mb_2u(sch_1):page246_i58@pure_quanta.mosfet_nch_dual~
(chips)',
 PATH='I58',
 DRAWING='@S9S_MB_2U_LIB.S9S_MB_2U(SCH_1):PAGE230',
 PHYS_PAGE='246',
 XY='(1150,-1725)',
 ROT='0',
 VER='2',
 CDS_LIB='pure_quanta',
 CDS_PART_NAME='MOSFET_NCH_DUAL-PJT138K,SMLF,IA',
 PART_TYPE='SMLF',
 MATERIAL='IC',
 VALUE='PJT138K',
 PRIM_FILE='./archive_libs/logical/mosfet_nch_dual/chips/chips.prt';

PART_NAME
 Q146 'MOSFET_NCH_DUAL-PJT138K,SMLF,IA':;

SECTION_NUMBER 1
 '@S9S_MB_2U_LIB.S9S_MB_2U(SCH_1):PAGE143_I126@PURE_QUANTA.MOSFET_NCH_DUAL(CHIPS)':
 C_PATH='@s9s_mb_2u_lib.s9s_mb_2u(sch_1):page143_i126@pure_quanta.mosfet_nch_dua~
l(chips)',
 P_PATH='@s9s_mb_2u_lib.s9s_mb_2u(sch_1):page146_i126@pure_quanta.mosfet_nch_dua~
l(chips)',
 PATH='I126',
 DRAWING='@S9S_MB_2U_LIB.S9S_MB_2U(SCH_1):PAGE143',
 PHYS_PAGE='146',
 XY='(3450,-500)',
 ROT='0',
 VER='1',
 CDS_LIB='pure_quanta',
 CDS_PART_NAME='MOSFET_NCH_DUAL-PJT138K,SMLF,IA',
 PART_TYPE='SMLF',
 MATERIAL='IC',
 VALUE='PJT138K',
 PRIM_FILE='./archive_libs/logical/mosfet_nch_dual/chips/chips.prt';

SECTION_NUMBER 2
 '@S9S_MB_2U_LIB.S9S_MB_2U(SCH_1):PAGE143_I121@PURE_QUANTA.MOSFET_NCH_DUAL(CHIPS)':
 C_PATH='@s9s_mb_2u_lib.s9s_mb_2u(sch_1):page143_i121@pure_quanta.mosfet_nch_dua~
l(chips)',
 P_PATH='@s9s_mb_2u_lib.s9s_mb_2u(sch_1):page146_i121@pure_quanta.mosfet_nch_dua~
l(chips)',
 PATH='I121',
 DRAWING='@S9S_MB_2U_LIB.S9S_MB_2U(SCH_1):PAGE143',
 PHYS_PAGE='146',
 XY='(4600,-200)',
 ROT='0',
 VER='2',
 LOCATION='Q146',
 CDS_LIB='pure_quanta',
 CDS_PART_NAME='MOSFET_NCH_DUAL-PJT138K,SMLF,IA',
 PART_TYPE='SMLF',
 MATERIAL='IC',
 VALUE='PJT138K',
 PRIM_FILE='./archive_libs/logical/mosfet_nch_dual/chips/chips.prt';

PART_NAME
 Q148 'MOSFET_NCH_DUAL-PJT138K,SMLF,IA':;

SECTION_NUMBER 1
 '@S9S_MB_2U_LIB.S9S_MB_2U(SCH_1):PAGE139_I61@PURE_QUANTA.MOSFET_NCH_DUAL(CHIPS)':
 C_PATH='@s9s_mb_2u_lib.s9s_mb_2u(sch_1):page139_i61@pure_quanta.mosfet_nch_dual~
(chips)',
 P_PATH='@s9s_mb_2u_lib.s9s_mb_2u(sch_1):page145_i61@pure_quanta.mosfet_nch_dual~
(chips)',
 PATH='I61',
 DRAWING='@S9S_MB_2U_LIB.S9S_MB_2U(SCH_1):PAGE139',
 PHYS_PAGE='145',
 XY='(-875,525)',
 ROT='0',
 VER='1',
 CDS_LIB='pure_quanta',
 CDS_PART_NAME='MOSFET_NCH_DUAL-PJT138K,SMLF,IA',
 PART_TYPE='SMLF',
 MATERIAL='IC',
 VALUE='PJT138K',
 PRIM_FILE='./archive_libs/logical/mosfet_nch_dual/chips/chips.prt';

SECTION_NUMBER 2
 '@S9S_MB_2U_LIB.S9S_MB_2U(SCH_1):PAGE139_I55@PURE_QUANTA.MOSFET_NCH_DUAL(CHIPS)':
 C_PATH='@s9s_mb_2u_lib.s9s_mb_2u(sch_1):page139_i55@pure_quanta.mosfet_nch_dual~
(chips)',
 P_PATH='@s9s_mb_2u_lib.s9s_mb_2u(sch_1):page145_i55@pure_quanta.mosfet_nch_dual~
(chips)',
 PATH='I55',
 DRAWING='@S9S_MB_2U_LIB.S9S_MB_2U(SCH_1):PAGE139',
 PHYS_PAGE='145',
 XY='(275,825)',
 ROT='0',
 VER='2',
 LOCATION='Q148',
 CDS_LIB='pure_quanta',
 CDS_PART_NAME='MOSFET_NCH_DUAL-PJT138K,SMLF,IA',
 PART_TYPE='SMLF',
 MATERIAL='IC',
 VALUE='PJT138K',
 PRIM_FILE='./archive_libs/logical/mosfet_nch_dual/chips/chips.prt';

PART_NAME
 Q150 'MOSFET_NCH_DUAL-PJT138K,SMLF,IA':;

SECTION_NUMBER 1
 '@S9S_MB_2U_LIB.S9S_MB_2U(SCH_1):PAGE241_I69@PURE_QUANTA.MOSFET_NCH_DUAL(CHIPS)':
 C_PATH='@s9s_mb_2u_lib.s9s_mb_2u(sch_1):page241_i69@pure_quanta.mosfet_nch_dual~
(chips)',
 P_PATH='@s9s_mb_2u_lib.s9s_mb_2u(sch_1):page255_i69@pure_quanta.mosfet_nch_dual~
(chips)',
 PATH='I69',
 DRAWING='@S9S_MB_2U_LIB.S9S_MB_2U(SCH_1):PAGE241',
 PHYS_PAGE='255',
 XY='(-9075,-225)',
 ROT='0',
 VER='1',
 CDS_LIB='pure_quanta',
 CDS_PART_NAME='MOSFET_NCH_DUAL-PJT138K,SMLF,IA',
 PART_TYPE='SMLF',
 MATERIAL='IC',
 VALUE='PJT138K',
 PRIM_FILE='./archive_libs/logical/mosfet_nch_dual/chips/chips.prt';

SECTION_NUMBER 2
 '@S9S_MB_2U_LIB.S9S_MB_2U(SCH_1):PAGE241_I72@PURE_QUANTA.MOSFET_NCH_DUAL(CHIPS)':
 C_PATH='@s9s_mb_2u_lib.s9s_mb_2u(sch_1):page241_i72@pure_quanta.mosfet_nch_dual~
(chips)',
 P_PATH='@s9s_mb_2u_lib.s9s_mb_2u(sch_1):page255_i72@pure_quanta.mosfet_nch_dual~
(chips)',
 PATH='I72',
 DRAWING='@S9S_MB_2U_LIB.S9S_MB_2U(SCH_1):PAGE241',
 PHYS_PAGE='255',
 XY='(-8025,150)',
 ROT='0',
 VER='2',
 CDS_LIB='pure_quanta',
 CDS_PART_NAME='MOSFET_NCH_DUAL-PJT138K,SMLF,IA',
 PART_TYPE='SMLF',
 MATERIAL='IC',
 VALUE='PJT138K',
 PRIM_FILE='./archive_libs/logical/mosfet_nch_dual/chips/chips.prt';

PART_NAME
 Q151 'MOSFET_NCH_DUAL-PJT138K,SMLF,IA':;

SECTION_NUMBER 1
 '@S9S_MB_2U_LIB.S9S_MB_2U(SCH_1):PAGE147_I31@PURE_QUANTA.MOSFET_NCH_DUAL(CHIPS)':
 C_PATH='@s9s_mb_2u_lib.s9s_mb_2u(sch_1):page147_i31@pure_quanta.mosfet_nch_dual~
(chips)',
 P_PATH='@s9s_mb_2u_lib.s9s_mb_2u(sch_1):page144_i31@pure_quanta.mosfet_nch_dual~
(chips)',
 PATH='I31',
 DRAWING='@S9S_MB_2U_LIB.S9S_MB_2U(SCH_1):PAGE147',
 PHYS_PAGE='144',
 XY='(-5600,7950)',
 ROT='0',
 VER='1',
 CDS_LIB='pure_quanta',
 CDS_PART_NAME='MOSFET_NCH_DUAL-PJT138K,SMLF,IA',
 PART_TYPE='SMLF',
 MATERIAL='IC',
 VALUE='PJT138K',
 PRIM_FILE='./archive_libs/logical/mosfet_nch_dual/chips/chips.prt';

SECTION_NUMBER 2
 '@S9S_MB_2U_LIB.S9S_MB_2U(SCH_1):PAGE147_I20@PURE_QUANTA.MOSFET_NCH_DUAL(CHIPS)':
 C_PATH='@s9s_mb_2u_lib.s9s_mb_2u(sch_1):page147_i20@pure_quanta.mosfet_nch_dual~
(chips)',
 P_PATH='@s9s_mb_2u_lib.s9s_mb_2u(sch_1):page144_i20@pure_quanta.mosfet_nch_dual~
(chips)',
 PATH='I20',
 DRAWING='@S9S_MB_2U_LIB.S9S_MB_2U(SCH_1):PAGE147',
 PHYS_PAGE='144',
 XY='(-4450,8250)',
 ROT='0',
 VER='2',
 LOCATION='Q151',
 CDS_LIB='pure_quanta',
 CDS_PART_NAME='MOSFET_NCH_DUAL-PJT138K,SMLF,IA',
 PART_TYPE='SMLF',
 MATERIAL='IC',
 VALUE='PJT138K',
 PRIM_FILE='./archive_libs/logical/mosfet_nch_dual/chips/chips.prt';

PART_NAME
 Q152 'MOSFET_NCH_DUAL-PJT138K,SMLF,IA':;

SECTION_NUMBER 1
 '@S9S_MB_2U_LIB.S9S_MB_2U(SCH_1):PAGE147_I38@PURE_QUANTA.MOSFET_NCH_DUAL(CHIPS)':
 C_PATH='@s9s_mb_2u_lib.s9s_mb_2u(sch_1):page147_i38@pure_quanta.mosfet_nch_dual~
(chips)',
 P_PATH='@s9s_mb_2u_lib.s9s_mb_2u(sch_1):page144_i38@pure_quanta.mosfet_nch_dual~
(chips)',
 PATH='I38',
 DRAWING='@S9S_MB_2U_LIB.S9S_MB_2U(SCH_1):PAGE147',
 PHYS_PAGE='144',
 XY='(-5475,6425)',
 ROT='0',
 VER='1',
 CDS_LIB='pure_quanta',
 CDS_PART_NAME='MOSFET_NCH_DUAL-PJT138K,SMLF,IA',
 PART_TYPE='SMLF',
 MATERIAL='IC',
 VALUE='PJT138K',
 PRIM_FILE='./archive_libs/logical/mosfet_nch_dual/chips/chips.prt';

SECTION_NUMBER 2
 '@S9S_MB_2U_LIB.S9S_MB_2U(SCH_1):PAGE147_I26@PURE_QUANTA.MOSFET_NCH_DUAL(CHIPS)':
 C_PATH='@s9s_mb_2u_lib.s9s_mb_2u(sch_1):page147_i26@pure_quanta.mosfet_nch_dual~
(chips)',
 P_PATH='@s9s_mb_2u_lib.s9s_mb_2u(sch_1):page144_i26@pure_quanta.mosfet_nch_dual~
(chips)',
 PATH='I26',
 DRAWING='@S9S_MB_2U_LIB.S9S_MB_2U(SCH_1):PAGE147',
 PHYS_PAGE='144',
 XY='(-4325,6725)',
 ROT='0',
 VER='2',
 LOCATION='Q152',
 CDS_LIB='pure_quanta',
 CDS_PART_NAME='MOSFET_NCH_DUAL-PJT138K,SMLF,IA',
 PART_TYPE='SMLF',
 MATERIAL='IC',
 VALUE='PJT138K',
 PRIM_FILE='./archive_libs/logical/mosfet_nch_dual/chips/chips.prt';

PART_NAME
 Q153 'MOSFET_NCH_DUAL-PJT138K,SMLF,IA':;

SECTION_NUMBER 1
 '@S9S_MB_2U_LIB.S9S_MB_2U(SCH_1):PAGE147_I55@PURE_QUANTA.MOSFET_NCH_DUAL(CHIPS)':
 C_PATH='@s9s_mb_2u_lib.s9s_mb_2u(sch_1):page147_i55@pure_quanta.mosfet_nch_dual~
(chips)',
 P_PATH='@s9s_mb_2u_lib.s9s_mb_2u(sch_1):page144_i55@pure_quanta.mosfet_nch_dual~
(chips)',
 PATH='I55',
 DRAWING='@S9S_MB_2U_LIB.S9S_MB_2U(SCH_1):PAGE147',
 PHYS_PAGE='144',
 XY='(-5250,4775)',
 ROT='0',
 VER='1',
 LOCATION='Q153',
 CDS_LIB='pure_quanta',
 CDS_PART_NAME='MOSFET_NCH_DUAL-PJT138K,SMLF,IA',
 PART_TYPE='SMLF',
 MATERIAL='IC',
 VALUE='PJT138K',
 PRIM_FILE='./archive_libs/logical/mosfet_nch_dual/chips/chips.prt';

SECTION_NUMBER 2
 '@S9S_MB_2U_LIB.S9S_MB_2U(SCH_1):PAGE147_I51@PURE_QUANTA.MOSFET_NCH_DUAL(CHIPS)':
 C_PATH='@s9s_mb_2u_lib.s9s_mb_2u(sch_1):page147_i51@pure_quanta.mosfet_nch_dual~
(chips)',
 P_PATH='@s9s_mb_2u_lib.s9s_mb_2u(sch_1):page144_i51@pure_quanta.mosfet_nch_dual~
(chips)',
 PATH='I51',
 DRAWING='@S9S_MB_2U_LIB.S9S_MB_2U(SCH_1):PAGE147',
 PHYS_PAGE='144',
 XY='(-4100,5075)',
 ROT='0',
 VER='2',
 LOCATION='Q153',
 CDS_LIB='pure_quanta',
 CDS_PART_NAME='MOSFET_NCH_DUAL-PJT138K,SMLF,IA',
 PART_TYPE='SMLF',
 MATERIAL='IC',
 VALUE='PJT138K',
 PRIM_FILE='./archive_libs/logical/mosfet_nch_dual/chips/chips.prt';

PART_NAME
 Q154 'MOSFET_NCH_DUAL-PJT138K,SMLF,IA':;

SECTION_NUMBER 1
 '@S9S_MB_2U_LIB.S9S_MB_2U(SCH_1):PAGE147_I71@PURE_QUANTA.MOSFET_NCH_DUAL(CHIPS)':
 C_PATH='@s9s_mb_2u_lib.s9s_mb_2u(sch_1):page147_i71@pure_quanta.mosfet_nch_dual~
(chips)',
 P_PATH='@s9s_mb_2u_lib.s9s_mb_2u(sch_1):page144_i71@pure_quanta.mosfet_nch_dual~
(chips)',
 PATH='I71',
 DRAWING='@S9S_MB_2U_LIB.S9S_MB_2U(SCH_1):PAGE147',
 PHYS_PAGE='144',
 XY='(-5225,3375)',
 ROT='0',
 VER='1',
 LOCATION='Q154',
 CDS_LIB='pure_quanta',
 CDS_PART_NAME='MOSFET_NCH_DUAL-PJT138K,SMLF,IA',
 PART_TYPE='SMLF',
 MATERIAL='IC',
 VALUE='PJT138K',
 PRIM_FILE='./archive_libs/logical/mosfet_nch_dual/chips/chips.prt';

SECTION_NUMBER 2
 '@S9S_MB_2U_LIB.S9S_MB_2U(SCH_1):PAGE147_I62@PURE_QUANTA.MOSFET_NCH_DUAL(CHIPS)':
 C_PATH='@s9s_mb_2u_lib.s9s_mb_2u(sch_1):page147_i62@pure_quanta.mosfet_nch_dual~
(chips)',
 P_PATH='@s9s_mb_2u_lib.s9s_mb_2u(sch_1):page144_i62@pure_quanta.mosfet_nch_dual~
(chips)',
 PATH='I62',
 DRAWING='@S9S_MB_2U_LIB.S9S_MB_2U(SCH_1):PAGE147',
 PHYS_PAGE='144',
 XY='(-4075,3675)',
 ROT='0',
 VER='2',
 LOCATION='Q154',
 CDS_LIB='pure_quanta',
 CDS_PART_NAME='MOSFET_NCH_DUAL-PJT138K,SMLF,IA',
 PART_TYPE='SMLF',
 MATERIAL='IC',
 VALUE='PJT138K',
 PRIM_FILE='./archive_libs/logical/mosfet_nch_dual/chips/chips.prt';

PART_NAME
 Q236 'MOSFET_NCH_DUAL-PJT138K,SMLF,IA':;

SECTION_NUMBER 1
 '@S9S_MB_2U_LIB.S9S_MB_2U(SCH_1):PAGE246_I99@PURE_QUANTA.MOSFET_NCH_DUAL(CHIPS)':
 C_PATH='@s9s_mb_2u_lib.s9s_mb_2u(sch_1):page246_i99@pure_quanta.mosfet_nch_dual~
(chips)',
 P_PATH='@s9s_mb_2u_lib.s9s_mb_2u(sch_1):page260_i99@pure_quanta.mosfet_nch_dual~
(chips)',
 PATH='I99',
 DRAWING='@S9S_MB_2U_LIB.S9S_MB_2U(SCH_1):PAGE246',
 PHYS_PAGE='260',
 XY='(-2075,3775)',
 ROT='0',
 VER='1',
 LOCATION='Q236',
 CDS_LIB='pure_quanta',
 CDS_PART_NAME='MOSFET_NCH_DUAL-PJT138K,SMLF,IA',
 PART_TYPE='SMLF',
 MATERIAL='IC',
 VALUE='PJT138K',
 PRIM_FILE='./archive_libs/logical/mosfet_nch_dual/chips/chips.prt';

SECTION_NUMBER 2
 '@S9S_MB_2U_LIB.S9S_MB_2U(SCH_1):PAGE246_I98@PURE_QUANTA.MOSFET_NCH_DUAL(CHIPS)':
 C_PATH='@s9s_mb_2u_lib.s9s_mb_2u(sch_1):page246_i98@pure_quanta.mosfet_nch_dual~
(chips)',
 P_PATH='@s9s_mb_2u_lib.s9s_mb_2u(sch_1):page260_i98@pure_quanta.mosfet_nch_dual~
(chips)',
 PATH='I98',
 DRAWING='@S9S_MB_2U_LIB.S9S_MB_2U(SCH_1):PAGE246',
 PHYS_PAGE='260',
 XY='(-1250,3750)',
 ROT='0',
 VER='2',
 LOCATION='Q236',
 CDS_LIB='pure_quanta',
 CDS_PART_NAME='MOSFET_NCH_DUAL-PJT138K,SMLF,IA',
 PART_TYPE='SMLF',
 MATERIAL='IC',
 VALUE='PJT138K',
 PRIM_FILE='./archive_libs/logical/mosfet_nch_dual/chips/chips.prt';

PART_NAME
 R1 'Q_RES_0402LF-10,1%,1/16W,CHIP,A':;

SECTION_NUMBER 1
 '@S9S_MB_2U_LIB.S9S_MB_2U(SCH_1):PAGE13_I18@PURE_QUANTA.Q_RES(CHIPS)':
 C_PATH='@s9s_mb_2u_lib.s9s_mb_2u(sch_1):page13_i18@pure_quanta.q_res(chips)',
 P_PATH='@s9s_mb_2u_lib.s9s_mb_2u(sch_1):page13_i18@pure_quanta.q_res(chips)',
 PATH='I18',
 DRAWING='@S9S_MB_2U_LIB.S9S_MB_2U(SCH_1):PAGE13',
 PHYS_PAGE='13',
 XY='(-2125,2075)',
 ROT='0',
 VER='1',
 PACK_TYPE='0402LF',
 CDS_LIB='pure_quanta',
 CDS_PART_NAME='Q_RES_0402LF-10,1%,1/16W,CHIP,A',
 WATTAGE='1/16W',
 TOLERANCE='1%',
 MATERIAL='CHIP',
 VALUE='10',
 PRIM_FILE='./archive_libs/logical/q_res/chips/chips.prt';

PART_NAME
 R2 'Q_RES_0402LF-100,1%,1/16W,CHIPA':;

SECTION_NUMBER 1
 '@S9S_MB_2U_LIB.S9S_MB_2U(SCH_1):PAGE13_I16@PURE_QUANTA.Q_RES(CHIPS)':
 C_PATH='@s9s_mb_2u_lib.s9s_mb_2u(sch_1):page13_i16@pure_quanta.q_res(chips)',
 P_PATH='@s9s_mb_2u_lib.s9s_mb_2u(sch_1):page13_i16@pure_quanta.q_res(chips)',
 PATH='I16',
 DRAWING='@S9S_MB_2U_LIB.S9S_MB_2U(SCH_1):PAGE13',
 PHYS_PAGE='13',
 XY='(-2125,2025)',
 ROT='0',
 VER='1',
 PACK_TYPE='0402LF',
 CDS_LIB='pure_quanta',
 CDS_PART_NAME='Q_RES_0402LF-100,1%,1/16W,CHIPA',
 WATTAGE='1/16W',
 TOLERANCE='1%',
 MATERIAL='CHIP',
 VALUE='100',
 PRIM_FILE='./archive_libs/logical/q_res/chips/chips.prt';

PART_NAME
 R3 'Q_RES_0402LF-33.2,1%,1/16W,CHIA':;

SECTION_NUMBER 1
 '@S9S_MB_2U_LIB.S9S_MB_2U(SCH_1):PAGE13_I21@PURE_QUANTA.Q_RES(CHIPS)':
 C_PATH='@s9s_mb_2u_lib.s9s_mb_2u(sch_1):page13_i21@pure_quanta.q_res(chips)',
 P_PATH='@s9s_mb_2u_lib.s9s_mb_2u(sch_1):page13_i21@pure_quanta.q_res(chips)',
 PATH='I21',
 DRAWING='@S9S_MB_2U_LIB.S9S_MB_2U(SCH_1):PAGE13',
 PHYS_PAGE='13',
 XY='(-2125,1925)',
 ROT='0',
 VER='1',
 PACK_TYPE='0402LF',
 CDS_LIB='pure_quanta',
 CDS_PART_NAME='Q_RES_0402LF-33.2,1%,1/16W,CHIA',
 WATTAGE='1/16W',
 TOLERANCE='1%',
 MATERIAL='CHIP',
 VALUE='33.2',
 PRIM_FILE='./archive_libs/logical/q_res/chips/chips.prt';

PART_NAME
 R4 'Q_RES_0402LF-200,1%,1/16W,CHIPA':;

SECTION_NUMBER 1
 '@S9S_MB_2U_LIB.S9S_MB_2U(SCH_1):PAGE13_I29@PURE_QUANTA.Q_RES(CHIPS)':
 C_PATH='@s9s_mb_2u_lib.s9s_mb_2u(sch_1):page13_i29@pure_quanta.q_res(chips)',
 P_PATH='@s9s_mb_2u_lib.s9s_mb_2u(sch_1):page13_i29@pure_quanta.q_res(chips)',
 PATH='I29',
 DRAWING='@S9S_MB_2U_LIB.S9S_MB_2U(SCH_1):PAGE13',
 PHYS_PAGE='13',
 XY='(-2125,1825)',
 ROT='0',
 VER='1',
 PACK_TYPE='0402LF',
 CDS_LIB='pure_quanta',
 CDS_PART_NAME='Q_RES_0402LF-200,1%,1/16W,CHIPA',
 WATTAGE='1/16W',
 TOLERANCE='1%',
 MATERIAL='CHIP',
 VALUE='200',
 PRIM_FILE='./archive_libs/logical/q_res/chips/chips.prt';

PART_NAME
 R5 'Q_RES_0402LF-100,1%,1/16W,CHIPA':;

SECTION_NUMBER 1
 '@S9S_MB_2U_LIB.S9S_MB_2U(SCH_1):PAGE13_I24@PURE_QUANTA.Q_RES(CHIPS)':
 C_PATH='@s9s_mb_2u_lib.s9s_mb_2u(sch_1):page13_i24@pure_quanta.q_res(chips)',
 P_PATH='@s9s_mb_2u_lib.s9s_mb_2u(sch_1):page13_i24@pure_quanta.q_res(chips)',
 PATH='I24',
 DRAWING='@S9S_MB_2U_LIB.S9S_MB_2U(SCH_1):PAGE13',
 PHYS_PAGE='13',
 XY='(-2125,1775)',
 ROT='0',
 VER='1',
 PACK_TYPE='0402LF',
 CDS_LIB='pure_quanta',
 CDS_PART_NAME='Q_RES_0402LF-100,1%,1/16W,CHIPA',
 WATTAGE='1/16W',
 TOLERANCE='1%',
 MATERIAL='CHIP',
 VALUE='100',
 PRIM_FILE='./archive_libs/logical/q_res/chips/chips.prt';

PART_NAME
 R6 'Q_RES_0402LF-100,1%,1/16W,CHIPA':;

SECTION_NUMBER 1
 '@S9S_MB_2U_LIB.S9S_MB_2U(SCH_1):PAGE13_I25@PURE_QUANTA.Q_RES(CHIPS)':
 C_PATH='@s9s_mb_2u_lib.s9s_mb_2u(sch_1):page13_i25@pure_quanta.q_res(chips)',
 P_PATH='@s9s_mb_2u_lib.s9s_mb_2u(sch_1):page13_i25@pure_quanta.q_res(chips)',
 PATH='I25',
 DRAWING='@S9S_MB_2U_LIB.S9S_MB_2U(SCH_1):PAGE13',
 PHYS_PAGE='13',
 XY='(-2125,1725)',
 ROT='0',
 VER='1',
 PACK_TYPE='0402LF',
 CDS_LIB='pure_quanta',
 CDS_PART_NAME='Q_RES_0402LF-100,1%,1/16W,CHIPA',
 WATTAGE='1/16W',
 TOLERANCE='1%',
 MATERIAL='CHIP',
 VALUE='100',
 PRIM_FILE='./archive_libs/logical/q_res/chips/chips.prt';

PART_NAME
 R7 'Q_RES_0402LF-33.2,1%,1/16W,CHIA':;

SECTION_NUMBER 1
 '@S9S_MB_2U_LIB.S9S_MB_2U(SCH_1):PAGE14_I66@PURE_QUANTA.Q_RES(CHIPS)':
 C_PATH='@s9s_mb_2u_lib.s9s_mb_2u(sch_1):page14_i66@pure_quanta.q_res(chips)',
 P_PATH='@s9s_mb_2u_lib.s9s_mb_2u(sch_1):page14_i66@pure_quanta.q_res(chips)',
 PATH='I66',
 DRAWING='@S9S_MB_2U_LIB.S9S_MB_2U(SCH_1):PAGE14',
 PHYS_PAGE='14',
 XY='(-1600,1200)',
 ROT='0',
 VER='1',
 PACK_TYPE='0402LF',
 CDS_LIB='pure_quanta',
 CDS_PART_NAME='Q_RES_0402LF-33.2,1%,1/16W,CHIA',
 WATTAGE='1/16W',
 TOLERANCE='1%',
 MATERIAL='CHIP',
 VALUE='33.2',
 PRIM_FILE='./archive_libs/logical/q_res/chips/chips.prt';

PART_NAME
 R8 'Q_RES_0402LF-10K,1%,1/16W,CHIPA':;

SECTION_NUMBER 1
 '@S9S_MB_2U_LIB.S9S_MB_2U(SCH_1):PAGE192_I59@PURE_QUANTA.Q_RES(CHIPS)':
 C_PATH='@s9s_mb_2u_lib.s9s_mb_2u(sch_1):page192_i59@pure_quanta.q_res(chips)',
 P_PATH='@s9s_mb_2u_lib.s9s_mb_2u(sch_1):page204_i59@pure_quanta.q_res(chips)',
 PATH='I59',
 DRAWING='@S9S_MB_2U_LIB.S9S_MB_2U(SCH_1):PAGE192',
 PHYS_PAGE='204',
 XY='(-4950,1300)',
 ROT='0',
 VER='1',
 PACK_TYPE='0402LF',
 CDS_LIB='pure_quanta',
 CDS_PART_NAME='Q_RES_0402LF-10K,1%,1/16W,CHIPA',
 WATTAGE='1/16W',
 TOLERANCE='1%',
 MATERIAL='CHIP',
 VALUE='10K',
 PRIM_FILE='./archive_libs/logical/q_res/chips/chips.prt';

PART_NAME
 R10 'Q_RES_0402LF-33.2,1%,1/16W,CHIA':;

SECTION_NUMBER 1
 '@S9S_MB_2U_LIB.S9S_MB_2U(SCH_1):PAGE14_I78@PURE_QUANTA.Q_RES(CHIPS)':
 C_PATH='@s9s_mb_2u_lib.s9s_mb_2u(sch_1):page14_i78@pure_quanta.q_res(chips)',
 P_PATH='@s9s_mb_2u_lib.s9s_mb_2u(sch_1):page14_i78@pure_quanta.q_res(chips)',
 PATH='I78',
 DRAWING='@S9S_MB_2U_LIB.S9S_MB_2U(SCH_1):PAGE14',
 PHYS_PAGE='14',
 XY='(-1600,500)',
 ROT='0',
 VER='1',
 PACK_TYPE='0402LF',
 CDS_LIB='pure_quanta',
 CDS_PART_NAME='Q_RES_0402LF-33.2,1%,1/16W,CHIA',
 WATTAGE='1/16W',
 TOLERANCE='1%',
 MATERIAL='CHIP',
 VALUE='33.2',
 PRIM_FILE='./archive_libs/logical/q_res/chips/chips.prt';

PART_NAME
 R11 'Q_RES_0402LF-33.2,1%,1/16W,CHIA':;

SECTION_NUMBER 1
 '@S9S_MB_2U_LIB.S9S_MB_2U(SCH_1):PAGE14_I79@PURE_QUANTA.Q_RES(CHIPS)':
 C_PATH='@s9s_mb_2u_lib.s9s_mb_2u(sch_1):page14_i79@pure_quanta.q_res(chips)',
 P_PATH='@s9s_mb_2u_lib.s9s_mb_2u(sch_1):page14_i79@pure_quanta.q_res(chips)',
 PATH='I79',
 DRAWING='@S9S_MB_2U_LIB.S9S_MB_2U(SCH_1):PAGE14',
 PHYS_PAGE='14',
 XY='(-1600,-225)',
 ROT='0',
 VER='1',
 PACK_TYPE='0402LF',
 CDS_LIB='pure_quanta',
 CDS_PART_NAME='Q_RES_0402LF-33.2,1%,1/16W,CHIA',
 WATTAGE='1/16W',
 TOLERANCE='1%',
 MATERIAL='CHIP',
 VALUE='33.2',
 PRIM_FILE='./archive_libs/logical/q_res/chips/chips.prt';

PART_NAME
 R12 'Q_RES_0402LF-0,5%,1/16W,CHIP,CA':;

SECTION_NUMBER 1
 '@S9S_MB_2U_LIB.S9S_MB_2U(SCH_1):PAGE14_I59@PURE_QUANTA.Q_RES(CHIPS)':
 C_PATH='@s9s_mb_2u_lib.s9s_mb_2u(sch_1):page14_i59@pure_quanta.q_res(chips)',
 P_PATH='@s9s_mb_2u_lib.s9s_mb_2u(sch_1):page14_i59@pure_quanta.q_res(chips)',
 PATH='I59',
 DRAWING='@S9S_MB_2U_LIB.S9S_MB_2U(SCH_1):PAGE14',
 PHYS_PAGE='14',
 XY='(2000,4500)',
 ROT='0',
 VER='1',
 PACK_TYPE='0402LF',
 CDS_LIB='pure_quanta',
 CDS_PART_NAME='Q_RES_0402LF-0,5%,1/16W,CHIP,CA',
 WATTAGE='1/16W',
 TOLERANCE='5%',
 MATERIAL='CHIP',
 VALUE='0',
 PRIM_FILE='./archive_libs/logical/q_res/chips/chips.prt';

PART_NAME
 R13 'Q_RES_0402LF-0,5%,1/16W,CHIP,CA':;

SECTION_NUMBER 1
 '@S9S_MB_2U_LIB.S9S_MB_2U(SCH_1):PAGE14_I60@PURE_QUANTA.Q_RES(CHIPS)':
 C_PATH='@s9s_mb_2u_lib.s9s_mb_2u(sch_1):page14_i60@pure_quanta.q_res(chips)',
 P_PATH='@s9s_mb_2u_lib.s9s_mb_2u(sch_1):page14_i60@pure_quanta.q_res(chips)',
 PATH='I60',
 DRAWING='@S9S_MB_2U_LIB.S9S_MB_2U(SCH_1):PAGE14',
 PHYS_PAGE='14',
 XY='(2000,4450)',
 ROT='0',
 VER='1',
 PACK_TYPE='0402LF',
 CDS_LIB='pure_quanta',
 CDS_PART_NAME='Q_RES_0402LF-0,5%,1/16W,CHIP,CA',
 WATTAGE='1/16W',
 TOLERANCE='5%',
 MATERIAL='CHIP',
 VALUE='0',
 PRIM_FILE='./archive_libs/logical/q_res/chips/chips.prt';

PART_NAME
 R14 'Q_RES_0402LF-200,1%,1/16W,CHIPA':;

SECTION_NUMBER 1
 '@S9S_MB_2U_LIB.S9S_MB_2U(SCH_1):PAGE14_I61@PURE_QUANTA.Q_RES(CHIPS)':
 C_PATH='@s9s_mb_2u_lib.s9s_mb_2u(sch_1):page14_i61@pure_quanta.q_res(chips)',
 P_PATH='@s9s_mb_2u_lib.s9s_mb_2u(sch_1):page14_i61@pure_quanta.q_res(chips)',
 PATH='I61',
 DRAWING='@S9S_MB_2U_LIB.S9S_MB_2U(SCH_1):PAGE14',
 PHYS_PAGE='14',
 XY='(2000,4400)',
 ROT='0',
 VER='1',
 PACK_TYPE='0402LF',
 CDS_LIB='pure_quanta',
 CDS_PART_NAME='Q_RES_0402LF-200,1%,1/16W,CHIPA',
 WATTAGE='1/16W',
 TOLERANCE='1%',
 MATERIAL='CHIP',
 VALUE='200',
 PRIM_FILE='./archive_libs/logical/q_res/chips/chips.prt';

PART_NAME
 R15 'Q_RES_0402LF-0,5%,1/16W,CHIP,CA':;

SECTION_NUMBER 1
 '@S9S_MB_2U_LIB.S9S_MB_2U(SCH_1):PAGE14_I62@PURE_QUANTA.Q_RES(CHIPS)':
 C_PATH='@s9s_mb_2u_lib.s9s_mb_2u(sch_1):page14_i62@pure_quanta.q_res(chips)',
 P_PATH='@s9s_mb_2u_lib.s9s_mb_2u(sch_1):page14_i62@pure_quanta.q_res(chips)',
 PATH='I62',
 DRAWING='@S9S_MB_2U_LIB.S9S_MB_2U(SCH_1):PAGE14',
 PHYS_PAGE='14',
 XY='(2000,4300)',
 ROT='0',
 VER='1',
 PACK_TYPE='0402LF',
 CDS_LIB='pure_quanta',
 CDS_PART_NAME='Q_RES_0402LF-0,5%,1/16W,CHIP,CA',
 WATTAGE='1/16W',
 TOLERANCE='5%',
 MATERIAL='CHIP',
 VALUE='0',
 PRIM_FILE='./archive_libs/logical/q_res/chips/chips.prt';

PART_NAME
 R16 'Q_RES_0402LF-0,5%,1/16W,CHIP,CA':;

SECTION_NUMBER 1
 '@S9S_MB_2U_LIB.S9S_MB_2U(SCH_1):PAGE14_I63@PURE_QUANTA.Q_RES(CHIPS)':
 C_PATH='@s9s_mb_2u_lib.s9s_mb_2u(sch_1):page14_i63@pure_quanta.q_res(chips)',
 P_PATH='@s9s_mb_2u_lib.s9s_mb_2u(sch_1):page14_i63@pure_quanta.q_res(chips)',
 PATH='I63',
 DRAWING='@S9S_MB_2U_LIB.S9S_MB_2U(SCH_1):PAGE14',
 PHYS_PAGE='14',
 XY='(2000,4250)',
 ROT='0',
 VER='1',
 PACK_TYPE='0402LF',
 CDS_LIB='pure_quanta',
 CDS_PART_NAME='Q_RES_0402LF-0,5%,1/16W,CHIP,CA',
 WATTAGE='1/16W',
 TOLERANCE='5%',
 MATERIAL='CHIP',
 VALUE='0',
 PRIM_FILE='./archive_libs/logical/q_res/chips/chips.prt';

PART_NAME
 R17 'Q_RES_0402LF-200,1%,1/16W,CHIPA':;

SECTION_NUMBER 1
 '@S9S_MB_2U_LIB.S9S_MB_2U(SCH_1):PAGE14_I64@PURE_QUANTA.Q_RES(CHIPS)':
 C_PATH='@s9s_mb_2u_lib.s9s_mb_2u(sch_1):page14_i64@pure_quanta.q_res(chips)',
 P_PATH='@s9s_mb_2u_lib.s9s_mb_2u(sch_1):page14_i64@pure_quanta.q_res(chips)',
 PATH='I64',
 DRAWING='@S9S_MB_2U_LIB.S9S_MB_2U(SCH_1):PAGE14',
 PHYS_PAGE='14',
 XY='(2000,4200)',
 ROT='0',
 VER='1',
 PACK_TYPE='0402LF',
 CDS_LIB='pure_quanta',
 CDS_PART_NAME='Q_RES_0402LF-200,1%,1/16W,CHIPA',
 WATTAGE='1/16W',
 TOLERANCE='1%',
 MATERIAL='CHIP',
 VALUE='200',
 PRIM_FILE='./archive_libs/logical/q_res/chips/chips.prt';

PART_NAME
 R18 'Q_RES_0402LF-499,1%,1/16W,CHIPA':;

SECTION_NUMBER 1
 '@S9S_MB_2U_LIB.S9S_MB_2U(SCH_1):PAGE16_I35@PURE_QUANTA.Q_RES(CHIPS)':
 C_PATH='@s9s_mb_2u_lib.s9s_mb_2u(sch_1):page16_i35@pure_quanta.q_res(chips)',
 P_PATH='@s9s_mb_2u_lib.s9s_mb_2u(sch_1):page16_i35@pure_quanta.q_res(chips)',
 PATH='I35',
 DRAWING='@S9S_MB_2U_LIB.S9S_MB_2U(SCH_1):PAGE16',
 PHYS_PAGE='16',
 XY='(2700,1750)',
 ROT='0',
 VER='2',
 PACK_TYPE='0402LF',
 CDS_LIB='pure_quanta',
 CDS_PART_NAME='Q_RES_0402LF-499,1%,1/16W,CHIPA',
 WATTAGE='1/16W',
 TOLERANCE='1%',
 MATERIAL='CHIP',
 VALUE='499',
 PRIM_FILE='./archive_libs/logical/q_res/chips/chips.prt';

PART_NAME
 R19 'Q_RES_0402LF-499,1%,1/16W,CHIPA':;

SECTION_NUMBER 1
 '@S9S_MB_2U_LIB.S9S_MB_2U(SCH_1):PAGE16_I36@PURE_QUANTA.Q_RES(CHIPS)':
 C_PATH='@s9s_mb_2u_lib.s9s_mb_2u(sch_1):page16_i36@pure_quanta.q_res(chips)',
 P_PATH='@s9s_mb_2u_lib.s9s_mb_2u(sch_1):page16_i36@pure_quanta.q_res(chips)',
 PATH='I36',
 DRAWING='@S9S_MB_2U_LIB.S9S_MB_2U(SCH_1):PAGE16',
 PHYS_PAGE='16',
 XY='(3075,1750)',
 ROT='0',
 VER='2',
 PACK_TYPE='0402LF',
 CDS_LIB='pure_quanta',
 CDS_PART_NAME='Q_RES_0402LF-499,1%,1/16W,CHIPA',
 WATTAGE='1/16W',
 TOLERANCE='1%',
 MATERIAL='CHIP',
 VALUE='499',
 PRIM_FILE='./archive_libs/logical/q_res/chips/chips.prt';

PART_NAME
 R20 'Q_RES_0402LF-0,5%,1/16W,CHIP,CA':;

SECTION_NUMBER 1
 '@S9S_MB_2U_LIB.S9S_MB_2U(SCH_1):PAGE16_I31@PURE_QUANTA.Q_RES(CHIPS)':
 C_PATH='@s9s_mb_2u_lib.s9s_mb_2u(sch_1):page16_i31@pure_quanta.q_res(chips)',
 P_PATH='@s9s_mb_2u_lib.s9s_mb_2u(sch_1):page16_i31@pure_quanta.q_res(chips)',
 PATH='I31',
 DRAWING='@S9S_MB_2U_LIB.S9S_MB_2U(SCH_1):PAGE16',
 PHYS_PAGE='16',
 XY='(4125,1375)',
 ROT='0',
 VER='1',
 PACK_TYPE='0402LF',
 CDS_LIB='pure_quanta',
 CDS_PART_NAME='Q_RES_0402LF-0,5%,1/16W,CHIP,CA',
 WATTAGE='1/16W',
 TOLERANCE='5%',
 MATERIAL='CHIP',
 VALUE='0',
 PRIM_FILE='./archive_libs/logical/q_res/chips/chips.prt';

PART_NAME
 R21 'Q_RES_0402LF-0,5%,1/16W,CHIP,CA':;

SECTION_NUMBER 1
 '@S9S_MB_2U_LIB.S9S_MB_2U(SCH_1):PAGE16_I32@PURE_QUANTA.Q_RES(CHIPS)':
 C_PATH='@s9s_mb_2u_lib.s9s_mb_2u(sch_1):page16_i32@pure_quanta.q_res(chips)',
 P_PATH='@s9s_mb_2u_lib.s9s_mb_2u(sch_1):page16_i32@pure_quanta.q_res(chips)',
 PATH='I32',
 DRAWING='@S9S_MB_2U_LIB.S9S_MB_2U(SCH_1):PAGE16',
 PHYS_PAGE='16',
 XY='(4125,1325)',
 ROT='0',
 VER='1',
 PACK_TYPE='0402LF',
 CDS_LIB='pure_quanta',
 CDS_PART_NAME='Q_RES_0402LF-0,5%,1/16W,CHIP,CA',
 WATTAGE='1/16W',
 TOLERANCE='5%',
 MATERIAL='CHIP',
 VALUE='0',
 PRIM_FILE='./archive_libs/logical/q_res/chips/chips.prt';

PART_NAME
 R22 'Q_RES_0402LF-100,1%,1/16W,CHIPA':;

SECTION_NUMBER 1
 '@S9S_MB_2U_LIB.S9S_MB_2U(SCH_1):PAGE16_I19@PURE_QUANTA.Q_RES(CHIPS)':
 C_PATH='@s9s_mb_2u_lib.s9s_mb_2u(sch_1):page16_i19@pure_quanta.q_res(chips)',
 P_PATH='@s9s_mb_2u_lib.s9s_mb_2u(sch_1):page16_i19@pure_quanta.q_res(chips)',
 PATH='I19',
 DRAWING='@S9S_MB_2U_LIB.S9S_MB_2U(SCH_1):PAGE16',
 PHYS_PAGE='16',
 XY='(3725,2625)',
 ROT='0',
 VER='1',
 PACK_TYPE='0402LF',
 CDS_LIB='pure_quanta',
 CDS_PART_NAME='Q_RES_0402LF-100,1%,1/16W,CHIPA',
 WATTAGE='1/16W',
 TOLERANCE='1%',
 MATERIAL='CHIP',
 VALUE='100',
 PRIM_FILE='./archive_libs/logical/q_res/chips/chips.prt';

PART_NAME
 R23 'Q_RES_0402LF-100,1%,1/16W,CHIPA':;

SECTION_NUMBER 1
 '@S9S_MB_2U_LIB.S9S_MB_2U(SCH_1):PAGE16_I20@PURE_QUANTA.Q_RES(CHIPS)':
 C_PATH='@s9s_mb_2u_lib.s9s_mb_2u(sch_1):page16_i20@pure_quanta.q_res(chips)',
 P_PATH='@s9s_mb_2u_lib.s9s_mb_2u(sch_1):page16_i20@pure_quanta.q_res(chips)',
 PATH='I20',
 DRAWING='@S9S_MB_2U_LIB.S9S_MB_2U(SCH_1):PAGE16',
 PHYS_PAGE='16',
 XY='(3725,2575)',
 ROT='0',
 VER='1',
 PACK_TYPE='0402LF',
 CDS_LIB='pure_quanta',
 CDS_PART_NAME='Q_RES_0402LF-100,1%,1/16W,CHIPA',
 WATTAGE='1/16W',
 TOLERANCE='1%',
 MATERIAL='CHIP',
 VALUE='100',
 PRIM_FILE='./archive_libs/logical/q_res/chips/chips.prt';

PART_NAME
 R24 'Q_RES_0402LF-10,1%,1/16W,CHIP,A':;

SECTION_NUMBER 1
 '@S9S_MB_2U_LIB.S9S_MB_2U(SCH_1):PAGE16_I25@PURE_QUANTA.Q_RES(CHIPS)':
 C_PATH='@s9s_mb_2u_lib.s9s_mb_2u(sch_1):page16_i25@pure_quanta.q_res(chips)',
 P_PATH='@s9s_mb_2u_lib.s9s_mb_2u(sch_1):page16_i25@pure_quanta.q_res(chips)',
 PATH='I25',
 DRAWING='@S9S_MB_2U_LIB.S9S_MB_2U(SCH_1):PAGE16',
 PHYS_PAGE='16',
 XY='(3725,2525)',
 ROT='0',
 VER='1',
 PACK_TYPE='0402LF',
 CDS_LIB='pure_quanta',
 CDS_PART_NAME='Q_RES_0402LF-10,1%,1/16W,CHIP,A',
 WATTAGE='1/16W',
 TOLERANCE='1%',
 MATERIAL='CHIP',
 VALUE='10',
 PRIM_FILE='./archive_libs/logical/q_res/chips/chips.prt';

PART_NAME
 R25 'Q_RES_0402LF-10,1%,1/16W,CHIP,A':;

SECTION_NUMBER 1
 '@S9S_MB_2U_LIB.S9S_MB_2U(SCH_1):PAGE16_I26@PURE_QUANTA.Q_RES(CHIPS)':
 C_PATH='@s9s_mb_2u_lib.s9s_mb_2u(sch_1):page16_i26@pure_quanta.q_res(chips)',
 P_PATH='@s9s_mb_2u_lib.s9s_mb_2u(sch_1):page16_i26@pure_quanta.q_res(chips)',
 PATH='I26',
 DRAWING='@S9S_MB_2U_LIB.S9S_MB_2U(SCH_1):PAGE16',
 PHYS_PAGE='16',
 XY='(3725,2475)',
 ROT='0',
 VER='1',
 PACK_TYPE='0402LF',
 CDS_LIB='pure_quanta',
 CDS_PART_NAME='Q_RES_0402LF-10,1%,1/16W,CHIP,A',
 WATTAGE='1/16W',
 TOLERANCE='1%',
 MATERIAL='CHIP',
 VALUE='10',
 PRIM_FILE='./archive_libs/logical/q_res/chips/chips.prt';

PART_NAME
 R26 'Q_RES_0402LF-10K,1%,1/16W,CHIPA':;

SECTION_NUMBER 1
 '@S9S_MB_2U_LIB.S9S_MB_2U(SCH_1):PAGE82_I196@PURE_QUANTA.Q_RES(CHIPS)':
 C_PATH='@s9s_mb_2u_lib.s9s_mb_2u(sch_1):page82_i196@pure_quanta.q_res(chips)',
 P_PATH='@s9s_mb_2u_lib.s9s_mb_2u(sch_1):page82_i196@pure_quanta.q_res(chips)',
 PATH='I196',
 DRAWING='@S9S_MB_2U_LIB.S9S_MB_2U(SCH_1):PAGE82',
 PHYS_PAGE='82',
 XY='(-2075,150)',
 ROT='0',
 VER='2',
 PACK_TYPE='0402LF',
 CDS_LIB='pure_quanta',
 CDS_PART_NAME='Q_RES_0402LF-10K,1%,1/16W,CHIPA',
 WATTAGE='1/16W',
 TOLERANCE='1%',
 MATERIAL='CHIP',
 VALUE='10K',
 PRIM_FILE='./archive_libs/logical/q_res/chips/chips.prt';

PART_NAME
 R27 'Q_RES_0402LF-15.4K,1%,1/16W,CHA':;

SECTION_NUMBER 1
 '@S9S_MB_2U_LIB.S9S_MB_2U(SCH_1):PAGE83_I10@PURE_QUANTA.Q_RES(CHIPS)':
 C_PATH='@s9s_mb_2u_lib.s9s_mb_2u(sch_1):page83_i10@pure_quanta.q_res(chips)',
 P_PATH='@s9s_mb_2u_lib.s9s_mb_2u(sch_1):page83_i10@pure_quanta.q_res(chips)',
 PATH='I10',
 DRAWING='@S9S_MB_2U_LIB.S9S_MB_2U(SCH_1):PAGE83',
 PHYS_PAGE='83',
 XY='(-1425,50)',
 ROT='0',
 VER='2',
 PACK_TYPE='0402LF',
 CDS_LIB='pure_quanta',
 CDS_PART_NAME='Q_RES_0402LF-15.4K,1%,1/16W,CHA',
 WATTAGE='1/16W',
 TOLERANCE='1%',
 MATERIAL='CHIP',
 VALUE='15.4K',
 PRIM_FILE='./archive_libs/logical/q_res/chips/chips.prt';

PART_NAME
 R28 'Q_RES_0402LF-23.2K,1%,1/16W,CHA':;

SECTION_NUMBER 1
 '@S9S_MB_2U_LIB.S9S_MB_2U(SCH_1):PAGE84_I10@PURE_QUANTA.Q_RES(CHIPS)':
 C_PATH='@s9s_mb_2u_lib.s9s_mb_2u(sch_1):page84_i10@pure_quanta.q_res(chips)',
 P_PATH='@s9s_mb_2u_lib.s9s_mb_2u(sch_1):page84_i10@pure_quanta.q_res(chips)',
 PATH='I10',
 DRAWING='@S9S_MB_2U_LIB.S9S_MB_2U(SCH_1):PAGE84',
 PHYS_PAGE='84',
 XY='(-1525,-250)',
 ROT='0',
 VER='2',
 PACK_TYPE='0402LF',
 CDS_LIB='pure_quanta',
 CDS_PART_NAME='Q_RES_0402LF-23.2K,1%,1/16W,CHA',
 WATTAGE='1/16W',
 TOLERANCE='1%',
 MATERIAL='CHIP',
 VALUE='23.2K',
 PRIM_FILE='./archive_libs/logical/q_res/chips/chips.prt';

PART_NAME
 R29 'Q_RES_0402LF-35.7K,1%,1/16W,CHA':;

SECTION_NUMBER 1
 '@S9S_MB_2U_LIB.S9S_MB_2U(SCH_1):PAGE85_I1@PURE_QUANTA.Q_RES(CHIPS)':
 C_PATH='@s9s_mb_2u_lib.s9s_mb_2u(sch_1):page85_i1@pure_quanta.q_res(chips)',
 P_PATH='@s9s_mb_2u_lib.s9s_mb_2u(sch_1):page85_i1@pure_quanta.q_res(chips)',
 PATH='I1',
 DRAWING='@S9S_MB_2U_LIB.S9S_MB_2U(SCH_1):PAGE85',
 PHYS_PAGE='85',
 XY='(-1950,250)',
 ROT='0',
 VER='2',
 PACK_TYPE='0402LF',
 CDS_LIB='pure_quanta',
 CDS_PART_NAME='Q_RES_0402LF-35.7K,1%,1/16W,CHA',
 WATTAGE='1/16W',
 TOLERANCE='1%',
 MATERIAL='CHIP',
 VALUE='35.7K',
 PRIM_FILE='./archive_libs/logical/q_res/chips/chips.prt';

PART_NAME
 R30 'Q_RES_0402LF-54.9K,1%,1/16W,CHA':;

SECTION_NUMBER 1
 '@S9S_MB_2U_LIB.S9S_MB_2U(SCH_1):PAGE86_I3@PURE_QUANTA.Q_RES(CHIPS)':
 C_PATH='@s9s_mb_2u_lib.s9s_mb_2u(sch_1):page86_i3@pure_quanta.q_res(chips)',
 P_PATH='@s9s_mb_2u_lib.s9s_mb_2u(sch_1):page86_i3@pure_quanta.q_res(chips)',
 PATH='I3',
 DRAWING='@S9S_MB_2U_LIB.S9S_MB_2U(SCH_1):PAGE86',
 PHYS_PAGE='86',
 XY='(-2650,0)',
 ROT='0',
 VER='2',
 PACK_TYPE='0402LF',
 CDS_LIB='pure_quanta',
 CDS_PART_NAME='Q_RES_0402LF-54.9K,1%,1/16W,CHA',
 WATTAGE='1/16W',
 TOLERANCE='1%',
 MATERIAL='CHIP',
 VALUE='54.9K',
 PRIM_FILE='./archive_libs/logical/q_res/chips/chips.prt';

PART_NAME
 R31 'Q_RES_0402LF-84.5K,1%,1/16W,CHA':;

SECTION_NUMBER 1
 '@S9S_MB_2U_LIB.S9S_MB_2U(SCH_1):PAGE87_I45@PURE_QUANTA.Q_RES(CHIPS)':
 C_PATH='@s9s_mb_2u_lib.s9s_mb_2u(sch_1):page87_i45@pure_quanta.q_res(chips)',
 P_PATH='@s9s_mb_2u_lib.s9s_mb_2u(sch_1):page87_i45@pure_quanta.q_res(chips)',
 PATH='I45',
 DRAWING='@S9S_MB_2U_LIB.S9S_MB_2U(SCH_1):PAGE87',
 PHYS_PAGE='87',
 XY='(-1875,50)',
 ROT='0',
 VER='2',
 PACK_TYPE='0402LF',
 CDS_LIB='pure_quanta',
 CDS_PART_NAME='Q_RES_0402LF-84.5K,1%,1/16W,CHA',
 WATTAGE='1/16W',
 TOLERANCE='1%',
 MATERIAL='CHIP',
 VALUE='84.5K',
 PRIM_FILE='./archive_libs/logical/q_res/chips/chips.prt';

PART_NAME
 R32 'Q_RES_0402LF-127K,1%,1/16W,CHIA':;

SECTION_NUMBER 1
 '@S9S_MB_2U_LIB.S9S_MB_2U(SCH_1):PAGE88_I2@PURE_QUANTA.Q_RES(CHIPS)':
 C_PATH='@s9s_mb_2u_lib.s9s_mb_2u(sch_1):page88_i2@pure_quanta.q_res(chips)',
 P_PATH='@s9s_mb_2u_lib.s9s_mb_2u(sch_1):page88_i2@pure_quanta.q_res(chips)',
 PATH='I2',
 DRAWING='@S9S_MB_2U_LIB.S9S_MB_2U(SCH_1):PAGE88',
 PHYS_PAGE='88',
 XY='(-1675,-100)',
 ROT='0',
 VER='2',
 PACK_TYPE='0402LF',
 CDS_LIB='pure_quanta',
 CDS_PART_NAME='Q_RES_0402LF-127K,1%,1/16W,CHIA',
 WATTAGE='1/16W',
 TOLERANCE='1%',
 MATERIAL='CHIP',
 VALUE='127K',
 PRIM_FILE='./archive_libs/logical/q_res/chips/chips.prt';

PART_NAME
 R33 'Q_RES_0402LF-196K,1%,1/16W,CHIA':;

SECTION_NUMBER 1
 '@S9S_MB_2U_LIB.S9S_MB_2U(SCH_1):PAGE89_I2@PURE_QUANTA.Q_RES(CHIPS)':
 C_PATH='@s9s_mb_2u_lib.s9s_mb_2u(sch_1):page89_i2@pure_quanta.q_res(chips)',
 P_PATH='@s9s_mb_2u_lib.s9s_mb_2u(sch_1):page89_i2@pure_quanta.q_res(chips)',
 PATH='I2',
 DRAWING='@S9S_MB_2U_LIB.S9S_MB_2U(SCH_1):PAGE89',
 PHYS_PAGE='89',
 XY='(-2125,50)',
 ROT='0',
 VER='2',
 PACK_TYPE='0402LF',
 CDS_LIB='pure_quanta',
 CDS_PART_NAME='Q_RES_0402LF-196K,1%,1/16W,CHIA',
 WATTAGE='1/16W',
 TOLERANCE='1%',
 MATERIAL='CHIP',
 VALUE='196K',
 PRIM_FILE='./archive_libs/logical/q_res/chips/chips.prt';

PART_NAME
 R34 'Q_RES_0402LF-10K,1%,1/16W,CHIPA':;

SECTION_NUMBER 1
 '@S9S_MB_2U_LIB.S9S_MB_2U(SCH_1):PAGE90_I11@PURE_QUANTA.Q_RES(CHIPS)':
 C_PATH='@s9s_mb_2u_lib.s9s_mb_2u(sch_1):page90_i11@pure_quanta.q_res(chips)',
 P_PATH='@s9s_mb_2u_lib.s9s_mb_2u(sch_1):page90_i11@pure_quanta.q_res(chips)',
 PATH='I11',
 DRAWING='@S9S_MB_2U_LIB.S9S_MB_2U(SCH_1):PAGE90',
 PHYS_PAGE='90',
 XY='(-1425,-125)',
 ROT='0',
 VER='2',
 PACK_TYPE='0402LF',
 CDS_LIB='pure_quanta',
 CDS_PART_NAME='Q_RES_0402LF-10K,1%,1/16W,CHIPA',
 WATTAGE='1/16W',
 TOLERANCE='1%',
 MATERIAL='CHIP',
 VALUE='10K',
 PRIM_FILE='./archive_libs/logical/q_res/chips/chips.prt';

PART_NAME
 R35 'Q_RES_0402LF-15.4K,1%,1/16W,CHA':;

SECTION_NUMBER 1
 '@S9S_MB_2U_LIB.S9S_MB_2U(SCH_1):PAGE91_I2@PURE_QUANTA.Q_RES(CHIPS)':
 C_PATH='@s9s_mb_2u_lib.s9s_mb_2u(sch_1):page91_i2@pure_quanta.q_res(chips)',
 P_PATH='@s9s_mb_2u_lib.s9s_mb_2u(sch_1):page91_i2@pure_quanta.q_res(chips)',
 PATH='I2',
 DRAWING='@S9S_MB_2U_LIB.S9S_MB_2U(SCH_1):PAGE91',
 PHYS_PAGE='91',
 XY='(-1650,-25)',
 ROT='0',
 VER='2',
 PACK_TYPE='0402LF',
 CDS_LIB='pure_quanta',
 CDS_PART_NAME='Q_RES_0402LF-15.4K,1%,1/16W,CHA',
 WATTAGE='1/16W',
 TOLERANCE='1%',
 MATERIAL='CHIP',
 VALUE='15.4K',
 PRIM_FILE='./archive_libs/logical/q_res/chips/chips.prt';

PART_NAME
 R36 'Q_RES_0402LF-23.2K,1%,1/16W,CHA':;

SECTION_NUMBER 1
 '@S9S_MB_2U_LIB.S9S_MB_2U(SCH_1):PAGE92_I2@PURE_QUANTA.Q_RES(CHIPS)':
 C_PATH='@s9s_mb_2u_lib.s9s_mb_2u(sch_1):page92_i2@pure_quanta.q_res(chips)',
 P_PATH='@s9s_mb_2u_lib.s9s_mb_2u(sch_1):page92_i2@pure_quanta.q_res(chips)',
 PATH='I2',
 DRAWING='@S9S_MB_2U_LIB.S9S_MB_2U(SCH_1):PAGE92',
 PHYS_PAGE='92',
 XY='(-2525,250)',
 ROT='0',
 VER='2',
 PACK_TYPE='0402LF',
 CDS_LIB='pure_quanta',
 CDS_PART_NAME='Q_RES_0402LF-23.2K,1%,1/16W,CHA',
 WATTAGE='1/16W',
 TOLERANCE='1%',
 MATERIAL='CHIP',
 VALUE='23.2K',
 PRIM_FILE='./archive_libs/logical/q_res/chips/chips.prt';

PART_NAME
 R37 'Q_RES_0402LF-35.7K,1%,1/16W,CHA':;

SECTION_NUMBER 1
 '@S9S_MB_2U_LIB.S9S_MB_2U(SCH_1):PAGE93_I2@PURE_QUANTA.Q_RES(CHIPS)':
 C_PATH='@s9s_mb_2u_lib.s9s_mb_2u(sch_1):page93_i2@pure_quanta.q_res(chips)',
 P_PATH='@s9s_mb_2u_lib.s9s_mb_2u(sch_1):page93_i2@pure_quanta.q_res(chips)',
 PATH='I2',
 DRAWING='@S9S_MB_2U_LIB.S9S_MB_2U(SCH_1):PAGE93',
 PHYS_PAGE='93',
 XY='(-1850,275)',
 ROT='0',
 VER='2',
 PACK_TYPE='0402LF',
 CDS_LIB='pure_quanta',
 CDS_PART_NAME='Q_RES_0402LF-35.7K,1%,1/16W,CHA',
 WATTAGE='1/16W',
 TOLERANCE='1%',
 MATERIAL='CHIP',
 VALUE='35.7K',
 PRIM_FILE='./archive_libs/logical/q_res/chips/chips.prt';

PART_NAME
 R38 'Q_RES_0402LF-54.9K,1%,1/16W,CHA':;

SECTION_NUMBER 1
 '@S9S_MB_2U_LIB.S9S_MB_2U(SCH_1):PAGE94_I10@PURE_QUANTA.Q_RES(CHIPS)':
 C_PATH='@s9s_mb_2u_lib.s9s_mb_2u(sch_1):page94_i10@pure_quanta.q_res(chips)',
 P_PATH='@s9s_mb_2u_lib.s9s_mb_2u(sch_1):page94_i10@pure_quanta.q_res(chips)',
 PATH='I10',
 DRAWING='@S9S_MB_2U_LIB.S9S_MB_2U(SCH_1):PAGE94',
 PHYS_PAGE='94',
 XY='(-1950,200)',
 ROT='0',
 VER='2',
 PACK_TYPE='0402LF',
 CDS_LIB='pure_quanta',
 CDS_PART_NAME='Q_RES_0402LF-54.9K,1%,1/16W,CHA',
 WATTAGE='1/16W',
 TOLERANCE='1%',
 MATERIAL='CHIP',
 VALUE='54.9K',
 PRIM_FILE='./archive_libs/logical/q_res/chips/chips.prt';

PART_NAME
 R39 'Q_RES_0402LF-84.5K,1%,1/16W,CHA':;

SECTION_NUMBER 1
 '@S9S_MB_2U_LIB.S9S_MB_2U(SCH_1):PAGE95_I46@PURE_QUANTA.Q_RES(CHIPS)':
 C_PATH='@s9s_mb_2u_lib.s9s_mb_2u(sch_1):page95_i46@pure_quanta.q_res(chips)',
 P_PATH='@s9s_mb_2u_lib.s9s_mb_2u(sch_1):page95_i46@pure_quanta.q_res(chips)',
 PATH='I46',
 DRAWING='@S9S_MB_2U_LIB.S9S_MB_2U(SCH_1):PAGE95',
 PHYS_PAGE='95',
 XY='(-825,-825)',
 ROT='0',
 VER='2',
 PACK_TYPE='0402LF',
 CDS_LIB='pure_quanta',
 CDS_PART_NAME='Q_RES_0402LF-84.5K,1%,1/16W,CHA',
 WATTAGE='1/16W',
 TOLERANCE='1%',
 MATERIAL='CHIP',
 VALUE='84.5K',
 PRIM_FILE='./archive_libs/logical/q_res/chips/chips.prt';

PART_NAME
 R40 'Q_RES_0402LF-127K,1%,1/16W,CHIA':;

SECTION_NUMBER 1
 '@S9S_MB_2U_LIB.S9S_MB_2U(SCH_1):PAGE96_I47@PURE_QUANTA.Q_RES(CHIPS)':
 C_PATH='@s9s_mb_2u_lib.s9s_mb_2u(sch_1):page96_i47@pure_quanta.q_res(chips)',
 P_PATH='@s9s_mb_2u_lib.s9s_mb_2u(sch_1):page96_i47@pure_quanta.q_res(chips)',
 PATH='I47',
 DRAWING='@S9S_MB_2U_LIB.S9S_MB_2U(SCH_1):PAGE96',
 PHYS_PAGE='96',
 XY='(-2275,-175)',
 ROT='0',
 VER='2',
 PACK_TYPE='0402LF',
 CDS_LIB='pure_quanta',
 CDS_PART_NAME='Q_RES_0402LF-127K,1%,1/16W,CHIA',
 WATTAGE='1/16W',
 TOLERANCE='1%',
 MATERIAL='CHIP',
 VALUE='127K',
 PRIM_FILE='./archive_libs/logical/q_res/chips/chips.prt';

PART_NAME
 R41 'Q_RES_0402LF-196K,1%,1/16W,CHIA':;

SECTION_NUMBER 1
 '@S9S_MB_2U_LIB.S9S_MB_2U(SCH_1):PAGE97_I5@PURE_QUANTA.Q_RES(CHIPS)':
 C_PATH='@s9s_mb_2u_lib.s9s_mb_2u(sch_1):page97_i5@pure_quanta.q_res(chips)',
 P_PATH='@s9s_mb_2u_lib.s9s_mb_2u(sch_1):page97_i5@pure_quanta.q_res(chips)',
 PATH='I5',
 DRAWING='@S9S_MB_2U_LIB.S9S_MB_2U(SCH_1):PAGE97',
 PHYS_PAGE='97',
 XY='(-1775,25)',
 ROT='0',
 VER='2',
 PACK_TYPE='0402LF',
 CDS_LIB='pure_quanta',
 CDS_PART_NAME='Q_RES_0402LF-196K,1%,1/16W,CHIA',
 WATTAGE='1/16W',
 TOLERANCE='1%',
 MATERIAL='CHIP',
 VALUE='196K',
 PRIM_FILE='./archive_libs/logical/q_res/chips/chips.prt';

PART_NAME
 R42 'Q_RES_0402LF-10K,1%,1/16W,CHIPA':;

SECTION_NUMBER 1
 '@S9S_MB_2U_LIB.S9S_MB_2U(SCH_1):PAGE98_I11@PURE_QUANTA.Q_RES(CHIPS)':
 C_PATH='@s9s_mb_2u_lib.s9s_mb_2u(sch_1):page98_i11@pure_quanta.q_res(chips)',
 P_PATH='@s9s_mb_2u_lib.s9s_mb_2u(sch_1):page98_i11@pure_quanta.q_res(chips)',
 PATH='I11',
 DRAWING='@S9S_MB_2U_LIB.S9S_MB_2U(SCH_1):PAGE98',
 PHYS_PAGE='98',
 XY='(-1400,-75)',
 ROT='0',
 VER='2',
 PACK_TYPE='0402LF',
 CDS_LIB='pure_quanta',
 CDS_PART_NAME='Q_RES_0402LF-10K,1%,1/16W,CHIPA',
 WATTAGE='1/16W',
 TOLERANCE='1%',
 MATERIAL='CHIP',
 VALUE='10K',
 PRIM_FILE='./archive_libs/logical/q_res/chips/chips.prt';

PART_NAME
 R43 'Q_RES_0402LF-15.4K,1%,1/16W,CHA':;

SECTION_NUMBER 1
 '@S9S_MB_2U_LIB.S9S_MB_2U(SCH_1):PAGE99_I2@PURE_QUANTA.Q_RES(CHIPS)':
 C_PATH='@s9s_mb_2u_lib.s9s_mb_2u(sch_1):page99_i2@pure_quanta.q_res(chips)',
 P_PATH='@s9s_mb_2u_lib.s9s_mb_2u(sch_1):page99_i2@pure_quanta.q_res(chips)',
 PATH='I2',
 DRAWING='@S9S_MB_2U_LIB.S9S_MB_2U(SCH_1):PAGE99',
 PHYS_PAGE='99',
 XY='(-1650,-350)',
 ROT='0',
 VER='2',
 PACK_TYPE='0402LF',
 CDS_LIB='pure_quanta',
 CDS_PART_NAME='Q_RES_0402LF-15.4K,1%,1/16W,CHA',
 WATTAGE='1/16W',
 TOLERANCE='1%',
 MATERIAL='CHIP',
 VALUE='15.4K',
 PRIM_FILE='./archive_libs/logical/q_res/chips/chips.prt';

PART_NAME
 R44 'Q_RES_0402LF-23.2K,1%,1/16W,CHA':;

SECTION_NUMBER 1
 '@S9S_MB_2U_LIB.S9S_MB_2U(SCH_1):PAGE100_I3@PURE_QUANTA.Q_RES(CHIPS)':
 C_PATH='@s9s_mb_2u_lib.s9s_mb_2u(sch_1):page100_i3@pure_quanta.q_res(chips)',
 P_PATH='@s9s_mb_2u_lib.s9s_mb_2u(sch_1):page100_i3@pure_quanta.q_res(chips)',
 PATH='I3',
 DRAWING='@S9S_MB_2U_LIB.S9S_MB_2U(SCH_1):PAGE100',
 PHYS_PAGE='100',
 XY='(-2000,250)',
 ROT='0',
 VER='2',
 PACK_TYPE='0402LF',
 CDS_LIB='pure_quanta',
 CDS_PART_NAME='Q_RES_0402LF-23.2K,1%,1/16W,CHA',
 WATTAGE='1/16W',
 TOLERANCE='1%',
 MATERIAL='CHIP',
 VALUE='23.2K',
 PRIM_FILE='./archive_libs/logical/q_res/chips/chips.prt';

PART_NAME
 R45 'Q_RES_0402LF-35.7K,1%,1/16W,CHA':;

SECTION_NUMBER 1
 '@S9S_MB_2U_LIB.S9S_MB_2U(SCH_1):PAGE101_I46@PURE_QUANTA.Q_RES(CHIPS)':
 C_PATH='@s9s_mb_2u_lib.s9s_mb_2u(sch_1):page101_i46@pure_quanta.q_res(chips)',
 P_PATH='@s9s_mb_2u_lib.s9s_mb_2u(sch_1):page101_i46@pure_quanta.q_res(chips)',
 PATH='I46',
 DRAWING='@S9S_MB_2U_LIB.S9S_MB_2U(SCH_1):PAGE101',
 PHYS_PAGE='101',
 XY='(-4050,500)',
 ROT='0',
 VER='2',
 PACK_TYPE='0402LF',
 CDS_LIB='pure_quanta',
 CDS_PART_NAME='Q_RES_0402LF-35.7K,1%,1/16W,CHA',
 WATTAGE='1/16W',
 TOLERANCE='1%',
 MATERIAL='CHIP',
 VALUE='35.7K',
 PRIM_FILE='./archive_libs/logical/q_res/chips/chips.prt';

PART_NAME
 R46 'Q_RES_0402LF-54.9K,1%,1/16W,CHA':;

SECTION_NUMBER 1
 '@S9S_MB_2U_LIB.S9S_MB_2U(SCH_1):PAGE102_I2@PURE_QUANTA.Q_RES(CHIPS)':
 C_PATH='@s9s_mb_2u_lib.s9s_mb_2u(sch_1):page102_i2@pure_quanta.q_res(chips)',
 P_PATH='@s9s_mb_2u_lib.s9s_mb_2u(sch_1):page102_i2@pure_quanta.q_res(chips)',
 PATH='I2',
 DRAWING='@S9S_MB_2U_LIB.S9S_MB_2U(SCH_1):PAGE102',
 PHYS_PAGE='102',
 XY='(-2600,25)',
 ROT='0',
 VER='2',
 PACK_TYPE='0402LF',
 CDS_LIB='pure_quanta',
 CDS_PART_NAME='Q_RES_0402LF-54.9K,1%,1/16W,CHA',
 WATTAGE='1/16W',
 TOLERANCE='1%',
 MATERIAL='CHIP',
 VALUE='54.9K',
 PRIM_FILE='./archive_libs/logical/q_res/chips/chips.prt';

PART_NAME
 R47 'Q_RES_0402LF-84.5K,1%,1/16W,CHA':;

SECTION_NUMBER 1
 '@S9S_MB_2U_LIB.S9S_MB_2U(SCH_1):PAGE103_I2@PURE_QUANTA.Q_RES(CHIPS)':
 C_PATH='@s9s_mb_2u_lib.s9s_mb_2u(sch_1):page103_i2@pure_quanta.q_res(chips)',
 P_PATH='@s9s_mb_2u_lib.s9s_mb_2u(sch_1):page103_i2@pure_quanta.q_res(chips)',
 PATH='I2',
 DRAWING='@S9S_MB_2U_LIB.S9S_MB_2U(SCH_1):PAGE103',
 PHYS_PAGE='103',
 XY='(-2675,-250)',
 ROT='0',
 VER='2',
 PACK_TYPE='0402LF',
 CDS_LIB='pure_quanta',
 CDS_PART_NAME='Q_RES_0402LF-84.5K,1%,1/16W,CHA',
 WATTAGE='1/16W',
 TOLERANCE='1%',
 MATERIAL='CHIP',
 VALUE='84.5K',
 PRIM_FILE='./archive_libs/logical/q_res/chips/chips.prt';

PART_NAME
 R48 'Q_RES_0402LF-127K,1%,1/16W,CHIA':;

SECTION_NUMBER 1
 '@S9S_MB_2U_LIB.S9S_MB_2U(SCH_1):PAGE104_I2@PURE_QUANTA.Q_RES(CHIPS)':
 C_PATH='@s9s_mb_2u_lib.s9s_mb_2u(sch_1):page104_i2@pure_quanta.q_res(chips)',
 P_PATH='@s9s_mb_2u_lib.s9s_mb_2u(sch_1):page104_i2@pure_quanta.q_res(chips)',
 PATH='I2',
 DRAWING='@S9S_MB_2U_LIB.S9S_MB_2U(SCH_1):PAGE104',
 PHYS_PAGE='104',
 XY='(-3100,-25)',
 ROT='0',
 VER='2',
 PACK_TYPE='0402LF',
 CDS_LIB='pure_quanta',
 CDS_PART_NAME='Q_RES_0402LF-127K,1%,1/16W,CHIA',
 WATTAGE='1/16W',
 TOLERANCE='1%',
 MATERIAL='CHIP',
 VALUE='127K',
 PRIM_FILE='./archive_libs/logical/q_res/chips/chips.prt';

PART_NAME
 R49 'Q_RES_0402LF-499,1%,1/16W,CHIPA':;

SECTION_NUMBER 1
 '@S9S_MB_2U_LIB.S9S_MB_2U(SCH_1):PAGE47_I34@PURE_QUANTA.Q_RES(CHIPS)':
 C_PATH='@s9s_mb_2u_lib.s9s_mb_2u(sch_1):page47_i34@pure_quanta.q_res(chips)',
 P_PATH='@s9s_mb_2u_lib.s9s_mb_2u(sch_1):page47_i34@pure_quanta.q_res(chips)',
 PATH='I34',
 DRAWING='@S9S_MB_2U_LIB.S9S_MB_2U(SCH_1):PAGE47',
 PHYS_PAGE='47',
 XY='(3675,4975)',
 ROT='0',
 VER='2',
 PACK_TYPE='0402LF',
 CDS_LIB='pure_quanta',
 CDS_PART_NAME='Q_RES_0402LF-499,1%,1/16W,CHIPA',
 WATTAGE='1/16W',
 TOLERANCE='1%',
 MATERIAL='CHIP',
 VALUE='499',
 PRIM_FILE='./archive_libs/logical/q_res/chips/chips.prt';

PART_NAME
 R50 'Q_RES_0402LF-499,1%,1/16W,CHIPA':;

SECTION_NUMBER 1
 '@S9S_MB_2U_LIB.S9S_MB_2U(SCH_1):PAGE47_I35@PURE_QUANTA.Q_RES(CHIPS)':
 C_PATH='@s9s_mb_2u_lib.s9s_mb_2u(sch_1):page47_i35@pure_quanta.q_res(chips)',
 P_PATH='@s9s_mb_2u_lib.s9s_mb_2u(sch_1):page47_i35@pure_quanta.q_res(chips)',
 PATH='I35',
 DRAWING='@S9S_MB_2U_LIB.S9S_MB_2U(SCH_1):PAGE47',
 PHYS_PAGE='47',
 XY='(3925,4975)',
 ROT='0',
 VER='2',
 PACK_TYPE='0402LF',
 CDS_LIB='pure_quanta',
 CDS_PART_NAME='Q_RES_0402LF-499,1%,1/16W,CHIPA',
 WATTAGE='1/16W',
 TOLERANCE='1%',
 MATERIAL='CHIP',
 VALUE='499',
 PRIM_FILE='./archive_libs/logical/q_res/chips/chips.prt';

PART_NAME
 R51 'Q_RES_0402LF-100,1%,1/16W,CHIPA':;

SECTION_NUMBER 1
 '@S9S_MB_2U_LIB.S9S_MB_2U(SCH_1):PAGE47_I24@PURE_QUANTA.Q_RES(CHIPS)':
 C_PATH='@s9s_mb_2u_lib.s9s_mb_2u(sch_1):page47_i24@pure_quanta.q_res(chips)',
 P_PATH='@s9s_mb_2u_lib.s9s_mb_2u(sch_1):page47_i24@pure_quanta.q_res(chips)',
 PATH='I24',
 DRAWING='@S9S_MB_2U_LIB.S9S_MB_2U(SCH_1):PAGE47',
 PHYS_PAGE='47',
 XY='(2250,4625)',
 ROT='0',
 VER='1',
 PACK_TYPE='0402LF',
 CDS_LIB='pure_quanta',
 CDS_PART_NAME='Q_RES_0402LF-100,1%,1/16W,CHIPA',
 WATTAGE='1/16W',
 TOLERANCE='1%',
 MATERIAL='CHIP',
 VALUE='100',
 PRIM_FILE='./archive_libs/logical/q_res/chips/chips.prt';

PART_NAME
 R52 'Q_RES_0402LF-100,1%,1/16W,CHIPA':;

SECTION_NUMBER 1
 '@S9S_MB_2U_LIB.S9S_MB_2U(SCH_1):PAGE47_I25@PURE_QUANTA.Q_RES(CHIPS)':
 C_PATH='@s9s_mb_2u_lib.s9s_mb_2u(sch_1):page47_i25@pure_quanta.q_res(chips)',
 P_PATH='@s9s_mb_2u_lib.s9s_mb_2u(sch_1):page47_i25@pure_quanta.q_res(chips)',
 PATH='I25',
 DRAWING='@S9S_MB_2U_LIB.S9S_MB_2U(SCH_1):PAGE47',
 PHYS_PAGE='47',
 XY='(2250,4575)',
 ROT='0',
 VER='1',
 PACK_TYPE='0402LF',
 CDS_LIB='pure_quanta',
 CDS_PART_NAME='Q_RES_0402LF-100,1%,1/16W,CHIPA',
 WATTAGE='1/16W',
 TOLERANCE='1%',
 MATERIAL='CHIP',
 VALUE='100',
 PRIM_FILE='./archive_libs/logical/q_res/chips/chips.prt';

PART_NAME
 R53 'Q_RES_0402LF-10,1%,1/16W,CHIP,A':;

SECTION_NUMBER 1
 '@S9S_MB_2U_LIB.S9S_MB_2U(SCH_1):PAGE47_I23@PURE_QUANTA.Q_RES(CHIPS)':
 C_PATH='@s9s_mb_2u_lib.s9s_mb_2u(sch_1):page47_i23@pure_quanta.q_res(chips)',
 P_PATH='@s9s_mb_2u_lib.s9s_mb_2u(sch_1):page47_i23@pure_quanta.q_res(chips)',
 PATH='I23',
 DRAWING='@S9S_MB_2U_LIB.S9S_MB_2U(SCH_1):PAGE47',
 PHYS_PAGE='47',
 XY='(2250,4525)',
 ROT='0',
 VER='1',
 PACK_TYPE='0402LF',
 CDS_LIB='pure_quanta',
 CDS_PART_NAME='Q_RES_0402LF-10,1%,1/16W,CHIP,A',
 WATTAGE='1/16W',
 TOLERANCE='1%',
 MATERIAL='CHIP',
 VALUE='10',
 PRIM_FILE='./archive_libs/logical/q_res/chips/chips.prt';

PART_NAME
 R54 'Q_RES_0402LF-10,1%,1/16W,CHIP,A':;

SECTION_NUMBER 1
 '@S9S_MB_2U_LIB.S9S_MB_2U(SCH_1):PAGE47_I22@PURE_QUANTA.Q_RES(CHIPS)':
 C_PATH='@s9s_mb_2u_lib.s9s_mb_2u(sch_1):page47_i22@pure_quanta.q_res(chips)',
 P_PATH='@s9s_mb_2u_lib.s9s_mb_2u(sch_1):page47_i22@pure_quanta.q_res(chips)',
 PATH='I22',
 DRAWING='@S9S_MB_2U_LIB.S9S_MB_2U(SCH_1):PAGE47',
 PHYS_PAGE='47',
 XY='(2250,4475)',
 ROT='0',
 VER='1',
 PACK_TYPE='0402LF',
 CDS_LIB='pure_quanta',
 CDS_PART_NAME='Q_RES_0402LF-10,1%,1/16W,CHIP,A',
 WATTAGE='1/16W',
 TOLERANCE='1%',
 MATERIAL='CHIP',
 VALUE='10',
 PRIM_FILE='./archive_libs/logical/q_res/chips/chips.prt';

PART_NAME
 R55 'Q_RES_0402LF-0,5%,1/16W,CHIP,CA':;

SECTION_NUMBER 1
 '@S9S_MB_2U_LIB.S9S_MB_2U(SCH_1):PAGE45_I54@PURE_QUANTA.Q_RES(CHIPS)':
 C_PATH='@s9s_mb_2u_lib.s9s_mb_2u(sch_1):page45_i54@pure_quanta.q_res(chips)',
 P_PATH='@s9s_mb_2u_lib.s9s_mb_2u(sch_1):page45_i54@pure_quanta.q_res(chips)',
 PATH='I54',
 DRAWING='@S9S_MB_2U_LIB.S9S_MB_2U(SCH_1):PAGE45',
 PHYS_PAGE='45',
 XY='(-3400,-675)',
 ROT='0',
 VER='1',
 PACK_TYPE='0402LF',
 CDS_LIB='pure_quanta',
 CDS_PART_NAME='Q_RES_0402LF-0,5%,1/16W,CHIP,CA',
 WATTAGE='1/16W',
 TOLERANCE='5%',
 MATERIAL='CHIP',
 VALUE='0',
 PRIM_FILE='./archive_libs/logical/q_res/chips/chips.prt';

PART_NAME
 R56 'Q_RES_0402LF-0,5%,1/16W,CHIP,CA':;

SECTION_NUMBER 1
 '@S9S_MB_2U_LIB.S9S_MB_2U(SCH_1):PAGE45_I55@PURE_QUANTA.Q_RES(CHIPS)':
 C_PATH='@s9s_mb_2u_lib.s9s_mb_2u(sch_1):page45_i55@pure_quanta.q_res(chips)',
 P_PATH='@s9s_mb_2u_lib.s9s_mb_2u(sch_1):page45_i55@pure_quanta.q_res(chips)',
 PATH='I55',
 DRAWING='@S9S_MB_2U_LIB.S9S_MB_2U(SCH_1):PAGE45',
 PHYS_PAGE='45',
 XY='(-3400,-725)',
 ROT='0',
 VER='1',
 PACK_TYPE='0402LF',
 CDS_LIB='pure_quanta',
 CDS_PART_NAME='Q_RES_0402LF-0,5%,1/16W,CHIP,CA',
 WATTAGE='1/16W',
 TOLERANCE='5%',
 MATERIAL='CHIP',
 VALUE='0',
 PRIM_FILE='./archive_libs/logical/q_res/chips/chips.prt';

PART_NAME
 R57 'Q_RES_0402LF-200,1%,1/16W,CHIPA':;

SECTION_NUMBER 1
 '@S9S_MB_2U_LIB.S9S_MB_2U(SCH_1):PAGE45_I56@PURE_QUANTA.Q_RES(CHIPS)':
 C_PATH='@s9s_mb_2u_lib.s9s_mb_2u(sch_1):page45_i56@pure_quanta.q_res(chips)',
 P_PATH='@s9s_mb_2u_lib.s9s_mb_2u(sch_1):page45_i56@pure_quanta.q_res(chips)',
 PATH='I56',
 DRAWING='@S9S_MB_2U_LIB.S9S_MB_2U(SCH_1):PAGE45',
 PHYS_PAGE='45',
 XY='(-3400,-775)',
 ROT='0',
 VER='1',
 PACK_TYPE='0402LF',
 CDS_LIB='pure_quanta',
 CDS_PART_NAME='Q_RES_0402LF-200,1%,1/16W,CHIPA',
 WATTAGE='1/16W',
 TOLERANCE='1%',
 MATERIAL='CHIP',
 VALUE='200',
 PRIM_FILE='./archive_libs/logical/q_res/chips/chips.prt';

PART_NAME
 R58 'Q_RES_0402LF-0,5%,1/16W,CHIP,CA':;

SECTION_NUMBER 1
 '@S9S_MB_2U_LIB.S9S_MB_2U(SCH_1):PAGE45_I51@PURE_QUANTA.Q_RES(CHIPS)':
 C_PATH='@s9s_mb_2u_lib.s9s_mb_2u(sch_1):page45_i51@pure_quanta.q_res(chips)',
 P_PATH='@s9s_mb_2u_lib.s9s_mb_2u(sch_1):page45_i51@pure_quanta.q_res(chips)',
 PATH='I51',
 DRAWING='@S9S_MB_2U_LIB.S9S_MB_2U(SCH_1):PAGE45',
 PHYS_PAGE='45',
 XY='(-3400,-875)',
 ROT='0',
 VER='1',
 PACK_TYPE='0402LF',
 CDS_LIB='pure_quanta',
 CDS_PART_NAME='Q_RES_0402LF-0,5%,1/16W,CHIP,CA',
 WATTAGE='1/16W',
 TOLERANCE='5%',
 MATERIAL='CHIP',
 VALUE='0',
 PRIM_FILE='./archive_libs/logical/q_res/chips/chips.prt';

PART_NAME
 R59 'Q_RES_0402LF-0,5%,1/16W,CHIP,CA':;

SECTION_NUMBER 1
 '@S9S_MB_2U_LIB.S9S_MB_2U(SCH_1):PAGE45_I52@PURE_QUANTA.Q_RES(CHIPS)':
 C_PATH='@s9s_mb_2u_lib.s9s_mb_2u(sch_1):page45_i52@pure_quanta.q_res(chips)',
 P_PATH='@s9s_mb_2u_lib.s9s_mb_2u(sch_1):page45_i52@pure_quanta.q_res(chips)',
 PATH='I52',
 DRAWING='@S9S_MB_2U_LIB.S9S_MB_2U(SCH_1):PAGE45',
 PHYS_PAGE='45',
 XY='(-3400,-925)',
 ROT='0',
 VER='1',
 PACK_TYPE='0402LF',
 CDS_LIB='pure_quanta',
 CDS_PART_NAME='Q_RES_0402LF-0,5%,1/16W,CHIP,CA',
 WATTAGE='1/16W',
 TOLERANCE='5%',
 MATERIAL='CHIP',
 VALUE='0',
 PRIM_FILE='./archive_libs/logical/q_res/chips/chips.prt';

PART_NAME
 R60 'Q_RES_0402LF-200,1%,1/16W,CHIPA':;

SECTION_NUMBER 1
 '@S9S_MB_2U_LIB.S9S_MB_2U(SCH_1):PAGE45_I53@PURE_QUANTA.Q_RES(CHIPS)':
 C_PATH='@s9s_mb_2u_lib.s9s_mb_2u(sch_1):page45_i53@pure_quanta.q_res(chips)',
 P_PATH='@s9s_mb_2u_lib.s9s_mb_2u(sch_1):page45_i53@pure_quanta.q_res(chips)',
 PATH='I53',
 DRAWING='@S9S_MB_2U_LIB.S9S_MB_2U(SCH_1):PAGE45',
 PHYS_PAGE='45',
 XY='(-3400,-975)',
 ROT='0',
 VER='1',
 PACK_TYPE='0402LF',
 CDS_LIB='pure_quanta',
 CDS_PART_NAME='Q_RES_0402LF-200,1%,1/16W,CHIPA',
 WATTAGE='1/16W',
 TOLERANCE='1%',
 MATERIAL='CHIP',
 VALUE='200',
 PRIM_FILE='./archive_libs/logical/q_res/chips/chips.prt';

PART_NAME
 R61 'Q_RES_0402LF-10,1%,1/16W,CHIP,A':;

SECTION_NUMBER 1
 '@S9S_MB_2U_LIB.S9S_MB_2U(SCH_1):PAGE44_I16@PURE_QUANTA.Q_RES(CHIPS)':
 C_PATH='@s9s_mb_2u_lib.s9s_mb_2u(sch_1):page44_i16@pure_quanta.q_res(chips)',
 P_PATH='@s9s_mb_2u_lib.s9s_mb_2u(sch_1):page44_i16@pure_quanta.q_res(chips)',
 PATH='I16',
 DRAWING='@S9S_MB_2U_LIB.S9S_MB_2U(SCH_1):PAGE44',
 PHYS_PAGE='44',
 XY='(-7325,6525)',
 ROT='0',
 VER='1',
 PACK_TYPE='0402LF',
 CDS_LIB='pure_quanta',
 CDS_PART_NAME='Q_RES_0402LF-10,1%,1/16W,CHIP,A',
 WATTAGE='1/16W',
 TOLERANCE='1%',
 MATERIAL='CHIP',
 VALUE='10',
 PRIM_FILE='./archive_libs/logical/q_res/chips/chips.prt';

PART_NAME
 R62 'Q_RES_0402LF-100,1%,1/16W,CHIPA':;

SECTION_NUMBER 1
 '@S9S_MB_2U_LIB.S9S_MB_2U(SCH_1):PAGE44_I11@PURE_QUANTA.Q_RES(CHIPS)':
 C_PATH='@s9s_mb_2u_lib.s9s_mb_2u(sch_1):page44_i11@pure_quanta.q_res(chips)',
 P_PATH='@s9s_mb_2u_lib.s9s_mb_2u(sch_1):page44_i11@pure_quanta.q_res(chips)',
 PATH='I11',
 DRAWING='@S9S_MB_2U_LIB.S9S_MB_2U(SCH_1):PAGE44',
 PHYS_PAGE='44',
 XY='(-7325,6475)',
 ROT='0',
 VER='1',
 PACK_TYPE='0402LF',
 CDS_LIB='pure_quanta',
 CDS_PART_NAME='Q_RES_0402LF-100,1%,1/16W,CHIPA',
 WATTAGE='1/16W',
 TOLERANCE='1%',
 MATERIAL='CHIP',
 VALUE='100',
 PRIM_FILE='./archive_libs/logical/q_res/chips/chips.prt';

PART_NAME
 R63 'Q_RES_0402LF-33.2,1%,1/16W,CHIA':;

SECTION_NUMBER 1
 '@S9S_MB_2U_LIB.S9S_MB_2U(SCH_1):PAGE44_I10@PURE_QUANTA.Q_RES(CHIPS)':
 C_PATH='@s9s_mb_2u_lib.s9s_mb_2u(sch_1):page44_i10@pure_quanta.q_res(chips)',
 P_PATH='@s9s_mb_2u_lib.s9s_mb_2u(sch_1):page44_i10@pure_quanta.q_res(chips)',
 PATH='I10',
 DRAWING='@S9S_MB_2U_LIB.S9S_MB_2U(SCH_1):PAGE44',
 PHYS_PAGE='44',
 XY='(-7325,6375)',
 ROT='0',
 VER='1',
 PACK_TYPE='0402LF',
 CDS_LIB='pure_quanta',
 CDS_PART_NAME='Q_RES_0402LF-33.2,1%,1/16W,CHIA',
 WATTAGE='1/16W',
 TOLERANCE='1%',
 MATERIAL='CHIP',
 VALUE='33.2',
 PRIM_FILE='./archive_libs/logical/q_res/chips/chips.prt';

PART_NAME
 R64 'Q_RES_0402LF-200,1%,1/16W,CHIPA':;

SECTION_NUMBER 1
 '@S9S_MB_2U_LIB.S9S_MB_2U(SCH_1):PAGE44_I9@PURE_QUANTA.Q_RES(CHIPS)':
 C_PATH='@s9s_mb_2u_lib.s9s_mb_2u(sch_1):page44_i9@pure_quanta.q_res(chips)',
 P_PATH='@s9s_mb_2u_lib.s9s_mb_2u(sch_1):page44_i9@pure_quanta.q_res(chips)',
 PATH='I9',
 DRAWING='@S9S_MB_2U_LIB.S9S_MB_2U(SCH_1):PAGE44',
 PHYS_PAGE='44',
 XY='(-7325,6275)',
 ROT='0',
 VER='1',
 PACK_TYPE='0402LF',
 CDS_LIB='pure_quanta',
 CDS_PART_NAME='Q_RES_0402LF-200,1%,1/16W,CHIPA',
 WATTAGE='1/16W',
 TOLERANCE='1%',
 MATERIAL='CHIP',
 VALUE='200',
 PRIM_FILE='./archive_libs/logical/q_res/chips/chips.prt';

PART_NAME
 R65 'Q_RES_0402LF-100,1%,1/16W,CHIPA':;

SECTION_NUMBER 1
 '@S9S_MB_2U_LIB.S9S_MB_2U(SCH_1):PAGE44_I8@PURE_QUANTA.Q_RES(CHIPS)':
 C_PATH='@s9s_mb_2u_lib.s9s_mb_2u(sch_1):page44_i8@pure_quanta.q_res(chips)',
 P_PATH='@s9s_mb_2u_lib.s9s_mb_2u(sch_1):page44_i8@pure_quanta.q_res(chips)',
 PATH='I8',
 DRAWING='@S9S_MB_2U_LIB.S9S_MB_2U(SCH_1):PAGE44',
 PHYS_PAGE='44',
 XY='(-7325,6225)',
 ROT='0',
 VER='1',
 PACK_TYPE='0402LF',
 CDS_LIB='pure_quanta',
 CDS_PART_NAME='Q_RES_0402LF-100,1%,1/16W,CHIPA',
 WATTAGE='1/16W',
 TOLERANCE='1%',
 MATERIAL='CHIP',
 VALUE='100',
 PRIM_FILE='./archive_libs/logical/q_res/chips/chips.prt';

PART_NAME
 R66 'Q_RES_0402LF-100,1%,1/16W,CHIPA':;

SECTION_NUMBER 1
 '@S9S_MB_2U_LIB.S9S_MB_2U(SCH_1):PAGE44_I7@PURE_QUANTA.Q_RES(CHIPS)':
 C_PATH='@s9s_mb_2u_lib.s9s_mb_2u(sch_1):page44_i7@pure_quanta.q_res(chips)',
 P_PATH='@s9s_mb_2u_lib.s9s_mb_2u(sch_1):page44_i7@pure_quanta.q_res(chips)',
 PATH='I7',
 DRAWING='@S9S_MB_2U_LIB.S9S_MB_2U(SCH_1):PAGE44',
 PHYS_PAGE='44',
 XY='(-7325,6175)',
 ROT='0',
 VER='1',
 PACK_TYPE='0402LF',
 CDS_LIB='pure_quanta',
 CDS_PART_NAME='Q_RES_0402LF-100,1%,1/16W,CHIPA',
 WATTAGE='1/16W',
 TOLERANCE='1%',
 MATERIAL='CHIP',
 VALUE='100',
 PRIM_FILE='./archive_libs/logical/q_res/chips/chips.prt';

PART_NAME
 R67 'Q_RES_0402LF-33.2,1%,1/16W,CHIA':;

SECTION_NUMBER 1
 '@S9S_MB_2U_LIB.S9S_MB_2U(SCH_1):PAGE43_I12@PURE_QUANTA.Q_RES(CHIPS)':
 C_PATH='@s9s_mb_2u_lib.s9s_mb_2u(sch_1):page43_i12@pure_quanta.q_res(chips)',
 P_PATH='@s9s_mb_2u_lib.s9s_mb_2u(sch_1):page43_i12@pure_quanta.q_res(chips)',
 PATH='I12',
 DRAWING='@S9S_MB_2U_LIB.S9S_MB_2U(SCH_1):PAGE43',
 PHYS_PAGE='43',
 XY='(425,800)',
 ROT='0',
 VER='1',
 PACK_TYPE='0402LF',
 CDS_LIB='pure_quanta',
 CDS_PART_NAME='Q_RES_0402LF-33.2,1%,1/16W,CHIA',
 WATTAGE='1/16W',
 TOLERANCE='1%',
 MATERIAL='CHIP',
 VALUE='33.2',
 PRIM_FILE='./archive_libs/logical/q_res/chips/chips.prt';

PART_NAME
 R68 'Q_RES_0402LF-33.2,1%,1/16W,CHIA':;

SECTION_NUMBER 1
 '@S9S_MB_2U_LIB.S9S_MB_2U(SCH_1):PAGE43_I13@PURE_QUANTA.Q_RES(CHIPS)':
 C_PATH='@s9s_mb_2u_lib.s9s_mb_2u(sch_1):page43_i13@pure_quanta.q_res(chips)',
 P_PATH='@s9s_mb_2u_lib.s9s_mb_2u(sch_1):page43_i13@pure_quanta.q_res(chips)',
 PATH='I13',
 DRAWING='@S9S_MB_2U_LIB.S9S_MB_2U(SCH_1):PAGE43',
 PHYS_PAGE='43',
 XY='(425,550)',
 ROT='0',
 VER='1',
 PACK_TYPE='0402LF',
 CDS_LIB='pure_quanta',
 CDS_PART_NAME='Q_RES_0402LF-33.2,1%,1/16W,CHIA',
 WATTAGE='1/16W',
 TOLERANCE='1%',
 MATERIAL='CHIP',
 VALUE='33.2',
 PRIM_FILE='./archive_libs/logical/q_res/chips/chips.prt';

PART_NAME
 R69 'Q_RES_0402LF-10K,1%,1/16W,CHIPA':;

SECTION_NUMBER 1
 '@S9S_MB_2U_LIB.S9S_MB_2U(SCH_1):PAGE43_I16@PURE_QUANTA.Q_RES(CHIPS)':
 C_PATH='@s9s_mb_2u_lib.s9s_mb_2u(sch_1):page43_i16@pure_quanta.q_res(chips)',
 P_PATH='@s9s_mb_2u_lib.s9s_mb_2u(sch_1):page43_i16@pure_quanta.q_res(chips)',
 PATH='I16',
 DRAWING='@S9S_MB_2U_LIB.S9S_MB_2U(SCH_1):PAGE43',
 PHYS_PAGE='43',
 XY='(475,-1875)',
 ROT='0',
 VER='1',
 PACK_TYPE='0402LF',
 CDS_LIB='pure_quanta',
 CDS_PART_NAME='Q_RES_0402LF-10K,1%,1/16W,CHIPA',
 WATTAGE='1/16W',
 TOLERANCE='1%',
 MATERIAL='CHIP',
 VALUE='10K',
 PRIM_FILE='./archive_libs/logical/q_res/chips/chips.prt';

PART_NAME
 R70 'Q_RES_0402LF-10K,1%,1/16W,CHIPA':;

SECTION_NUMBER 1
 '@S9S_MB_2U_LIB.S9S_MB_2U(SCH_1):PAGE43_I17@PURE_QUANTA.Q_RES(CHIPS)':
 C_PATH='@s9s_mb_2u_lib.s9s_mb_2u(sch_1):page43_i17@pure_quanta.q_res(chips)',
 P_PATH='@s9s_mb_2u_lib.s9s_mb_2u(sch_1):page43_i17@pure_quanta.q_res(chips)',
 PATH='I17',
 DRAWING='@S9S_MB_2U_LIB.S9S_MB_2U(SCH_1):PAGE43',
 PHYS_PAGE='43',
 XY='(475,-2125)',
 ROT='0',
 VER='1',
 PACK_TYPE='0402LF',
 CDS_LIB='pure_quanta',
 CDS_PART_NAME='Q_RES_0402LF-10K,1%,1/16W,CHIPA',
 WATTAGE='1/16W',
 TOLERANCE='1%',
 MATERIAL='CHIP',
 VALUE='10K',
 PRIM_FILE='./archive_libs/logical/q_res/chips/chips.prt';

PART_NAME
 R71 'Q_RES_0402LF-10K,1%,1/16W,CHIPA':;

SECTION_NUMBER 1
 '@S9S_MB_2U_LIB.S9S_MB_2U(SCH_1):PAGE192_I60@PURE_QUANTA.Q_RES(CHIPS)':
 C_PATH='@s9s_mb_2u_lib.s9s_mb_2u(sch_1):page192_i60@pure_quanta.q_res(chips)',
 P_PATH='@s9s_mb_2u_lib.s9s_mb_2u(sch_1):page204_i60@pure_quanta.q_res(chips)',
 PATH='I60',
 DRAWING='@S9S_MB_2U_LIB.S9S_MB_2U(SCH_1):PAGE192',
 PHYS_PAGE='204',
 XY='(-4950,1175)',
 ROT='0',
 VER='1',
 PACK_TYPE='0402LF',
 CDS_LIB='pure_quanta',
 CDS_PART_NAME='Q_RES_0402LF-10K,1%,1/16W,CHIPA',
 WATTAGE='1/16W',
 TOLERANCE='1%',
 MATERIAL='CHIP',
 VALUE='10K',
 PRIM_FILE='./archive_libs/logical/q_res/chips/chips.prt';

PART_NAME
 R72 'Q_RES_0402LF-196K,1%,1/16W,CHIA':;

SECTION_NUMBER 1
 '@S9S_MB_2U_LIB.S9S_MB_2U(SCH_1):PAGE113_I2@PURE_QUANTA.Q_RES(CHIPS)':
 C_PATH='@s9s_mb_2u_lib.s9s_mb_2u(sch_1):page113_i2@pure_quanta.q_res(chips)',
 P_PATH='@s9s_mb_2u_lib.s9s_mb_2u(sch_1):page113_i2@pure_quanta.q_res(chips)',
 PATH='I2',
 DRAWING='@S9S_MB_2U_LIB.S9S_MB_2U(SCH_1):PAGE113',
 PHYS_PAGE='113',
 XY='(-3675,300)',
 ROT='0',
 VER='2',
 PACK_TYPE='0402LF',
 CDS_LIB='pure_quanta',
 CDS_PART_NAME='Q_RES_0402LF-196K,1%,1/16W,CHIA',
 WATTAGE='1/16W',
 TOLERANCE='1%',
 MATERIAL='CHIP',
 VALUE='196K',
 PRIM_FILE='./archive_libs/logical/q_res/chips/chips.prt';

PART_NAME
 R73 'Q_RES_0402LF-127K,1%,1/16W,CHIA':;

SECTION_NUMBER 1
 '@S9S_MB_2U_LIB.S9S_MB_2U(SCH_1):PAGE112_I3@PURE_QUANTA.Q_RES(CHIPS)':
 C_PATH='@s9s_mb_2u_lib.s9s_mb_2u(sch_1):page112_i3@pure_quanta.q_res(chips)',
 P_PATH='@s9s_mb_2u_lib.s9s_mb_2u(sch_1):page112_i3@pure_quanta.q_res(chips)',
 PATH='I3',
 DRAWING='@S9S_MB_2U_LIB.S9S_MB_2U(SCH_1):PAGE112',
 PHYS_PAGE='112',
 XY='(-3025,150)',
 ROT='0',
 VER='2',
 PACK_TYPE='0402LF',
 CDS_LIB='pure_quanta',
 CDS_PART_NAME='Q_RES_0402LF-127K,1%,1/16W,CHIA',
 WATTAGE='1/16W',
 TOLERANCE='1%',
 MATERIAL='CHIP',
 VALUE='127K',
 PRIM_FILE='./archive_libs/logical/q_res/chips/chips.prt';

PART_NAME
 R74 'Q_RES_0402LF-84.5K,1%,1/16W,CHA':;

SECTION_NUMBER 1
 '@S9S_MB_2U_LIB.S9S_MB_2U(SCH_1):PAGE111_I5@PURE_QUANTA.Q_RES(CHIPS)':
 C_PATH='@s9s_mb_2u_lib.s9s_mb_2u(sch_1):page111_i5@pure_quanta.q_res(chips)',
 P_PATH='@s9s_mb_2u_lib.s9s_mb_2u(sch_1):page111_i5@pure_quanta.q_res(chips)',
 PATH='I5',
 DRAWING='@S9S_MB_2U_LIB.S9S_MB_2U(SCH_1):PAGE111',
 PHYS_PAGE='111',
 XY='(-2925,250)',
 ROT='0',
 VER='2',
 PACK_TYPE='0402LF',
 CDS_LIB='pure_quanta',
 CDS_PART_NAME='Q_RES_0402LF-84.5K,1%,1/16W,CHA',
 WATTAGE='1/16W',
 TOLERANCE='1%',
 MATERIAL='CHIP',
 VALUE='84.5K',
 PRIM_FILE='./archive_libs/logical/q_res/chips/chips.prt';

PART_NAME
 R75 'Q_RES_0402LF-54.9K,1%,1/16W,CHA':;

SECTION_NUMBER 1
 '@S9S_MB_2U_LIB.S9S_MB_2U(SCH_1):PAGE110_I47@PURE_QUANTA.Q_RES(CHIPS)':
 C_PATH='@s9s_mb_2u_lib.s9s_mb_2u(sch_1):page110_i47@pure_quanta.q_res(chips)',
 P_PATH='@s9s_mb_2u_lib.s9s_mb_2u(sch_1):page110_i47@pure_quanta.q_res(chips)',
 PATH='I47',
 DRAWING='@S9S_MB_2U_LIB.S9S_MB_2U(SCH_1):PAGE110',
 PHYS_PAGE='110',
 XY='(-2350,-200)',
 ROT='0',
 VER='2',
 PACK_TYPE='0402LF',
 CDS_LIB='pure_quanta',
 CDS_PART_NAME='Q_RES_0402LF-54.9K,1%,1/16W,CHA',
 WATTAGE='1/16W',
 TOLERANCE='1%',
 MATERIAL='CHIP',
 VALUE='54.9K',
 PRIM_FILE='./archive_libs/logical/q_res/chips/chips.prt';

PART_NAME
 R76 'Q_RES_0402LF-35.7K,1%,1/16W,CHA':;

SECTION_NUMBER 1
 '@S9S_MB_2U_LIB.S9S_MB_2U(SCH_1):PAGE109_I46@PURE_QUANTA.Q_RES(CHIPS)':
 C_PATH='@s9s_mb_2u_lib.s9s_mb_2u(sch_1):page109_i46@pure_quanta.q_res(chips)',
 P_PATH='@s9s_mb_2u_lib.s9s_mb_2u(sch_1):page109_i46@pure_quanta.q_res(chips)',
 PATH='I46',
 DRAWING='@S9S_MB_2U_LIB.S9S_MB_2U(SCH_1):PAGE109',
 PHYS_PAGE='109',
 XY='(-2225,50)',
 ROT='0',
 VER='2',
 PACK_TYPE='0402LF',
 CDS_LIB='pure_quanta',
 CDS_PART_NAME='Q_RES_0402LF-35.7K,1%,1/16W,CHA',
 WATTAGE='1/16W',
 TOLERANCE='1%',
 MATERIAL='CHIP',
 VALUE='35.7K',
 PRIM_FILE='./archive_libs/logical/q_res/chips/chips.prt';

PART_NAME
 R77 'Q_RES_0402LF-23.2K,1%,1/16W,CHA':;

SECTION_NUMBER 1
 '@S9S_MB_2U_LIB.S9S_MB_2U(SCH_1):PAGE108_I10@PURE_QUANTA.Q_RES(CHIPS)':
 C_PATH='@s9s_mb_2u_lib.s9s_mb_2u(sch_1):page108_i10@pure_quanta.q_res(chips)',
 P_PATH='@s9s_mb_2u_lib.s9s_mb_2u(sch_1):page108_i10@pure_quanta.q_res(chips)',
 PATH='I10',
 DRAWING='@S9S_MB_2U_LIB.S9S_MB_2U(SCH_1):PAGE108',
 PHYS_PAGE='108',
 XY='(-2500,1200)',
 ROT='0',
 VER='2',
 PACK_TYPE='0402LF',
 CDS_LIB='pure_quanta',
 CDS_PART_NAME='Q_RES_0402LF-23.2K,1%,1/16W,CHA',
 WATTAGE='1/16W',
 TOLERANCE='1%',
 MATERIAL='CHIP',
 VALUE='23.2K',
 PRIM_FILE='./archive_libs/logical/q_res/chips/chips.prt';

PART_NAME
 R78 'Q_RES_0402LF-15.4K,1%,1/16W,CHA':;

SECTION_NUMBER 1
 '@S9S_MB_2U_LIB.S9S_MB_2U(SCH_1):PAGE107_I2@PURE_QUANTA.Q_RES(CHIPS)':
 C_PATH='@s9s_mb_2u_lib.s9s_mb_2u(sch_1):page107_i2@pure_quanta.q_res(chips)',
 P_PATH='@s9s_mb_2u_lib.s9s_mb_2u(sch_1):page107_i2@pure_quanta.q_res(chips)',
 PATH='I2',
 DRAWING='@S9S_MB_2U_LIB.S9S_MB_2U(SCH_1):PAGE107',
 PHYS_PAGE='107',
 XY='(-2275,225)',
 ROT='0',
 VER='2',
 PACK_TYPE='0402LF',
 CDS_LIB='pure_quanta',
 CDS_PART_NAME='Q_RES_0402LF-15.4K,1%,1/16W,CHA',
 WATTAGE='1/16W',
 TOLERANCE='1%',
 MATERIAL='CHIP',
 VALUE='15.4K',
 PRIM_FILE='./archive_libs/logical/q_res/chips/chips.prt';

PART_NAME
 R79 'Q_RES_0402LF-10K,1%,1/16W,CHIPA':;

SECTION_NUMBER 1
 '@S9S_MB_2U_LIB.S9S_MB_2U(SCH_1):PAGE106_I2@PURE_QUANTA.Q_RES(CHIPS)':
 C_PATH='@s9s_mb_2u_lib.s9s_mb_2u(sch_1):page106_i2@pure_quanta.q_res(chips)',
 P_PATH='@s9s_mb_2u_lib.s9s_mb_2u(sch_1):page106_i2@pure_quanta.q_res(chips)',
 PATH='I2',
 DRAWING='@S9S_MB_2U_LIB.S9S_MB_2U(SCH_1):PAGE106',
 PHYS_PAGE='106',
 XY='(-2525,-175)',
 ROT='0',
 VER='2',
 PACK_TYPE='0402LF',
 CDS_LIB='pure_quanta',
 CDS_PART_NAME='Q_RES_0402LF-10K,1%,1/16W,CHIPA',
 WATTAGE='1/16W',
 TOLERANCE='1%',
 MATERIAL='CHIP',
 VALUE='10K',
 PRIM_FILE='./archive_libs/logical/q_res/chips/chips.prt';

PART_NAME
 R80 'Q_RES_0402LF-196K,1%,1/16W,CHIA':;

SECTION_NUMBER 1
 '@S9S_MB_2U_LIB.S9S_MB_2U(SCH_1):PAGE105_I2@PURE_QUANTA.Q_RES(CHIPS)':
 C_PATH='@s9s_mb_2u_lib.s9s_mb_2u(sch_1):page105_i2@pure_quanta.q_res(chips)',
 P_PATH='@s9s_mb_2u_lib.s9s_mb_2u(sch_1):page105_i2@pure_quanta.q_res(chips)',
 PATH='I2',
 DRAWING='@S9S_MB_2U_LIB.S9S_MB_2U(SCH_1):PAGE105',
 PHYS_PAGE='105',
 XY='(-2625,125)',
 ROT='0',
 VER='2',
 PACK_TYPE='0402LF',
 CDS_LIB='pure_quanta',
 CDS_PART_NAME='Q_RES_0402LF-196K,1%,1/16W,CHIA',
 WATTAGE='1/16W',
 TOLERANCE='1%',
 MATERIAL='CHIP',
 VALUE='196K',
 PRIM_FILE='./archive_libs/logical/q_res/chips/chips.prt';

PART_NAME
 R87 'Q_RES_0402LF-1K,1%,1/16W,EMPTYA':;

SECTION_NUMBER 1
 '@S9S_MB_2U_LIB.S9S_MB_2U(SCH_1):PAGE217_I43@PURE_QUANTA.Q_RES(CHIPS)':
 C_PATH='@s9s_mb_2u_lib.s9s_mb_2u(sch_1):page217_i43@pure_quanta.q_res(chips)',
 P_PATH='@s9s_mb_2u_lib.s9s_mb_2u(sch_1):page229_i43@pure_quanta.q_res(chips)',
 PATH='I43',
 DRAWING='@S9S_MB_2U_LIB.S9S_MB_2U(SCH_1):PAGE217',
 PHYS_PAGE='229',
 XY='(1600,950)',
 ROT='0',
 VER='2',
 PACK_TYPE='0402LF',
 CDS_LIB='pure_quanta',
 CDS_PART_NAME='Q_RES_0402LF-1K,1%,1/16W,EMPTYA',
 WATTAGE='1/16W',
 TOLERANCE='1%',
 MATERIAL='EMPTY',
 VALUE='1K',
 PRIM_FILE='./archive_libs/logical/q_res/chips/chips.prt';

PART_NAME
 R90 'Q_RES_0402LF-240,1%,1/16W,EMPTA':;

SECTION_NUMBER 1
 '@S9S_MB_2U_LIB.S9S_MB_2U(SCH_1):PAGE126_I135@PURE_QUANTA.Q_RES(CHIPS)':
 C_PATH='@s9s_mb_2u_lib.s9s_mb_2u(sch_1):page126_i135@pure_quanta.q_res(chips)',
 P_PATH='@s9s_mb_2u_lib.s9s_mb_2u(sch_1):page126_i135@pure_quanta.q_res(chips)',
 PATH='I135',
 DRAWING='@S9S_MB_2U_LIB.S9S_MB_2U(SCH_1):PAGE126',
 PHYS_PAGE='126',
 XY='(-1725,-1100)',
 ROT='0',
 VER='1',
 PACK_TYPE='0402LF',
 CDS_LIB='pure_quanta',
 CDS_PART_NAME='Q_RES_0402LF-240,1%,1/16W,EMPTA',
 WATTAGE='1/16W',
 TOLERANCE='1%',
 MATERIAL='EMPTY',
 VALUE='240',
 PRIM_FILE='./archive_libs/logical/q_res/chips/chips.prt';

PART_NAME
 R91 'Q_RES_0402LF-240,1%,1/16W,EMPTA':;

SECTION_NUMBER 1
 '@S9S_MB_2U_LIB.S9S_MB_2U(SCH_1):PAGE126_I136@PURE_QUANTA.Q_RES(CHIPS)':
 C_PATH='@s9s_mb_2u_lib.s9s_mb_2u(sch_1):page126_i136@pure_quanta.q_res(chips)',
 P_PATH='@s9s_mb_2u_lib.s9s_mb_2u(sch_1):page126_i136@pure_quanta.q_res(chips)',
 PATH='I136',
 DRAWING='@S9S_MB_2U_LIB.S9S_MB_2U(SCH_1):PAGE126',
 PHYS_PAGE='126',
 XY='(-1725,-1225)',
 ROT='0',
 VER='1',
 PACK_TYPE='0402LF',
 CDS_LIB='pure_quanta',
 CDS_PART_NAME='Q_RES_0402LF-240,1%,1/16W,EMPTA',
 WATTAGE='1/16W',
 TOLERANCE='1%',
 MATERIAL='EMPTY',
 VALUE='240',
 PRIM_FILE='./archive_libs/logical/q_res/chips/chips.prt';

PART_NAME
 R92 'Q_RES_0402LF-240,1%,1/16W,EMPTA':;

SECTION_NUMBER 1
 '@S9S_MB_2U_LIB.S9S_MB_2U(SCH_1):PAGE126_I140@PURE_QUANTA.Q_RES(CHIPS)':
 C_PATH='@s9s_mb_2u_lib.s9s_mb_2u(sch_1):page126_i140@pure_quanta.q_res(chips)',
 P_PATH='@s9s_mb_2u_lib.s9s_mb_2u(sch_1):page126_i140@pure_quanta.q_res(chips)',
 PATH='I140',
 DRAWING='@S9S_MB_2U_LIB.S9S_MB_2U(SCH_1):PAGE126',
 PHYS_PAGE='126',
 XY='(-1725,-1350)',
 ROT='0',
 VER='1',
 PACK_TYPE='0402LF',
 CDS_LIB='pure_quanta',
 CDS_PART_NAME='Q_RES_0402LF-240,1%,1/16W,EMPTA',
 WATTAGE='1/16W',
 TOLERANCE='1%',
 MATERIAL='EMPTY',
 VALUE='240',
 PRIM_FILE='./archive_libs/logical/q_res/chips/chips.prt';

PART_NAME
 R93 'Q_RES_0402LF-240,1%,1/16W,EMPTA':;

SECTION_NUMBER 1
 '@S9S_MB_2U_LIB.S9S_MB_2U(SCH_1):PAGE126_I141@PURE_QUANTA.Q_RES(CHIPS)':
 C_PATH='@s9s_mb_2u_lib.s9s_mb_2u(sch_1):page126_i141@pure_quanta.q_res(chips)',
 P_PATH='@s9s_mb_2u_lib.s9s_mb_2u(sch_1):page126_i141@pure_quanta.q_res(chips)',
 PATH='I141',
 DRAWING='@S9S_MB_2U_LIB.S9S_MB_2U(SCH_1):PAGE126',
 PHYS_PAGE='126',
 XY='(-1725,-1475)',
 ROT='0',
 VER='1',
 PACK_TYPE='0402LF',
 CDS_LIB='pure_quanta',
 CDS_PART_NAME='Q_RES_0402LF-240,1%,1/16W,EMPTA',
 WATTAGE='1/16W',
 TOLERANCE='1%',
 MATERIAL='EMPTY',
 VALUE='240',
 PRIM_FILE='./archive_libs/logical/q_res/chips/chips.prt';

PART_NAME
 R94 'Q_RES_0402LF-240,1%,1/16W,EMPTA':;

SECTION_NUMBER 1
 '@S9S_MB_2U_LIB.S9S_MB_2U(SCH_1):PAGE126_I25@PURE_QUANTA.Q_RES(CHIPS)':
 C_PATH='@s9s_mb_2u_lib.s9s_mb_2u(sch_1):page126_i25@pure_quanta.q_res(chips)',
 P_PATH='@s9s_mb_2u_lib.s9s_mb_2u(sch_1):page126_i25@pure_quanta.q_res(chips)',
 PATH='I25',
 DRAWING='@S9S_MB_2U_LIB.S9S_MB_2U(SCH_1):PAGE126',
 PHYS_PAGE='126',
 XY='(-1700,225)',
 ROT='0',
 VER='1',
 PACK_TYPE='0402LF',
 CDS_LIB='pure_quanta',
 CDS_PART_NAME='Q_RES_0402LF-240,1%,1/16W,EMPTA',
 WATTAGE='1/16W',
 TOLERANCE='1%',
 MATERIAL='EMPTY',
 VALUE='240',
 PRIM_FILE='./archive_libs/logical/q_res/chips/chips.prt';

PART_NAME
 R95 'Q_RES_0402LF-240,1%,1/16W,EMPTA':;

SECTION_NUMBER 1
 '@S9S_MB_2U_LIB.S9S_MB_2U(SCH_1):PAGE126_I23@PURE_QUANTA.Q_RES(CHIPS)':
 C_PATH='@s9s_mb_2u_lib.s9s_mb_2u(sch_1):page126_i23@pure_quanta.q_res(chips)',
 P_PATH='@s9s_mb_2u_lib.s9s_mb_2u(sch_1):page126_i23@pure_quanta.q_res(chips)',
 PATH='I23',
 DRAWING='@S9S_MB_2U_LIB.S9S_MB_2U(SCH_1):PAGE126',
 PHYS_PAGE='126',
 XY='(-1700,100)',
 ROT='0',
 VER='1',
 PACK_TYPE='0402LF',
 CDS_LIB='pure_quanta',
 CDS_PART_NAME='Q_RES_0402LF-240,1%,1/16W,EMPTA',
 WATTAGE='1/16W',
 TOLERANCE='1%',
 MATERIAL='EMPTY',
 VALUE='240',
 PRIM_FILE='./archive_libs/logical/q_res/chips/chips.prt';

PART_NAME
 R96 'Q_RES_0402LF-240,1%,1/16W,EMPTA':;

SECTION_NUMBER 1
 '@S9S_MB_2U_LIB.S9S_MB_2U(SCH_1):PAGE126_I22@PURE_QUANTA.Q_RES(CHIPS)':
 C_PATH='@s9s_mb_2u_lib.s9s_mb_2u(sch_1):page126_i22@pure_quanta.q_res(chips)',
 P_PATH='@s9s_mb_2u_lib.s9s_mb_2u(sch_1):page126_i22@pure_quanta.q_res(chips)',
 PATH='I22',
 DRAWING='@S9S_MB_2U_LIB.S9S_MB_2U(SCH_1):PAGE126',
 PHYS_PAGE='126',
 XY='(-1700,-25)',
 ROT='0',
 VER='1',
 PACK_TYPE='0402LF',
 CDS_LIB='pure_quanta',
 CDS_PART_NAME='Q_RES_0402LF-240,1%,1/16W,EMPTA',
 WATTAGE='1/16W',
 TOLERANCE='1%',
 MATERIAL='EMPTY',
 VALUE='240',
 PRIM_FILE='./archive_libs/logical/q_res/chips/chips.prt';

PART_NAME
 R97 'Q_RES_0402LF-240,1%,1/16W,EMPTA':;

SECTION_NUMBER 1
 '@S9S_MB_2U_LIB.S9S_MB_2U(SCH_1):PAGE126_I114@PURE_QUANTA.Q_RES(CHIPS)':
 C_PATH='@s9s_mb_2u_lib.s9s_mb_2u(sch_1):page126_i114@pure_quanta.q_res(chips)',
 P_PATH='@s9s_mb_2u_lib.s9s_mb_2u(sch_1):page126_i114@pure_quanta.q_res(chips)',
 PATH='I114',
 DRAWING='@S9S_MB_2U_LIB.S9S_MB_2U(SCH_1):PAGE126',
 PHYS_PAGE='126',
 XY='(-1700,-150)',
 ROT='0',
 VER='1',
 PACK_TYPE='0402LF',
 CDS_LIB='pure_quanta',
 CDS_PART_NAME='Q_RES_0402LF-240,1%,1/16W,EMPTA',
 WATTAGE='1/16W',
 TOLERANCE='1%',
 MATERIAL='EMPTY',
 VALUE='240',
 PRIM_FILE='./archive_libs/logical/q_res/chips/chips.prt';

PART_NAME
 R106 'Q_RES_0402LF-2K,1%,1/16W,CHIP,A':;

SECTION_NUMBER 1
 '@S9S_MB_2U_LIB.S9S_MB_2U(SCH_1):PAGE195_I304@PURE_QUANTA.Q_RES(CHIPS)':
 C_PATH='@s9s_mb_2u_lib.s9s_mb_2u(sch_1):page195_i304@pure_quanta.q_res(chips)',
 P_PATH='@s9s_mb_2u_lib.s9s_mb_2u(sch_1):page206_i304@pure_quanta.q_res(chips)',
 PATH='I304',
 DRAWING='@S9S_MB_2U_LIB.S9S_MB_2U(SCH_1):PAGE195',
 PHYS_PAGE='206',
 XY='(-6225,2400)',
 ROT='0',
 VER='1',
 PACK_TYPE='0402LF',
 CDS_LIB='pure_quanta',
 CDS_PART_NAME='Q_RES_0402LF-2K,1%,1/16W,CHIP,A',
 WATTAGE='1/16W',
 TOLERANCE='1%',
 MATERIAL='CHIP',
 VALUE='2K',
 PRIM_FILE='./archive_libs/logical/q_res/chips/chips.prt';

PART_NAME
 R107 'Q_RES_0402LF-33.2,1%,1/16W,CHIA':;

SECTION_NUMBER 1
 '@S9S_MB_2U_LIB.S9S_MB_2U(SCH_1):PAGE228_I43@PURE_QUANTA.Q_RES(CHIPS)':
 C_PATH='@s9s_mb_2u_lib.s9s_mb_2u(sch_1):page228_i43@pure_quanta.q_res(chips)',
 P_PATH='@s9s_mb_2u_lib.s9s_mb_2u(sch_1):page241_i43@pure_quanta.q_res(chips)',
 PATH='I43',
 DRAWING='@S9S_MB_2U_LIB.S9S_MB_2U(SCH_1):PAGE228',
 PHYS_PAGE='241',
 XY='(-350,5175)',
 ROT='0',
 VER='1',
 PACK_TYPE='0402LF',
 CDS_LIB='pure_quanta',
 CDS_PART_NAME='Q_RES_0402LF-33.2,1%,1/16W,CHIA',
 WATTAGE='1/16W',
 TOLERANCE='1%',
 MATERIAL='CHIP',
 VALUE='33.2',
 PRIM_FILE='./archive_libs/logical/q_res/chips/chips.prt';

PART_NAME
 R108 'Q_RES_0402LF-33.2,1%,1/16W,CHIA':;

SECTION_NUMBER 1
 '@S9S_MB_2U_LIB.S9S_MB_2U(SCH_1):PAGE228_I42@PURE_QUANTA.Q_RES(CHIPS)':
 C_PATH='@s9s_mb_2u_lib.s9s_mb_2u(sch_1):page228_i42@pure_quanta.q_res(chips)',
 P_PATH='@s9s_mb_2u_lib.s9s_mb_2u(sch_1):page241_i42@pure_quanta.q_res(chips)',
 PATH='I42',
 DRAWING='@S9S_MB_2U_LIB.S9S_MB_2U(SCH_1):PAGE228',
 PHYS_PAGE='241',
 XY='(-350,5125)',
 ROT='0',
 VER='1',
 PACK_TYPE='0402LF',
 CDS_LIB='pure_quanta',
 CDS_PART_NAME='Q_RES_0402LF-33.2,1%,1/16W,CHIA',
 WATTAGE='1/16W',
 TOLERANCE='1%',
 MATERIAL='CHIP',
 VALUE='33.2',
 PRIM_FILE='./archive_libs/logical/q_res/chips/chips.prt';

PART_NAME
 R109 'Q_RES_0402LF-33.2,1%,1/16W,CHIA':;

SECTION_NUMBER 1
 '@S9S_MB_2U_LIB.S9S_MB_2U(SCH_1):PAGE212_I44@PURE_QUANTA.Q_RES(CHIPS)':
 C_PATH='@s9s_mb_2u_lib.s9s_mb_2u(sch_1):page212_i44@pure_quanta.q_res(chips)',
 P_PATH='@s9s_mb_2u_lib.s9s_mb_2u(sch_1):page223_i44@pure_quanta.q_res(chips)',
 PATH='I44',
 DRAWING='@S9S_MB_2U_LIB.S9S_MB_2U(SCH_1):PAGE212',
 PHYS_PAGE='223',
 XY='(-2800,3550)',
 ROT='0',
 VER='1',
 PACK_TYPE='0402LF',
 CDS_LIB='pure_quanta',
 CDS_PART_NAME='Q_RES_0402LF-33.2,1%,1/16W,CHIA',
 WATTAGE='1/16W',
 TOLERANCE='1%',
 MATERIAL='CHIP',
 VALUE='33.2',
 PRIM_FILE='./archive_libs/logical/q_res/chips/chips.prt';

PART_NAME
 R110 'Q_RES_0402LF-33.2,1%,1/16W,CHIA':;

SECTION_NUMBER 1
 '@S9S_MB_2U_LIB.S9S_MB_2U(SCH_1):PAGE212_I17@PURE_QUANTA.Q_RES(CHIPS)':
 C_PATH='@s9s_mb_2u_lib.s9s_mb_2u(sch_1):page212_i17@pure_quanta.q_res(chips)',
 P_PATH='@s9s_mb_2u_lib.s9s_mb_2u(sch_1):page223_i17@pure_quanta.q_res(chips)',
 PATH='I17',
 DRAWING='@S9S_MB_2U_LIB.S9S_MB_2U(SCH_1):PAGE212',
 PHYS_PAGE='223',
 XY='(-2800,1575)',
 ROT='0',
 VER='1',
 PACK_TYPE='0402LF',
 CDS_LIB='pure_quanta',
 CDS_PART_NAME='Q_RES_0402LF-33.2,1%,1/16W,CHIA',
 WATTAGE='1/16W',
 TOLERANCE='1%',
 MATERIAL='CHIP',
 VALUE='33.2',
 PRIM_FILE='./archive_libs/logical/q_res/chips/chips.prt';

PART_NAME
 R111 'Q_RES_0402LF-10K,1%,1/16W,CHIPA':;

SECTION_NUMBER 1
 '@S9S_MB_2U_LIB.S9S_MB_2U(SCH_1):PAGE212_I24@PURE_QUANTA.Q_RES(CHIPS)':
 C_PATH='@s9s_mb_2u_lib.s9s_mb_2u(sch_1):page212_i24@pure_quanta.q_res(chips)',
 P_PATH='@s9s_mb_2u_lib.s9s_mb_2u(sch_1):page223_i24@pure_quanta.q_res(chips)',
 PATH='I24',
 DRAWING='@S9S_MB_2U_LIB.S9S_MB_2U(SCH_1):PAGE212',
 PHYS_PAGE='223',
 XY='(-2750,1075)',
 ROT='0',
 VER='2',
 PACK_TYPE='0402LF',
 CDS_LIB='pure_quanta',
 CDS_PART_NAME='Q_RES_0402LF-10K,1%,1/16W,CHIPA',
 WATTAGE='1/16W',
 TOLERANCE='1%',
 MATERIAL='CHIP',
 VALUE='10K',
 PRIM_FILE='./archive_libs/logical/q_res/chips/chips.prt';

PART_NAME
 R113 'Q_RES_0402LF-33.2,1%,1/16W,CHIA':;

SECTION_NUMBER 1
 '@S9S_MB_2U_LIB.S9S_MB_2U(SCH_1):PAGE212_I27@PURE_QUANTA.Q_RES(CHIPS)':
 C_PATH='@s9s_mb_2u_lib.s9s_mb_2u(sch_1):page212_i27@pure_quanta.q_res(chips)',
 P_PATH='@s9s_mb_2u_lib.s9s_mb_2u(sch_1):page223_i27@pure_quanta.q_res(chips)',
 PATH='I27',
 DRAWING='@S9S_MB_2U_LIB.S9S_MB_2U(SCH_1):PAGE212',
 PHYS_PAGE='223',
 XY='(-1550,825)',
 ROT='0',
 VER='1',
 PACK_TYPE='0402LF',
 CDS_LIB='pure_quanta',
 CDS_PART_NAME='Q_RES_0402LF-33.2,1%,1/16W,CHIA',
 WATTAGE='1/16W',
 TOLERANCE='1%',
 MATERIAL='CHIP',
 VALUE='33.2',
 PRIM_FILE='./archive_libs/logical/q_res/chips/chips.prt';

PART_NAME
 R120 'Q_RES_0603LF-10M,1%,1/10W,CHIPA':;

SECTION_NUMBER 1
 '@S9S_MB_2U_LIB.S9S_MB_2U(SCH_1):PAGE171_I74@PURE_QUANTA.Q_RES(CHIPS)':
 C_PATH='@s9s_mb_2u_lib.s9s_mb_2u(sch_1):page171_i74@pure_quanta.q_res(chips)',
 P_PATH='@s9s_mb_2u_lib.s9s_mb_2u(sch_1):page179_i74@pure_quanta.q_res(chips)',
 PATH='I74',
 DRAWING='@S9S_MB_2U_LIB.S9S_MB_2U(SCH_1):PAGE171',
 PHYS_PAGE='179',
 XY='(1675,-100)',
 ROT='0',
 VER='1',
 PACK_TYPE='0603LF',
 CDS_LIB='pure_quanta',
 CDS_PART_NAME='Q_RES_0603LF-10M,1%,1/10W,CHIPA',
 WATTAGE='1/10W',
 TOLERANCE='1%',
 MATERIAL='CHIP',
 VALUE='10M',
 PRIM_FILE='./archive_libs/logical/q_res/chips/chips.prt';

PART_NAME
 R122 'Q_RES_0402LF-0,5%,1/16W,CHIP,CA':;

SECTION_NUMBER 1
 '@S9S_MB_2U_LIB.S9S_MB_2U(SCH_1):PAGE125_I17@PURE_QUANTA.Q_RES(CHIPS)':
 C_PATH='@s9s_mb_2u_lib.s9s_mb_2u(sch_1):page125_i17@pure_quanta.q_res(chips)',
 P_PATH='@s9s_mb_2u_lib.s9s_mb_2u(sch_1):page125_i17@pure_quanta.q_res(chips)',
 PATH='I17',
 DRAWING='@S9S_MB_2U_LIB.S9S_MB_2U(SCH_1):PAGE125',
 PHYS_PAGE='125',
 XY='(-5300,3275)',
 ROT='0',
 VER='1',
 PACK_TYPE='0402LF',
 CDS_LIB='pure_quanta',
 CDS_PART_NAME='Q_RES_0402LF-0,5%,1/16W,CHIP,CA',
 WATTAGE='1/16W',
 TOLERANCE='5%',
 MATERIAL='CHIP',
 VALUE='0',
 PRIM_FILE='./archive_libs/logical/q_res/chips/chips.prt';

PART_NAME
 R124 'Q_RES_0402LF-0,5%,1/16W,CHIP,CA':;

SECTION_NUMBER 1
 '@S9S_MB_2U_LIB.S9S_MB_2U(SCH_1):PAGE125_I15@PURE_QUANTA.Q_RES(CHIPS)':
 C_PATH='@s9s_mb_2u_lib.s9s_mb_2u(sch_1):page125_i15@pure_quanta.q_res(chips)',
 P_PATH='@s9s_mb_2u_lib.s9s_mb_2u(sch_1):page125_i15@pure_quanta.q_res(chips)',
 PATH='I15',
 DRAWING='@S9S_MB_2U_LIB.S9S_MB_2U(SCH_1):PAGE125',
 PHYS_PAGE='125',
 XY='(-5300,2450)',
 ROT='0',
 VER='1',
 PACK_TYPE='0402LF',
 CDS_LIB='pure_quanta',
 CDS_PART_NAME='Q_RES_0402LF-0,5%,1/16W,CHIP,CA',
 WATTAGE='1/16W',
 TOLERANCE='5%',
 MATERIAL='CHIP',
 VALUE='0',
 PRIM_FILE='./archive_libs/logical/q_res/chips/chips.prt';

PART_NAME
 R126 'Q_RES_0402LF-0,5%,1/16W,CHIP,CA':;

SECTION_NUMBER 1
 '@S9S_MB_2U_LIB.S9S_MB_2U(SCH_1):PAGE125_I13@PURE_QUANTA.Q_RES(CHIPS)':
 C_PATH='@s9s_mb_2u_lib.s9s_mb_2u(sch_1):page125_i13@pure_quanta.q_res(chips)',
 P_PATH='@s9s_mb_2u_lib.s9s_mb_2u(sch_1):page125_i13@pure_quanta.q_res(chips)',
 PATH='I13',
 DRAWING='@S9S_MB_2U_LIB.S9S_MB_2U(SCH_1):PAGE125',
 PHYS_PAGE='125',
 XY='(-5300,1600)',
 ROT='0',
 VER='1',
 PACK_TYPE='0402LF',
 CDS_LIB='pure_quanta',
 CDS_PART_NAME='Q_RES_0402LF-0,5%,1/16W,CHIP,CA',
 WATTAGE='1/16W',
 TOLERANCE='5%',
 MATERIAL='CHIP',
 VALUE='0',
 PRIM_FILE='./archive_libs/logical/q_res/chips/chips.prt';

PART_NAME
 R128 'Q_RES_0402LF-0,5%,1/16W,CHIP,CA':;

SECTION_NUMBER 1
 '@S9S_MB_2U_LIB.S9S_MB_2U(SCH_1):PAGE125_I7@PURE_QUANTA.Q_RES(CHIPS)':
 C_PATH='@s9s_mb_2u_lib.s9s_mb_2u(sch_1):page125_i7@pure_quanta.q_res(chips)',
 P_PATH='@s9s_mb_2u_lib.s9s_mb_2u(sch_1):page125_i7@pure_quanta.q_res(chips)',
 PATH='I7',
 DRAWING='@S9S_MB_2U_LIB.S9S_MB_2U(SCH_1):PAGE125',
 PHYS_PAGE='125',
 XY='(-5300,775)',
 ROT='0',
 VER='1',
 PACK_TYPE='0402LF',
 CDS_LIB='pure_quanta',
 CDS_PART_NAME='Q_RES_0402LF-0,5%,1/16W,CHIP,CA',
 WATTAGE='1/16W',
 TOLERANCE='5%',
 MATERIAL='CHIP',
 VALUE='0',
 PRIM_FILE='./archive_libs/logical/q_res/chips/chips.prt';

PART_NAME
 R130 'Q_RES_0402LF-0,5%,1/16W,CHIP,CA':;

SECTION_NUMBER 1
 '@S9S_MB_2U_LIB.S9S_MB_2U(SCH_1):PAGE125_I5@PURE_QUANTA.Q_RES(CHIPS)':
 C_PATH='@s9s_mb_2u_lib.s9s_mb_2u(sch_1):page125_i5@pure_quanta.q_res(chips)',
 P_PATH='@s9s_mb_2u_lib.s9s_mb_2u(sch_1):page125_i5@pure_quanta.q_res(chips)',
 PATH='I5',
 DRAWING='@S9S_MB_2U_LIB.S9S_MB_2U(SCH_1):PAGE125',
 PHYS_PAGE='125',
 XY='(-5300,-50)',
 ROT='0',
 VER='1',
 PACK_TYPE='0402LF',
 CDS_LIB='pure_quanta',
 CDS_PART_NAME='Q_RES_0402LF-0,5%,1/16W,CHIP,CA',
 WATTAGE='1/16W',
 TOLERANCE='5%',
 MATERIAL='CHIP',
 VALUE='0',
 PRIM_FILE='./archive_libs/logical/q_res/chips/chips.prt';

PART_NAME
 R132 'Q_RES_0402LF-0,5%,1/16W,CHIP,CA':;

SECTION_NUMBER 1
 '@S9S_MB_2U_LIB.S9S_MB_2U(SCH_1):PAGE125_I3@PURE_QUANTA.Q_RES(CHIPS)':
 C_PATH='@s9s_mb_2u_lib.s9s_mb_2u(sch_1):page125_i3@pure_quanta.q_res(chips)',
 P_PATH='@s9s_mb_2u_lib.s9s_mb_2u(sch_1):page125_i3@pure_quanta.q_res(chips)',
 PATH='I3',
 DRAWING='@S9S_MB_2U_LIB.S9S_MB_2U(SCH_1):PAGE125',
 PHYS_PAGE='125',
 XY='(-5300,-900)',
 ROT='0',
 VER='1',
 PACK_TYPE='0402LF',
 CDS_LIB='pure_quanta',
 CDS_PART_NAME='Q_RES_0402LF-0,5%,1/16W,CHIP,CA',
 WATTAGE='1/16W',
 TOLERANCE='5%',
 MATERIAL='CHIP',
 VALUE='0',
 PRIM_FILE='./archive_libs/logical/q_res/chips/chips.prt';

PART_NAME
 R135 'Q_RES_0402LF-100,1%,1/16W,CHIPA':;

SECTION_NUMBER 1
 '@S9S_MB_2U_LIB.S9S_MB_2U(SCH_1):PAGE125_I62@PURE_QUANTA.Q_RES(CHIPS)':
 C_PATH='@s9s_mb_2u_lib.s9s_mb_2u(sch_1):page125_i62@pure_quanta.q_res(chips)',
 P_PATH='@s9s_mb_2u_lib.s9s_mb_2u(sch_1):page125_i62@pure_quanta.q_res(chips)',
 PATH='I62',
 DRAWING='@S9S_MB_2U_LIB.S9S_MB_2U(SCH_1):PAGE125',
 PHYS_PAGE='125',
 XY='(-1100,3450)',
 ROT='0',
 VER='1',
 PACK_TYPE='0402LF',
 CDS_LIB='pure_quanta',
 CDS_PART_NAME='Q_RES_0402LF-100,1%,1/16W,CHIPA',
 WATTAGE='1/16W',
 TOLERANCE='1%',
 MATERIAL='CHIP',
 VALUE='100',
 PRIM_FILE='./archive_libs/logical/q_res/chips/chips.prt';

PART_NAME
 R137 'Q_RES_0402LF-100,1%,1/16W,CHIPA':;

SECTION_NUMBER 1
 '@S9S_MB_2U_LIB.S9S_MB_2U(SCH_1):PAGE125_I60@PURE_QUANTA.Q_RES(CHIPS)':
 C_PATH='@s9s_mb_2u_lib.s9s_mb_2u(sch_1):page125_i60@pure_quanta.q_res(chips)',
 P_PATH='@s9s_mb_2u_lib.s9s_mb_2u(sch_1):page125_i60@pure_quanta.q_res(chips)',
 PATH='I60',
 DRAWING='@S9S_MB_2U_LIB.S9S_MB_2U(SCH_1):PAGE125',
 PHYS_PAGE='125',
 XY='(-1100,2625)',
 ROT='0',
 VER='1',
 PACK_TYPE='0402LF',
 CDS_LIB='pure_quanta',
 CDS_PART_NAME='Q_RES_0402LF-100,1%,1/16W,CHIPA',
 WATTAGE='1/16W',
 TOLERANCE='1%',
 MATERIAL='CHIP',
 VALUE='100',
 PRIM_FILE='./archive_libs/logical/q_res/chips/chips.prt';

PART_NAME
 R139 'Q_RES_0402LF-10K,1%,1/16W,EMPTA':;

SECTION_NUMBER 1
 '@S9S_MB_2U_LIB.S9S_MB_2U(SCH_1):PAGE209_I40@PURE_QUANTA.Q_RES(CHIPS)':
 C_PATH='@s9s_mb_2u_lib.s9s_mb_2u(sch_1):page209_i40@pure_quanta.q_res(chips)',
 P_PATH='@s9s_mb_2u_lib.s9s_mb_2u(sch_1):page220_i40@pure_quanta.q_res(chips)',
 PATH='I40',
 DRAWING='@S9S_MB_2U_LIB.S9S_MB_2U(SCH_1):PAGE209',
 PHYS_PAGE='220',
 XY='(1775,-350)',
 ROT='0',
 VER='1',
 PACK_TYPE='0402LF',
 CDS_LIB='pure_quanta',
 CDS_PART_NAME='Q_RES_0402LF-10K,1%,1/16W,EMPTA',
 WATTAGE='1/16W',
 TOLERANCE='1%',
 MATERIAL='EMPTY',
 VALUE='10K',
 PRIM_FILE='./archive_libs/logical/q_res/chips/chips.prt';

PART_NAME
 R142 'Q_RES_0402LF-0,5%,1/16W,CHIP,CA':;

SECTION_NUMBER 1
 '@S9S_MB_2U_LIB.S9S_MB_2U(SCH_1):PAGE227_I84@PURE_QUANTA.Q_RES(CHIPS)':
 C_PATH='@s9s_mb_2u_lib.s9s_mb_2u(sch_1):page227_i84@pure_quanta.q_res(chips)',
 P_PATH='@s9s_mb_2u_lib.s9s_mb_2u(sch_1):page240_i84@pure_quanta.q_res(chips)',
 PATH='I84',
 DRAWING='@S9S_MB_2U_LIB.S9S_MB_2U(SCH_1):PAGE227',
 PHYS_PAGE='240',
 XY='(-14625,2375)',
 ROT='0',
 VER='1',
 PACK_TYPE='0402LF',
 CDS_LIB='pure_quanta',
 CDS_PART_NAME='Q_RES_0402LF-0,5%,1/16W,CHIP,CA',
 WATTAGE='1/16W',
 TOLERANCE='5%',
 MATERIAL='CHIP',
 VALUE='0',
 PRIM_FILE='./archive_libs/logical/q_res/chips/chips.prt';

PART_NAME
 R143 'Q_RES_0402LF-49.9,1%,1/16W,CHIA':;

SECTION_NUMBER 1
 '@S9S_MB_2U_LIB.S9S_MB_2U(SCH_1):PAGE185_I47@PURE_QUANTA.Q_RES(CHIPS)':
 C_PATH='@s9s_mb_2u_lib.s9s_mb_2u(sch_1):page185_i47@pure_quanta.q_res(chips)',
 P_PATH='@s9s_mb_2u_lib.s9s_mb_2u(sch_1):page197_i47@pure_quanta.q_res(chips)',
 PATH='I47',
 DRAWING='@S9S_MB_2U_LIB.S9S_MB_2U(SCH_1):PAGE185',
 PHYS_PAGE='197',
 XY='(-8800,3300)',
 ROT='0',
 VER='1',
 PACK_TYPE='0402LF',
 LOCATION='R143',
 CDS_LIB='pure_quanta',
 CDS_PART_NAME='Q_RES_0402LF-49.9,1%,1/16W,CHIA',
 WATTAGE='1/16W',
 TOLERANCE='1%',
 MATERIAL='CHIP',
 VALUE='49.9',
 PRIM_FILE='./archive_libs/logical/q_res/chips/chips.prt';

PART_NAME
 R144 'Q_RES_0402LF-0,5%,1/16W,CHIP,CA':;

SECTION_NUMBER 1
 '@S9S_MB_2U_LIB.S9S_MB_2U(SCH_1):PAGE185_I51@PURE_QUANTA.Q_RES(CHIPS)':
 C_PATH='@s9s_mb_2u_lib.s9s_mb_2u(sch_1):page185_i51@pure_quanta.q_res(chips)',
 P_PATH='@s9s_mb_2u_lib.s9s_mb_2u(sch_1):page197_i51@pure_quanta.q_res(chips)',
 PATH='I51',
 DRAWING='@S9S_MB_2U_LIB.S9S_MB_2U(SCH_1):PAGE185',
 PHYS_PAGE='197',
 XY='(-8800,4625)',
 ROT='0',
 VER='1',
 PACK_TYPE='0402LF',
 LOCATION='R144',
 CDS_LIB='pure_quanta',
 CDS_PART_NAME='Q_RES_0402LF-0,5%,1/16W,CHIP,CA',
 WATTAGE='1/16W',
 TOLERANCE='5%',
 MATERIAL='CHIP',
 VALUE='0',
 PRIM_FILE='./archive_libs/logical/q_res/chips/chips.prt';

PART_NAME
 R145 'Q_RES_0402LF-4.75K,1%,1/16W,EMA':;

SECTION_NUMBER 1
 '@S9S_MB_2U_LIB.S9S_MB_2U(SCH_1):PAGE185_I26@PURE_QUANTA.Q_RES(CHIPS)':
 C_PATH='@s9s_mb_2u_lib.s9s_mb_2u(sch_1):page185_i26@pure_quanta.q_res(chips)',
 P_PATH='@s9s_mb_2u_lib.s9s_mb_2u(sch_1):page197_i26@pure_quanta.q_res(chips)',
 PATH='I26',
 DRAWING='@S9S_MB_2U_LIB.S9S_MB_2U(SCH_1):PAGE185',
 PHYS_PAGE='197',
 XY='(-7700,3625)',
 ROT='0',
 VER='2',
 PACK_TYPE='0402LF',
 CDS_LIB='pure_quanta',
 CDS_PART_NAME='Q_RES_0402LF-4.75K,1%,1/16W,EMA',
 WATTAGE='1/16W',
 TOLERANCE='1%',
 MATERIAL='EMPTY',
 VALUE='4.75K',
 PRIM_FILE='./archive_libs/logical/q_res/chips/chips.prt';

PART_NAME
 R146 'Q_RES_0402LF-4.75K,1%,1/16W,EMA':;

SECTION_NUMBER 1
 '@S9S_MB_2U_LIB.S9S_MB_2U(SCH_1):PAGE185_I30@PURE_QUANTA.Q_RES(CHIPS)':
 C_PATH='@s9s_mb_2u_lib.s9s_mb_2u(sch_1):page185_i30@pure_quanta.q_res(chips)',
 P_PATH='@s9s_mb_2u_lib.s9s_mb_2u(sch_1):page197_i30@pure_quanta.q_res(chips)',
 PATH='I30',
 DRAWING='@S9S_MB_2U_LIB.S9S_MB_2U(SCH_1):PAGE185',
 PHYS_PAGE='197',
 XY='(-7675,4950)',
 ROT='0',
 VER='2',
 PACK_TYPE='0402LF',
 CDS_LIB='pure_quanta',
 CDS_PART_NAME='Q_RES_0402LF-4.75K,1%,1/16W,EMA',
 WATTAGE='1/16W',
 TOLERANCE='1%',
 MATERIAL='EMPTY',
 VALUE='4.75K',
 PRIM_FILE='./archive_libs/logical/q_res/chips/chips.prt';

PART_NAME
 R147 'Q_RES_0402LF-10K,1%,1/16W,CHIPA':;

SECTION_NUMBER 1
 '@S9S_MB_2U_LIB.S9S_MB_2U(SCH_1):PAGE185_I50@PURE_QUANTA.Q_RES(CHIPS)':
 C_PATH='@s9s_mb_2u_lib.s9s_mb_2u(sch_1):page185_i50@pure_quanta.q_res(chips)',
 P_PATH='@s9s_mb_2u_lib.s9s_mb_2u(sch_1):page197_i50@pure_quanta.q_res(chips)',
 PATH='I50',
 DRAWING='@S9S_MB_2U_LIB.S9S_MB_2U(SCH_1):PAGE185',
 PHYS_PAGE='197',
 XY='(-7550,3050)',
 ROT='0',
 VER='2',
 PACK_TYPE='0402LF',
 LOCATION='R147',
 CDS_LIB='pure_quanta',
 CDS_PART_NAME='Q_RES_0402LF-10K,1%,1/16W,CHIPA',
 WATTAGE='1/16W',
 TOLERANCE='1%',
 MATERIAL='CHIP',
 VALUE='10K',
 PRIM_FILE='./archive_libs/logical/q_res/chips/chips.prt';

PART_NAME
 R148 'Q_RES_0402LF-10K,1%,1/16W,EMPTA':;

SECTION_NUMBER 1
 '@S9S_MB_2U_LIB.S9S_MB_2U(SCH_1):PAGE185_I49@PURE_QUANTA.Q_RES(CHIPS)':
 C_PATH='@s9s_mb_2u_lib.s9s_mb_2u(sch_1):page185_i49@pure_quanta.q_res(chips)',
 P_PATH='@s9s_mb_2u_lib.s9s_mb_2u(sch_1):page197_i49@pure_quanta.q_res(chips)',
 PATH='I49',
 DRAWING='@S9S_MB_2U_LIB.S9S_MB_2U(SCH_1):PAGE185',
 PHYS_PAGE='197',
 XY='(-7525,4375)',
 ROT='0',
 VER='2',
 PACK_TYPE='0402LF',
 LOCATION='R148',
 CDS_LIB='pure_quanta',
 CDS_PART_NAME='Q_RES_0402LF-10K,1%,1/16W,EMPTA',
 WATTAGE='1/16W',
 TOLERANCE='1%',
 MATERIAL='EMPTY',
 VALUE='10K',
 PRIM_FILE='./archive_libs/logical/q_res/chips/chips.prt';

PART_NAME
 R149 'Q_RES_0402LF-0,5%,1/16W,CHIP,CA':;

SECTION_NUMBER 1
 '@S9S_MB_2U_LIB.S9S_MB_2U(SCH_1):PAGE185_I24@PURE_QUANTA.Q_RES(CHIPS)':
 C_PATH='@s9s_mb_2u_lib.s9s_mb_2u(sch_1):page185_i24@pure_quanta.q_res(chips)',
 P_PATH='@s9s_mb_2u_lib.s9s_mb_2u(sch_1):page197_i24@pure_quanta.q_res(chips)',
 PATH='I24',
 DRAWING='@S9S_MB_2U_LIB.S9S_MB_2U(SCH_1):PAGE185',
 PHYS_PAGE='197',
 XY='(-7075,3300)',
 ROT='0',
 VER='1',
 PACK_TYPE='0402LF',
 CDS_LIB='pure_quanta',
 CDS_PART_NAME='Q_RES_0402LF-0,5%,1/16W,CHIP,CA',
 WATTAGE='1/16W',
 TOLERANCE='5%',
 MATERIAL='CHIP',
 VALUE='0',
 PRIM_FILE='./archive_libs/logical/q_res/chips/chips.prt';

PART_NAME
 R151 'Q_RES_0402LF-100,1%,1/16W,CHIPA':;

SECTION_NUMBER 1
 '@S9S_MB_2U_LIB.S9S_MB_2U(SCH_1):PAGE125_I58@PURE_QUANTA.Q_RES(CHIPS)':
 C_PATH='@s9s_mb_2u_lib.s9s_mb_2u(sch_1):page125_i58@pure_quanta.q_res(chips)',
 P_PATH='@s9s_mb_2u_lib.s9s_mb_2u(sch_1):page125_i58@pure_quanta.q_res(chips)',
 PATH='I58',
 DRAWING='@S9S_MB_2U_LIB.S9S_MB_2U(SCH_1):PAGE125',
 PHYS_PAGE='125',
 XY='(-1100,1775)',
 ROT='0',
 VER='1',
 PACK_TYPE='0402LF',
 CDS_LIB='pure_quanta',
 CDS_PART_NAME='Q_RES_0402LF-100,1%,1/16W,CHIPA',
 WATTAGE='1/16W',
 TOLERANCE='1%',
 MATERIAL='CHIP',
 VALUE='100',
 PRIM_FILE='./archive_libs/logical/q_res/chips/chips.prt';

PART_NAME
 R153 'Q_RES_0402LF-100,1%,1/16W,CHIPA':;

SECTION_NUMBER 1
 '@S9S_MB_2U_LIB.S9S_MB_2U(SCH_1):PAGE125_I56@PURE_QUANTA.Q_RES(CHIPS)':
 C_PATH='@s9s_mb_2u_lib.s9s_mb_2u(sch_1):page125_i56@pure_quanta.q_res(chips)',
 P_PATH='@s9s_mb_2u_lib.s9s_mb_2u(sch_1):page125_i56@pure_quanta.q_res(chips)',
 PATH='I56',
 DRAWING='@S9S_MB_2U_LIB.S9S_MB_2U(SCH_1):PAGE125',
 PHYS_PAGE='125',
 XY='(-1100,950)',
 ROT='0',
 VER='1',
 PACK_TYPE='0402LF',
 CDS_LIB='pure_quanta',
 CDS_PART_NAME='Q_RES_0402LF-100,1%,1/16W,CHIPA',
 WATTAGE='1/16W',
 TOLERANCE='1%',
 MATERIAL='CHIP',
 VALUE='100',
 PRIM_FILE='./archive_libs/logical/q_res/chips/chips.prt';

PART_NAME
 R155 'Q_RES_0402LF-100,1%,1/16W,CHIPA':;

SECTION_NUMBER 1
 '@S9S_MB_2U_LIB.S9S_MB_2U(SCH_1):PAGE125_I26@PURE_QUANTA.Q_RES(CHIPS)':
 C_PATH='@s9s_mb_2u_lib.s9s_mb_2u(sch_1):page125_i26@pure_quanta.q_res(chips)',
 P_PATH='@s9s_mb_2u_lib.s9s_mb_2u(sch_1):page125_i26@pure_quanta.q_res(chips)',
 PATH='I26',
 DRAWING='@S9S_MB_2U_LIB.S9S_MB_2U(SCH_1):PAGE125',
 PHYS_PAGE='125',
 XY='(-1125,125)',
 ROT='0',
 VER='1',
 PACK_TYPE='0402LF',
 CDS_LIB='pure_quanta',
 CDS_PART_NAME='Q_RES_0402LF-100,1%,1/16W,CHIPA',
 WATTAGE='1/16W',
 TOLERANCE='1%',
 MATERIAL='CHIP',
 VALUE='100',
 PRIM_FILE='./archive_libs/logical/q_res/chips/chips.prt';

PART_NAME
 R156 'Q_RES_0402LF-100,1%,1/16W,CHIPA':;

SECTION_NUMBER 1
 '@S9S_MB_2U_LIB.S9S_MB_2U(SCH_1):PAGE125_I64@PURE_QUANTA.Q_RES(CHIPS)':
 C_PATH='@s9s_mb_2u_lib.s9s_mb_2u(sch_1):page125_i64@pure_quanta.q_res(chips)',
 P_PATH='@s9s_mb_2u_lib.s9s_mb_2u(sch_1):page125_i64@pure_quanta.q_res(chips)',
 PATH='I64',
 DRAWING='@S9S_MB_2U_LIB.S9S_MB_2U(SCH_1):PAGE125',
 PHYS_PAGE='125',
 XY='(-1125,-50)',
 ROT='0',
 VER='1',
 PACK_TYPE='0402LF',
 LOCATION='R156',
 CDS_LIB='pure_quanta',
 CDS_PART_NAME='Q_RES_0402LF-100,1%,1/16W,CHIPA',
 WATTAGE='1/16W',
 TOLERANCE='1%',
 MATERIAL='CHIP',
 VALUE='100',
 PRIM_FILE='./archive_libs/logical/q_res/chips/chips.prt';

PART_NAME
 R157 'Q_RES_0402LF-100,1%,1/16W,CHIPA':;

SECTION_NUMBER 1
 '@S9S_MB_2U_LIB.S9S_MB_2U(SCH_1):PAGE125_I24@PURE_QUANTA.Q_RES(CHIPS)':
 C_PATH='@s9s_mb_2u_lib.s9s_mb_2u(sch_1):page125_i24@pure_quanta.q_res(chips)',
 P_PATH='@s9s_mb_2u_lib.s9s_mb_2u(sch_1):page125_i24@pure_quanta.q_res(chips)',
 PATH='I24',
 DRAWING='@S9S_MB_2U_LIB.S9S_MB_2U(SCH_1):PAGE125',
 PHYS_PAGE='125',
 XY='(-1125,-725)',
 ROT='0',
 VER='1',
 PACK_TYPE='0402LF',
 CDS_LIB='pure_quanta',
 CDS_PART_NAME='Q_RES_0402LF-100,1%,1/16W,CHIPA',
 WATTAGE='1/16W',
 TOLERANCE='1%',
 MATERIAL='CHIP',
 VALUE='100',
 PRIM_FILE='./archive_libs/logical/q_res/chips/chips.prt';

PART_NAME
 R158 'Q_RES_0402LF-100,1%,1/16W,CHIPA':;

SECTION_NUMBER 1
 '@S9S_MB_2U_LIB.S9S_MB_2U(SCH_1):PAGE125_I65@PURE_QUANTA.Q_RES(CHIPS)':
 C_PATH='@s9s_mb_2u_lib.s9s_mb_2u(sch_1):page125_i65@pure_quanta.q_res(chips)',
 P_PATH='@s9s_mb_2u_lib.s9s_mb_2u(sch_1):page125_i65@pure_quanta.q_res(chips)',
 PATH='I65',
 DRAWING='@S9S_MB_2U_LIB.S9S_MB_2U(SCH_1):PAGE125',
 PHYS_PAGE='125',
 XY='(-1125,-900)',
 ROT='0',
 VER='1',
 PACK_TYPE='0402LF',
 LOCATION='R158',
 CDS_LIB='pure_quanta',
 CDS_PART_NAME='Q_RES_0402LF-100,1%,1/16W,CHIPA',
 WATTAGE='1/16W',
 TOLERANCE='1%',
 MATERIAL='CHIP',
 VALUE='100',
 PRIM_FILE='./archive_libs/logical/q_res/chips/chips.prt';

PART_NAME
 R160 'Q_RES_0402LF-0,5%,1/16W,CHIP,CA':;

SECTION_NUMBER 1
 '@S9S_MB_2U_LIB.S9S_MB_2U(SCH_1):PAGE124_I17@PURE_QUANTA.Q_RES(CHIPS)':
 C_PATH='@s9s_mb_2u_lib.s9s_mb_2u(sch_1):page124_i17@pure_quanta.q_res(chips)',
 P_PATH='@s9s_mb_2u_lib.s9s_mb_2u(sch_1):page124_i17@pure_quanta.q_res(chips)',
 PATH='I17',
 DRAWING='@S9S_MB_2U_LIB.S9S_MB_2U(SCH_1):PAGE124',
 PHYS_PAGE='124',
 XY='(-550,2800)',
 ROT='0',
 VER='1',
 PACK_TYPE='0402LF',
 CDS_LIB='pure_quanta',
 CDS_PART_NAME='Q_RES_0402LF-0,5%,1/16W,CHIP,CA',
 WATTAGE='1/16W',
 TOLERANCE='5%',
 MATERIAL='CHIP',
 VALUE='0',
 PRIM_FILE='./archive_libs/logical/q_res/chips/chips.prt';

PART_NAME
 R162 'Q_RES_0402LF-0,5%,1/16W,CHIP,CA':;

SECTION_NUMBER 1
 '@S9S_MB_2U_LIB.S9S_MB_2U(SCH_1):PAGE124_I19@PURE_QUANTA.Q_RES(CHIPS)':
 C_PATH='@s9s_mb_2u_lib.s9s_mb_2u(sch_1):page124_i19@pure_quanta.q_res(chips)',
 P_PATH='@s9s_mb_2u_lib.s9s_mb_2u(sch_1):page124_i19@pure_quanta.q_res(chips)',
 PATH='I19',
 DRAWING='@S9S_MB_2U_LIB.S9S_MB_2U(SCH_1):PAGE124',
 PHYS_PAGE='124',
 XY='(-550,1975)',
 ROT='0',
 VER='1',
 PACK_TYPE='0402LF',
 CDS_LIB='pure_quanta',
 CDS_PART_NAME='Q_RES_0402LF-0,5%,1/16W,CHIP,CA',
 WATTAGE='1/16W',
 TOLERANCE='5%',
 MATERIAL='CHIP',
 VALUE='0',
 PRIM_FILE='./archive_libs/logical/q_res/chips/chips.prt';

PART_NAME
 R164 'Q_RES_0402LF-0,5%,1/16W,CHIP,CA':;

SECTION_NUMBER 1
 '@S9S_MB_2U_LIB.S9S_MB_2U(SCH_1):PAGE124_I26@PURE_QUANTA.Q_RES(CHIPS)':
 C_PATH='@s9s_mb_2u_lib.s9s_mb_2u(sch_1):page124_i26@pure_quanta.q_res(chips)',
 P_PATH='@s9s_mb_2u_lib.s9s_mb_2u(sch_1):page124_i26@pure_quanta.q_res(chips)',
 PATH='I26',
 DRAWING='@S9S_MB_2U_LIB.S9S_MB_2U(SCH_1):PAGE124',
 PHYS_PAGE='124',
 XY='(-550,1125)',
 ROT='0',
 VER='1',
 PACK_TYPE='0402LF',
 CDS_LIB='pure_quanta',
 CDS_PART_NAME='Q_RES_0402LF-0,5%,1/16W,CHIP,CA',
 WATTAGE='1/16W',
 TOLERANCE='5%',
 MATERIAL='CHIP',
 VALUE='0',
 PRIM_FILE='./archive_libs/logical/q_res/chips/chips.prt';

PART_NAME
 R166 'Q_RES_0402LF-0,5%,1/16W,CHIP,CA':;

SECTION_NUMBER 1
 '@S9S_MB_2U_LIB.S9S_MB_2U(SCH_1):PAGE124_I33@PURE_QUANTA.Q_RES(CHIPS)':
 C_PATH='@s9s_mb_2u_lib.s9s_mb_2u(sch_1):page124_i33@pure_quanta.q_res(chips)',
 P_PATH='@s9s_mb_2u_lib.s9s_mb_2u(sch_1):page124_i33@pure_quanta.q_res(chips)',
 PATH='I33',
 DRAWING='@S9S_MB_2U_LIB.S9S_MB_2U(SCH_1):PAGE124',
 PHYS_PAGE='124',
 XY='(-550,300)',
 ROT='0',
 VER='1',
 PACK_TYPE='0402LF',
 CDS_LIB='pure_quanta',
 CDS_PART_NAME='Q_RES_0402LF-0,5%,1/16W,CHIP,CA',
 WATTAGE='1/16W',
 TOLERANCE='5%',
 MATERIAL='CHIP',
 VALUE='0',
 PRIM_FILE='./archive_libs/logical/q_res/chips/chips.prt';

PART_NAME
 R168 'Q_RES_0402LF-0,5%,1/16W,CHIP,CA':;

SECTION_NUMBER 1
 '@S9S_MB_2U_LIB.S9S_MB_2U(SCH_1):PAGE124_I43@PURE_QUANTA.Q_RES(CHIPS)':
 C_PATH='@s9s_mb_2u_lib.s9s_mb_2u(sch_1):page124_i43@pure_quanta.q_res(chips)',
 P_PATH='@s9s_mb_2u_lib.s9s_mb_2u(sch_1):page124_i43@pure_quanta.q_res(chips)',
 PATH='I43',
 DRAWING='@S9S_MB_2U_LIB.S9S_MB_2U(SCH_1):PAGE124',
 PHYS_PAGE='124',
 XY='(-550,-525)',
 ROT='0',
 VER='1',
 PACK_TYPE='0402LF',
 CDS_LIB='pure_quanta',
 CDS_PART_NAME='Q_RES_0402LF-0,5%,1/16W,CHIP,CA',
 WATTAGE='1/16W',
 TOLERANCE='5%',
 MATERIAL='CHIP',
 VALUE='0',
 PRIM_FILE='./archive_libs/logical/q_res/chips/chips.prt';

PART_NAME
 R171 'Q_RES_0402LF-0,5%,1/16W,CHIP,CA':;

SECTION_NUMBER 1
 '@S9S_MB_2U_LIB.S9S_MB_2U(SCH_1):PAGE124_I52@PURE_QUANTA.Q_RES(CHIPS)':
 C_PATH='@s9s_mb_2u_lib.s9s_mb_2u(sch_1):page124_i52@pure_quanta.q_res(chips)',
 P_PATH='@s9s_mb_2u_lib.s9s_mb_2u(sch_1):page124_i52@pure_quanta.q_res(chips)',
 PATH='I52',
 DRAWING='@S9S_MB_2U_LIB.S9S_MB_2U(SCH_1):PAGE124',
 PHYS_PAGE='124',
 XY='(-550,-1375)',
 ROT='0',
 VER='1',
 PACK_TYPE='0402LF',
 CDS_LIB='pure_quanta',
 CDS_PART_NAME='Q_RES_0402LF-0,5%,1/16W,CHIP,CA',
 WATTAGE='1/16W',
 TOLERANCE='5%',
 MATERIAL='CHIP',
 VALUE='0',
 PRIM_FILE='./archive_libs/logical/q_res/chips/chips.prt';

PART_NAME
 R175 'Q_RES_0402LF-100,1%,1/16W,CHIPA':;

SECTION_NUMBER 1
 '@S9S_MB_2U_LIB.S9S_MB_2U(SCH_1):PAGE124_I76@PURE_QUANTA.Q_RES(CHIPS)':
 C_PATH='@s9s_mb_2u_lib.s9s_mb_2u(sch_1):page124_i76@pure_quanta.q_res(chips)',
 P_PATH='@s9s_mb_2u_lib.s9s_mb_2u(sch_1):page124_i76@pure_quanta.q_res(chips)',
 PATH='I76',
 DRAWING='@S9S_MB_2U_LIB.S9S_MB_2U(SCH_1):PAGE124',
 PHYS_PAGE='124',
 XY='(3725,2975)',
 ROT='0',
 VER='1',
 PACK_TYPE='0402LF',
 LOCATION='R175',
 CDS_LIB='pure_quanta',
 CDS_PART_NAME='Q_RES_0402LF-100,1%,1/16W,CHIPA',
 WATTAGE='1/16W',
 TOLERANCE='1%',
 MATERIAL='CHIP',
 VALUE='100',
 PRIM_FILE='./archive_libs/logical/q_res/chips/chips.prt';

PART_NAME
 R177 'Q_RES_0402LF-100,1%,1/16W,CHIPA':;

SECTION_NUMBER 1
 '@S9S_MB_2U_LIB.S9S_MB_2U(SCH_1):PAGE124_I72@PURE_QUANTA.Q_RES(CHIPS)':
 C_PATH='@s9s_mb_2u_lib.s9s_mb_2u(sch_1):page124_i72@pure_quanta.q_res(chips)',
 P_PATH='@s9s_mb_2u_lib.s9s_mb_2u(sch_1):page124_i72@pure_quanta.q_res(chips)',
 PATH='I72',
 DRAWING='@S9S_MB_2U_LIB.S9S_MB_2U(SCH_1):PAGE124',
 PHYS_PAGE='124',
 XY='(3725,2150)',
 ROT='0',
 VER='1',
 PACK_TYPE='0402LF',
 CDS_LIB='pure_quanta',
 CDS_PART_NAME='Q_RES_0402LF-100,1%,1/16W,CHIPA',
 WATTAGE='1/16W',
 TOLERANCE='1%',
 MATERIAL='CHIP',
 VALUE='100',
 PRIM_FILE='./archive_libs/logical/q_res/chips/chips.prt';

PART_NAME
 R179 'Q_RES_0402LF-100,1%,1/16W,CHIPA':;

SECTION_NUMBER 1
 '@S9S_MB_2U_LIB.S9S_MB_2U(SCH_1):PAGE124_I70@PURE_QUANTA.Q_RES(CHIPS)':
 C_PATH='@s9s_mb_2u_lib.s9s_mb_2u(sch_1):page124_i70@pure_quanta.q_res(chips)',
 P_PATH='@s9s_mb_2u_lib.s9s_mb_2u(sch_1):page124_i70@pure_quanta.q_res(chips)',
 PATH='I70',
 DRAWING='@S9S_MB_2U_LIB.S9S_MB_2U(SCH_1):PAGE124',
 PHYS_PAGE='124',
 XY='(3725,1300)',
 ROT='0',
 VER='1',
 PACK_TYPE='0402LF',
 CDS_LIB='pure_quanta',
 CDS_PART_NAME='Q_RES_0402LF-100,1%,1/16W,CHIPA',
 WATTAGE='1/16W',
 TOLERANCE='1%',
 MATERIAL='CHIP',
 VALUE='100',
 PRIM_FILE='./archive_libs/logical/q_res/chips/chips.prt';

PART_NAME
 R181 'Q_RES_0402LF-100,1%,1/16W,CHIPA':;

SECTION_NUMBER 1
 '@S9S_MB_2U_LIB.S9S_MB_2U(SCH_1):PAGE124_I68@PURE_QUANTA.Q_RES(CHIPS)':
 C_PATH='@s9s_mb_2u_lib.s9s_mb_2u(sch_1):page124_i68@pure_quanta.q_res(chips)',
 P_PATH='@s9s_mb_2u_lib.s9s_mb_2u(sch_1):page124_i68@pure_quanta.q_res(chips)',
 PATH='I68',
 DRAWING='@S9S_MB_2U_LIB.S9S_MB_2U(SCH_1):PAGE124',
 PHYS_PAGE='124',
 XY='(3725,475)',
 ROT='0',
 VER='1',
 PACK_TYPE='0402LF',
 CDS_LIB='pure_quanta',
 CDS_PART_NAME='Q_RES_0402LF-100,1%,1/16W,CHIPA',
 WATTAGE='1/16W',
 TOLERANCE='1%',
 MATERIAL='CHIP',
 VALUE='100',
 PRIM_FILE='./archive_libs/logical/q_res/chips/chips.prt';

PART_NAME
 R183 'Q_RES_0402LF-100,1%,1/16W,CHIPA':;

SECTION_NUMBER 1
 '@S9S_MB_2U_LIB.S9S_MB_2U(SCH_1):PAGE124_I62@PURE_QUANTA.Q_RES(CHIPS)':
 C_PATH='@s9s_mb_2u_lib.s9s_mb_2u(sch_1):page124_i62@pure_quanta.q_res(chips)',
 P_PATH='@s9s_mb_2u_lib.s9s_mb_2u(sch_1):page124_i62@pure_quanta.q_res(chips)',
 PATH='I62',
 DRAWING='@S9S_MB_2U_LIB.S9S_MB_2U(SCH_1):PAGE124',
 PHYS_PAGE='124',
 XY='(3700,-350)',
 ROT='0',
 VER='1',
 PACK_TYPE='0402LF',
 CDS_LIB='pure_quanta',
 CDS_PART_NAME='Q_RES_0402LF-100,1%,1/16W,CHIPA',
 WATTAGE='1/16W',
 TOLERANCE='1%',
 MATERIAL='CHIP',
 VALUE='100',
 PRIM_FILE='./archive_libs/logical/q_res/chips/chips.prt';

PART_NAME
 R184 'Q_RES_0402LF-100,1%,1/16W,CHIPA':;

SECTION_NUMBER 1
 '@S9S_MB_2U_LIB.S9S_MB_2U(SCH_1):PAGE124_I77@PURE_QUANTA.Q_RES(CHIPS)':
 C_PATH='@s9s_mb_2u_lib.s9s_mb_2u(sch_1):page124_i77@pure_quanta.q_res(chips)',
 P_PATH='@s9s_mb_2u_lib.s9s_mb_2u(sch_1):page124_i77@pure_quanta.q_res(chips)',
 PATH='I77',
 DRAWING='@S9S_MB_2U_LIB.S9S_MB_2U(SCH_1):PAGE124',
 PHYS_PAGE='124',
 XY='(3700,-525)',
 ROT='0',
 VER='1',
 PACK_TYPE='0402LF',
 LOCATION='R184',
 CDS_LIB='pure_quanta',
 CDS_PART_NAME='Q_RES_0402LF-100,1%,1/16W,CHIPA',
 WATTAGE='1/16W',
 TOLERANCE='1%',
 MATERIAL='CHIP',
 VALUE='100',
 PRIM_FILE='./archive_libs/logical/q_res/chips/chips.prt';

PART_NAME
 R185 'Q_RES_0402LF-100,1%,1/16W,CHIPA':;

SECTION_NUMBER 1
 '@S9S_MB_2U_LIB.S9S_MB_2U(SCH_1):PAGE124_I60@PURE_QUANTA.Q_RES(CHIPS)':
 C_PATH='@s9s_mb_2u_lib.s9s_mb_2u(sch_1):page124_i60@pure_quanta.q_res(chips)',
 P_PATH='@s9s_mb_2u_lib.s9s_mb_2u(sch_1):page124_i60@pure_quanta.q_res(chips)',
 PATH='I60',
 DRAWING='@S9S_MB_2U_LIB.S9S_MB_2U(SCH_1):PAGE124',
 PHYS_PAGE='124',
 XY='(3700,-1200)',
 ROT='0',
 VER='1',
 PACK_TYPE='0402LF',
 CDS_LIB='pure_quanta',
 CDS_PART_NAME='Q_RES_0402LF-100,1%,1/16W,CHIPA',
 WATTAGE='1/16W',
 TOLERANCE='1%',
 MATERIAL='CHIP',
 VALUE='100',
 PRIM_FILE='./archive_libs/logical/q_res/chips/chips.prt';

PART_NAME
 R186 'Q_RES_0402LF-100,1%,1/16W,CHIPA':;

SECTION_NUMBER 1
 '@S9S_MB_2U_LIB.S9S_MB_2U(SCH_1):PAGE124_I78@PURE_QUANTA.Q_RES(CHIPS)':
 C_PATH='@s9s_mb_2u_lib.s9s_mb_2u(sch_1):page124_i78@pure_quanta.q_res(chips)',
 P_PATH='@s9s_mb_2u_lib.s9s_mb_2u(sch_1):page124_i78@pure_quanta.q_res(chips)',
 PATH='I78',
 DRAWING='@S9S_MB_2U_LIB.S9S_MB_2U(SCH_1):PAGE124',
 PHYS_PAGE='124',
 XY='(3700,-1375)',
 ROT='0',
 VER='1',
 PACK_TYPE='0402LF',
 LOCATION='R186',
 CDS_LIB='pure_quanta',
 CDS_PART_NAME='Q_RES_0402LF-100,1%,1/16W,CHIPA',
 WATTAGE='1/16W',
 TOLERANCE='1%',
 MATERIAL='CHIP',
 VALUE='100',
 PRIM_FILE='./archive_libs/logical/q_res/chips/chips.prt';

PART_NAME
 R188 'Q_RES_0402LF-0,5%,1/16W,CHIP,CA':;

SECTION_NUMBER 1
 '@S9S_MB_2U_LIB.S9S_MB_2U(SCH_1):PAGE123_I4@PURE_QUANTA.Q_RES(CHIPS)':
 C_PATH='@s9s_mb_2u_lib.s9s_mb_2u(sch_1):page123_i4@pure_quanta.q_res(chips)',
 P_PATH='@s9s_mb_2u_lib.s9s_mb_2u(sch_1):page123_i4@pure_quanta.q_res(chips)',
 PATH='I4',
 DRAWING='@S9S_MB_2U_LIB.S9S_MB_2U(SCH_1):PAGE123',
 PHYS_PAGE='123',
 XY='(-1875,-4925)',
 ROT='0',
 VER='1',
 PACK_TYPE='0402LF',
 CDS_LIB='pure_quanta',
 CDS_PART_NAME='Q_RES_0402LF-0,5%,1/16W,CHIP,CA',
 WATTAGE='1/16W',
 TOLERANCE='5%',
 MATERIAL='CHIP',
 VALUE='0',
 PRIM_FILE='./archive_libs/logical/q_res/chips/chips.prt';

PART_NAME
 R195 'Q_RES_0402LF-49.9,1%,1/16W,CHIA':;

SECTION_NUMBER 1
 '@S9S_MB_2U_LIB.S9S_MB_2U(SCH_1):PAGE123_I6@PURE_QUANTA.Q_RES(CHIPS)':
 C_PATH='@s9s_mb_2u_lib.s9s_mb_2u(sch_1):page123_i6@pure_quanta.q_res(chips)',
 P_PATH='@s9s_mb_2u_lib.s9s_mb_2u(sch_1):page123_i6@pure_quanta.q_res(chips)',
 PATH='I6',
 DRAWING='@S9S_MB_2U_LIB.S9S_MB_2U(SCH_1):PAGE123',
 PHYS_PAGE='123',
 XY='(-25,-4925)',
 ROT='0',
 VER='1',
 PACK_TYPE='0402LF',
 CDS_LIB='pure_quanta',
 CDS_PART_NAME='Q_RES_0402LF-49.9,1%,1/16W,CHIA',
 WATTAGE='1/16W',
 TOLERANCE='1%',
 MATERIAL='CHIP',
 VALUE='49.9',
 PRIM_FILE='./archive_libs/logical/q_res/chips/chips.prt';

PART_NAME
 R196 'Q_RES_0402LF-49.9,1%,1/16W,CHIA':;

SECTION_NUMBER 1
 '@S9S_MB_2U_LIB.S9S_MB_2U(SCH_1):PAGE123_I5@PURE_QUANTA.Q_RES(CHIPS)':
 C_PATH='@s9s_mb_2u_lib.s9s_mb_2u(sch_1):page123_i5@pure_quanta.q_res(chips)',
 P_PATH='@s9s_mb_2u_lib.s9s_mb_2u(sch_1):page123_i5@pure_quanta.q_res(chips)',
 PATH='I5',
 DRAWING='@S9S_MB_2U_LIB.S9S_MB_2U(SCH_1):PAGE123',
 PHYS_PAGE='123',
 XY='(-25,-5600)',
 ROT='0',
 VER='1',
 PACK_TYPE='0402LF',
 CDS_LIB='pure_quanta',
 CDS_PART_NAME='Q_RES_0402LF-49.9,1%,1/16W,CHIA',
 WATTAGE='1/16W',
 TOLERANCE='1%',
 MATERIAL='CHIP',
 VALUE='49.9',
 PRIM_FILE='./archive_libs/logical/q_res/chips/chips.prt';

PART_NAME
 R197 'Q_RES_0402LF-301,1%,1/16W,CHIPA':;

SECTION_NUMBER 1
 '@S9S_MB_2U_LIB.S9S_MB_2U(SCH_1):PAGE123_I27@PURE_QUANTA.Q_RES(CHIPS)':
 C_PATH='@s9s_mb_2u_lib.s9s_mb_2u(sch_1):page123_i27@pure_quanta.q_res(chips)',
 P_PATH='@s9s_mb_2u_lib.s9s_mb_2u(sch_1):page123_i27@pure_quanta.q_res(chips)',
 PATH='I27',
 DRAWING='@S9S_MB_2U_LIB.S9S_MB_2U(SCH_1):PAGE123',
 PHYS_PAGE='123',
 XY='(1025,-4675)',
 ROT='0',
 VER='2',
 PACK_TYPE='0402LF',
 LOCATION='R197',
 CDS_LIB='pure_quanta',
 CDS_PART_NAME='Q_RES_0402LF-301,1%,1/16W,CHIPA',
 WATTAGE='1/16W',
 TOLERANCE='1%',
 MATERIAL='CHIP',
 VALUE='301',
 PRIM_FILE='./archive_libs/logical/q_res/chips/chips.prt';

PART_NAME
 R198 'Q_RES_0402LF-301,1%,1/16W,CHIPA':;

SECTION_NUMBER 1
 '@S9S_MB_2U_LIB.S9S_MB_2U(SCH_1):PAGE123_I23@PURE_QUANTA.Q_RES(CHIPS)':
 C_PATH='@s9s_mb_2u_lib.s9s_mb_2u(sch_1):page123_i23@pure_quanta.q_res(chips)',
 P_PATH='@s9s_mb_2u_lib.s9s_mb_2u(sch_1):page123_i23@pure_quanta.q_res(chips)',
 PATH='I23',
 DRAWING='@S9S_MB_2U_LIB.S9S_MB_2U(SCH_1):PAGE123',
 PHYS_PAGE='123',
 XY='(1025,-5350)',
 ROT='0',
 VER='2',
 PACK_TYPE='0402LF',
 LOCATION='R198',
 CDS_LIB='pure_quanta',
 CDS_PART_NAME='Q_RES_0402LF-301,1%,1/16W,CHIPA',
 WATTAGE='1/16W',
 TOLERANCE='1%',
 MATERIAL='CHIP',
 VALUE='301',
 PRIM_FILE='./archive_libs/logical/q_res/chips/chips.prt';

PART_NAME
 R200 'Q_RES_0402LF-100,1%,1/16W,CHIPA':;

SECTION_NUMBER 1
 '@S9S_MB_2U_LIB.S9S_MB_2U(SCH_1):PAGE123_I19@PURE_QUANTA.Q_RES(CHIPS)':
 C_PATH='@s9s_mb_2u_lib.s9s_mb_2u(sch_1):page123_i19@pure_quanta.q_res(chips)',
 P_PATH='@s9s_mb_2u_lib.s9s_mb_2u(sch_1):page123_i19@pure_quanta.q_res(chips)',
 PATH='I19',
 DRAWING='@S9S_MB_2U_LIB.S9S_MB_2U(SCH_1):PAGE123',
 PHYS_PAGE='123',
 XY='(-3375,-500)',
 ROT='0',
 VER='2',
 PACK_TYPE='0402LF',
 LOCATION='R200',
 CDS_LIB='pure_quanta',
 CDS_PART_NAME='Q_RES_0402LF-100,1%,1/16W,CHIPA',
 WATTAGE='1/16W',
 TOLERANCE='1%',
 MATERIAL='CHIP',
 VALUE='100',
 PRIM_FILE='./archive_libs/logical/q_res/chips/chips.prt';

PART_NAME
 R202 'Q_RES_0402LF-100,1%,1/16W,CHIPA':;

SECTION_NUMBER 1
 '@S9S_MB_2U_LIB.S9S_MB_2U(SCH_1):PAGE123_I7@PURE_QUANTA.Q_RES(CHIPS)':
 C_PATH='@s9s_mb_2u_lib.s9s_mb_2u(sch_1):page123_i7@pure_quanta.q_res(chips)',
 P_PATH='@s9s_mb_2u_lib.s9s_mb_2u(sch_1):page123_i7@pure_quanta.q_res(chips)',
 PATH='I7',
 DRAWING='@S9S_MB_2U_LIB.S9S_MB_2U(SCH_1):PAGE123',
 PHYS_PAGE='123',
 XY='(-3375,-1850)',
 ROT='0',
 VER='2',
 PACK_TYPE='0402LF',
 LOCATION='R202',
 CDS_LIB='pure_quanta',
 CDS_PART_NAME='Q_RES_0402LF-100,1%,1/16W,CHIPA',
 WATTAGE='1/16W',
 TOLERANCE='1%',
 MATERIAL='CHIP',
 VALUE='100',
 PRIM_FILE='./archive_libs/logical/q_res/chips/chips.prt';

PART_NAME
 R203 'Q_RES_0402LF-1.5K,1%,1/16W,CHIA':;

SECTION_NUMBER 1
 '@S9S_MB_2U_LIB.S9S_MB_2U(SCH_1):PAGE122_I9@PURE_QUANTA.Q_RES(CHIPS)':
 C_PATH='@s9s_mb_2u_lib.s9s_mb_2u(sch_1):page122_i9@pure_quanta.q_res(chips)',
 P_PATH='@s9s_mb_2u_lib.s9s_mb_2u(sch_1):page122_i9@pure_quanta.q_res(chips)',
 PATH='I9',
 DRAWING='@S9S_MB_2U_LIB.S9S_MB_2U(SCH_1):PAGE122',
 PHYS_PAGE='122',
 XY='(-1650,2175)',
 ROT='0',
 VER='1',
 PACK_TYPE='0402LF',
 LOCATION='R203',
 CDS_LIB='pure_quanta',
 CDS_PART_NAME='Q_RES_0402LF-1.5K,1%,1/16W,CHIA',
 WATTAGE='1/16W',
 TOLERANCE='1%',
 MATERIAL='CHIP',
 VALUE='1.5K',
 PRIM_FILE='./archive_libs/logical/q_res/chips/chips.prt';

PART_NAME
 R204 'Q_RES_0402LF-1.5K,1%,1/16W,CHIA':;

SECTION_NUMBER 1
 '@S9S_MB_2U_LIB.S9S_MB_2U(SCH_1):PAGE122_I6@PURE_QUANTA.Q_RES(CHIPS)':
 C_PATH='@s9s_mb_2u_lib.s9s_mb_2u(sch_1):page122_i6@pure_quanta.q_res(chips)',
 P_PATH='@s9s_mb_2u_lib.s9s_mb_2u(sch_1):page122_i6@pure_quanta.q_res(chips)',
 PATH='I6',
 DRAWING='@S9S_MB_2U_LIB.S9S_MB_2U(SCH_1):PAGE122',
 PHYS_PAGE='122',
 XY='(-1650,825)',
 ROT='0',
 VER='1',
 PACK_TYPE='0402LF',
 LOCATION='R204',
 CDS_LIB='pure_quanta',
 CDS_PART_NAME='Q_RES_0402LF-1.5K,1%,1/16W,CHIA',
 WATTAGE='1/16W',
 TOLERANCE='1%',
 MATERIAL='CHIP',
 VALUE='1.5K',
 PRIM_FILE='./archive_libs/logical/q_res/chips/chips.prt';

PART_NAME
 R205 'Q_RES_0402LF-1.5K,1%,1/16W,CHIA':;

SECTION_NUMBER 1
 '@S9S_MB_2U_LIB.S9S_MB_2U(SCH_1):PAGE123_I10@PURE_QUANTA.Q_RES(CHIPS)':
 C_PATH='@s9s_mb_2u_lib.s9s_mb_2u(sch_1):page123_i10@pure_quanta.q_res(chips)',
 P_PATH='@s9s_mb_2u_lib.s9s_mb_2u(sch_1):page123_i10@pure_quanta.q_res(chips)',
 PATH='I10',
 DRAWING='@S9S_MB_2U_LIB.S9S_MB_2U(SCH_1):PAGE123',
 PHYS_PAGE='123',
 XY='(-3025,-775)',
 ROT='0',
 VER='1',
 PACK_TYPE='0402LF',
 LOCATION='R205',
 CDS_LIB='pure_quanta',
 CDS_PART_NAME='Q_RES_0402LF-1.5K,1%,1/16W,CHIA',
 WATTAGE='1/16W',
 TOLERANCE='1%',
 MATERIAL='CHIP',
 VALUE='1.5K',
 PRIM_FILE='./archive_libs/logical/q_res/chips/chips.prt';

PART_NAME
 R206 'Q_RES_0402LF-1.5K,1%,1/16W,CHIA':;

SECTION_NUMBER 1
 '@S9S_MB_2U_LIB.S9S_MB_2U(SCH_1):PAGE123_I8@PURE_QUANTA.Q_RES(CHIPS)':
 C_PATH='@s9s_mb_2u_lib.s9s_mb_2u(sch_1):page123_i8@pure_quanta.q_res(chips)',
 P_PATH='@s9s_mb_2u_lib.s9s_mb_2u(sch_1):page123_i8@pure_quanta.q_res(chips)',
 PATH='I8',
 DRAWING='@S9S_MB_2U_LIB.S9S_MB_2U(SCH_1):PAGE123',
 PHYS_PAGE='123',
 XY='(-3025,-2125)',
 ROT='0',
 VER='1',
 PACK_TYPE='0402LF',
 LOCATION='R206',
 CDS_LIB='pure_quanta',
 CDS_PART_NAME='Q_RES_0402LF-1.5K,1%,1/16W,CHIA',
 WATTAGE='1/16W',
 TOLERANCE='1%',
 MATERIAL='CHIP',
 VALUE='1.5K',
 PRIM_FILE='./archive_libs/logical/q_res/chips/chips.prt';

PART_NAME
 R208 'Q_RES_0402LF-0,5%,1/16W,CHIP,CA':;

SECTION_NUMBER 1
 '@S9S_MB_2U_LIB.S9S_MB_2U(SCH_1):PAGE122_I16@PURE_QUANTA.Q_RES(CHIPS)':
 C_PATH='@s9s_mb_2u_lib.s9s_mb_2u(sch_1):page122_i16@pure_quanta.q_res(chips)',
 P_PATH='@s9s_mb_2u_lib.s9s_mb_2u(sch_1):page122_i16@pure_quanta.q_res(chips)',
 PATH='I16',
 DRAWING='@S9S_MB_2U_LIB.S9S_MB_2U(SCH_1):PAGE122',
 PHYS_PAGE='122',
 XY='(-1475,4350)',
 ROT='0',
 VER='1',
 PACK_TYPE='0402LF',
 CDS_LIB='pure_quanta',
 CDS_PART_NAME='Q_RES_0402LF-0,5%,1/16W,CHIP,CA',
 WATTAGE='1/16W',
 TOLERANCE='5%',
 MATERIAL='CHIP',
 VALUE='0',
 PRIM_FILE='./archive_libs/logical/q_res/chips/chips.prt';

PART_NAME
 R210 'Q_RES_0402LF-0,5%,1/16W,CHIP,CA':;

SECTION_NUMBER 1
 '@S9S_MB_2U_LIB.S9S_MB_2U(SCH_1):PAGE122_I15@PURE_QUANTA.Q_RES(CHIPS)':
 C_PATH='@s9s_mb_2u_lib.s9s_mb_2u(sch_1):page122_i15@pure_quanta.q_res(chips)',
 P_PATH='@s9s_mb_2u_lib.s9s_mb_2u(sch_1):page122_i15@pure_quanta.q_res(chips)',
 PATH='I15',
 DRAWING='@S9S_MB_2U_LIB.S9S_MB_2U(SCH_1):PAGE122',
 PHYS_PAGE='122',
 XY='(-1475,3400)',
 ROT='0',
 VER='1',
 PACK_TYPE='0402LF',
 CDS_LIB='pure_quanta',
 CDS_PART_NAME='Q_RES_0402LF-0,5%,1/16W,CHIP,CA',
 WATTAGE='1/16W',
 TOLERANCE='5%',
 MATERIAL='CHIP',
 VALUE='0',
 PRIM_FILE='./archive_libs/logical/q_res/chips/chips.prt';

PART_NAME
 R219 'Q_RES_0402LF-100,1%,1/16W,CHIPA':;

SECTION_NUMBER 1
 '@S9S_MB_2U_LIB.S9S_MB_2U(SCH_1):PAGE122_I37@PURE_QUANTA.Q_RES(CHIPS)':
 C_PATH='@s9s_mb_2u_lib.s9s_mb_2u(sch_1):page122_i37@pure_quanta.q_res(chips)',
 P_PATH='@s9s_mb_2u_lib.s9s_mb_2u(sch_1):page122_i37@pure_quanta.q_res(chips)',
 PATH='I37',
 DRAWING='@S9S_MB_2U_LIB.S9S_MB_2U(SCH_1):PAGE122',
 PHYS_PAGE='122',
 XY='(1175,4700)',
 ROT='0',
 VER='2',
 PACK_TYPE='0402LF',
 CDS_LIB='pure_quanta',
 CDS_PART_NAME='Q_RES_0402LF-100,1%,1/16W,CHIPA',
 WATTAGE='1/16W',
 TOLERANCE='1%',
 MATERIAL='CHIP',
 VALUE='100',
 PRIM_FILE='./archive_libs/logical/q_res/chips/chips.prt';

PART_NAME
 R220 'Q_RES_0402LF-100,1%,1/16W,CHIPA':;

SECTION_NUMBER 1
 '@S9S_MB_2U_LIB.S9S_MB_2U(SCH_1):PAGE122_I29@PURE_QUANTA.Q_RES(CHIPS)':
 C_PATH='@s9s_mb_2u_lib.s9s_mb_2u(sch_1):page122_i29@pure_quanta.q_res(chips)',
 P_PATH='@s9s_mb_2u_lib.s9s_mb_2u(sch_1):page122_i29@pure_quanta.q_res(chips)',
 PATH='I29',
 DRAWING='@S9S_MB_2U_LIB.S9S_MB_2U(SCH_1):PAGE122',
 PHYS_PAGE='122',
 XY='(1175,3750)',
 ROT='0',
 VER='2',
 PACK_TYPE='0402LF',
 CDS_LIB='pure_quanta',
 CDS_PART_NAME='Q_RES_0402LF-100,1%,1/16W,CHIPA',
 WATTAGE='1/16W',
 TOLERANCE='1%',
 MATERIAL='CHIP',
 VALUE='100',
 PRIM_FILE='./archive_libs/logical/q_res/chips/chips.prt';

PART_NAME
 R223 'Q_RES_0402LF-1K,1%,1/16W,CHIP,A':;

SECTION_NUMBER 1
 '@S9S_MB_2U_LIB.S9S_MB_2U(SCH_1):PAGE282_I85@PURE_QUANTA.Q_RES(CHIPS)':
 C_PATH='@s9s_mb_2u_lib.s9s_mb_2u(sch_1):page282_i85@pure_quanta.q_res(chips)',
 P_PATH='@s9s_mb_2u_lib.s9s_mb_2u(sch_1):page296_i85@pure_quanta.q_res(chips)',
 PATH='I85',
 DRAWING='@S9S_MB_2U_LIB.S9S_MB_2U(SCH_1):PAGE282',
 PHYS_PAGE='296',
 XY='(100,1225)',
 ROT='0',
 VER='2',
 PACK_TYPE='0402LF',
 LOCATION='R223',
 CDS_LIB='pure_quanta',
 CDS_PART_NAME='Q_RES_0402LF-1K,1%,1/16W,CHIP,A',
 WATTAGE='1/16W',
 TOLERANCE='1%',
 MATERIAL='CHIP',
 VALUE='1K',
 PRIM_FILE='./archive_libs/logical/q_res/chips/chips.prt';

PART_NAME
 R237 'Q_RES_0402LF-1.5K,1%,1/16W,CHIA':;

SECTION_NUMBER 1
 '@S9S_MB_2U_LIB.S9S_MB_2U(SCH_1):PAGE121_I15@PURE_QUANTA.Q_RES(CHIPS)':
 C_PATH='@s9s_mb_2u_lib.s9s_mb_2u(sch_1):page121_i15@pure_quanta.q_res(chips)',
 P_PATH='@s9s_mb_2u_lib.s9s_mb_2u(sch_1):page121_i15@pure_quanta.q_res(chips)',
 PATH='I15',
 DRAWING='@S9S_MB_2U_LIB.S9S_MB_2U(SCH_1):PAGE121',
 PHYS_PAGE='121',
 XY='(-1650,2200)',
 ROT='0',
 VER='1',
 PACK_TYPE='0402LF',
 LOCATION='R237',
 CDS_LIB='pure_quanta',
 CDS_PART_NAME='Q_RES_0402LF-1.5K,1%,1/16W,CHIA',
 WATTAGE='1/16W',
 TOLERANCE='1%',
 MATERIAL='CHIP',
 VALUE='1.5K',
 PRIM_FILE='./archive_libs/logical/q_res/chips/chips.prt';

PART_NAME
 R238 'Q_RES_0402LF-1.5K,1%,1/16W,CHIA':;

SECTION_NUMBER 1
 '@S9S_MB_2U_LIB.S9S_MB_2U(SCH_1):PAGE121_I6@PURE_QUANTA.Q_RES(CHIPS)':
 C_PATH='@s9s_mb_2u_lib.s9s_mb_2u(sch_1):page121_i6@pure_quanta.q_res(chips)',
 P_PATH='@s9s_mb_2u_lib.s9s_mb_2u(sch_1):page121_i6@pure_quanta.q_res(chips)',
 PATH='I6',
 DRAWING='@S9S_MB_2U_LIB.S9S_MB_2U(SCH_1):PAGE121',
 PHYS_PAGE='121',
 XY='(-1650,850)',
 ROT='0',
 VER='1',
 PACK_TYPE='0402LF',
 LOCATION='R238',
 CDS_LIB='pure_quanta',
 CDS_PART_NAME='Q_RES_0402LF-1.5K,1%,1/16W,CHIA',
 WATTAGE='1/16W',
 TOLERANCE='1%',
 MATERIAL='CHIP',
 VALUE='1.5K',
 PRIM_FILE='./archive_libs/logical/q_res/chips/chips.prt';

PART_NAME
 R239 'Q_RES_0402LF-0,5%,1/16W,CHIP,CA':;

SECTION_NUMBER 1
 '@S9S_MB_2U_LIB.S9S_MB_2U(SCH_1):PAGE121_I7@PURE_QUANTA.Q_RES(CHIPS)':
 C_PATH='@s9s_mb_2u_lib.s9s_mb_2u(sch_1):page121_i7@pure_quanta.q_res(chips)',
 P_PATH='@s9s_mb_2u_lib.s9s_mb_2u(sch_1):page121_i7@pure_quanta.q_res(chips)',
 PATH='I7',
 DRAWING='@S9S_MB_2U_LIB.S9S_MB_2U(SCH_1):PAGE121',
 PHYS_PAGE='121',
 XY='(-725,-575)',
 ROT='0',
 VER='1',
 PACK_TYPE='0402LF',
 CDS_LIB='pure_quanta',
 CDS_PART_NAME='Q_RES_0402LF-0,5%,1/16W,CHIP,CA',
 WATTAGE='1/16W',
 TOLERANCE='5%',
 MATERIAL='CHIP',
 VALUE='0',
 PRIM_FILE='./archive_libs/logical/q_res/chips/chips.prt';

PART_NAME
 R240 'Q_RES_0402LF-0,5%,1/16W,CHIP,CA':;

SECTION_NUMBER 1
 '@S9S_MB_2U_LIB.S9S_MB_2U(SCH_1):PAGE121_I5@PURE_QUANTA.Q_RES(CHIPS)':
 C_PATH='@s9s_mb_2u_lib.s9s_mb_2u(sch_1):page121_i5@pure_quanta.q_res(chips)',
 P_PATH='@s9s_mb_2u_lib.s9s_mb_2u(sch_1):page121_i5@pure_quanta.q_res(chips)',
 PATH='I5',
 DRAWING='@S9S_MB_2U_LIB.S9S_MB_2U(SCH_1):PAGE121',
 PHYS_PAGE='121',
 XY='(-725,-1475)',
 ROT='0',
 VER='1',
 PACK_TYPE='0402LF',
 CDS_LIB='pure_quanta',
 CDS_PART_NAME='Q_RES_0402LF-0,5%,1/16W,CHIP,CA',
 WATTAGE='1/16W',
 TOLERANCE='5%',
 MATERIAL='CHIP',
 VALUE='0',
 PRIM_FILE='./archive_libs/logical/q_res/chips/chips.prt';

PART_NAME
 R241 'Q_RES_0402LF-4.75K,1%,1/16W,CHA':;

SECTION_NUMBER 1
 '@S9S_MB_2U_LIB.S9S_MB_2U(SCH_1):PAGE121_I33@PURE_QUANTA.Q_RES(CHIPS)':
 C_PATH='@s9s_mb_2u_lib.s9s_mb_2u(sch_1):page121_i33@pure_quanta.q_res(chips)',
 P_PATH='@s9s_mb_2u_lib.s9s_mb_2u(sch_1):page121_i33@pure_quanta.q_res(chips)',
 PATH='I33',
 DRAWING='@S9S_MB_2U_LIB.S9S_MB_2U(SCH_1):PAGE121',
 PHYS_PAGE='121',
 XY='(1725,2100)',
 ROT='0',
 VER='2',
 PACK_TYPE='0402LF',
 CDS_LIB='pure_quanta',
 CDS_PART_NAME='Q_RES_0402LF-4.75K,1%,1/16W,CHA',
 WATTAGE='1/16W',
 TOLERANCE='1%',
 MATERIAL='CHIP',
 VALUE='4.75K',
 PRIM_FILE='./archive_libs/logical/q_res/chips/chips.prt';

PART_NAME
 R242 'Q_RES_0402LF-4.75K,1%,1/16W,CHA':;

SECTION_NUMBER 1
 '@S9S_MB_2U_LIB.S9S_MB_2U(SCH_1):PAGE121_I26@PURE_QUANTA.Q_RES(CHIPS)':
 C_PATH='@s9s_mb_2u_lib.s9s_mb_2u(sch_1):page121_i26@pure_quanta.q_res(chips)',
 P_PATH='@s9s_mb_2u_lib.s9s_mb_2u(sch_1):page121_i26@pure_quanta.q_res(chips)',
 PATH='I26',
 DRAWING='@S9S_MB_2U_LIB.S9S_MB_2U(SCH_1):PAGE121',
 PHYS_PAGE='121',
 XY='(1725,750)',
 ROT='0',
 VER='2',
 PACK_TYPE='0402LF',
 LOCATION='R242',
 CDS_LIB='pure_quanta',
 CDS_PART_NAME='Q_RES_0402LF-4.75K,1%,1/16W,CHA',
 WATTAGE='1/16W',
 TOLERANCE='1%',
 MATERIAL='CHIP',
 VALUE='4.75K',
 PRIM_FILE='./archive_libs/logical/q_res/chips/chips.prt';

PART_NAME
 R243 'Q_RES_0402LF-100,1%,1/16W,CHIPA':;

SECTION_NUMBER 1
 '@S9S_MB_2U_LIB.S9S_MB_2U(SCH_1):PAGE121_I23@PURE_QUANTA.Q_RES(CHIPS)':
 C_PATH='@s9s_mb_2u_lib.s9s_mb_2u(sch_1):page121_i23@pure_quanta.q_res(chips)',
 P_PATH='@s9s_mb_2u_lib.s9s_mb_2u(sch_1):page121_i23@pure_quanta.q_res(chips)',
 PATH='I23',
 DRAWING='@S9S_MB_2U_LIB.S9S_MB_2U(SCH_1):PAGE121',
 PHYS_PAGE='121',
 XY='(1450,-325)',
 ROT='0',
 VER='2',
 PACK_TYPE='0402LF',
 CDS_LIB='pure_quanta',
 CDS_PART_NAME='Q_RES_0402LF-100,1%,1/16W,CHIPA',
 WATTAGE='1/16W',
 TOLERANCE='1%',
 MATERIAL='CHIP',
 VALUE='100',
 PRIM_FILE='./archive_libs/logical/q_res/chips/chips.prt';

PART_NAME
 R244 'Q_RES_0402LF-100,1%,1/16W,CHIPA':;

SECTION_NUMBER 1
 '@S9S_MB_2U_LIB.S9S_MB_2U(SCH_1):PAGE121_I19@PURE_QUANTA.Q_RES(CHIPS)':
 C_PATH='@s9s_mb_2u_lib.s9s_mb_2u(sch_1):page121_i19@pure_quanta.q_res(chips)',
 P_PATH='@s9s_mb_2u_lib.s9s_mb_2u(sch_1):page121_i19@pure_quanta.q_res(chips)',
 PATH='I19',
 DRAWING='@S9S_MB_2U_LIB.S9S_MB_2U(SCH_1):PAGE121',
 PHYS_PAGE='121',
 XY='(1450,-1225)',
 ROT='0',
 VER='2',
 PACK_TYPE='0402LF',
 CDS_LIB='pure_quanta',
 CDS_PART_NAME='Q_RES_0402LF-100,1%,1/16W,CHIPA',
 WATTAGE='1/16W',
 TOLERANCE='1%',
 MATERIAL='CHIP',
 VALUE='100',
 PRIM_FILE='./archive_libs/logical/q_res/chips/chips.prt';

PART_NAME
 R249 'Q_RES_0402LF-240,1%,1/16W,EMPTA':;

SECTION_NUMBER 1
 '@S9S_MB_2U_LIB.S9S_MB_2U(SCH_1):PAGE120_I27@PURE_QUANTA.Q_RES(CHIPS)':
 C_PATH='@s9s_mb_2u_lib.s9s_mb_2u(sch_1):page120_i27@pure_quanta.q_res(chips)',
 P_PATH='@s9s_mb_2u_lib.s9s_mb_2u(sch_1):page120_i27@pure_quanta.q_res(chips)',
 PATH='I27',
 DRAWING='@S9S_MB_2U_LIB.S9S_MB_2U(SCH_1):PAGE120',
 PHYS_PAGE='120',
 XY='(-2000,3400)',
 ROT='0',
 VER='1',
 PACK_TYPE='0402LF',
 CDS_LIB='pure_quanta',
 CDS_PART_NAME='Q_RES_0402LF-240,1%,1/16W,EMPTA',
 WATTAGE='1/16W',
 TOLERANCE='1%',
 MATERIAL='EMPTY',
 VALUE='240',
 PRIM_FILE='./archive_libs/logical/q_res/chips/chips.prt';

PART_NAME
 R250 'Q_RES_0402LF-240,1%,1/16W,EMPTA':;

SECTION_NUMBER 1
 '@S9S_MB_2U_LIB.S9S_MB_2U(SCH_1):PAGE120_I29@PURE_QUANTA.Q_RES(CHIPS)':
 C_PATH='@s9s_mb_2u_lib.s9s_mb_2u(sch_1):page120_i29@pure_quanta.q_res(chips)',
 P_PATH='@s9s_mb_2u_lib.s9s_mb_2u(sch_1):page120_i29@pure_quanta.q_res(chips)',
 PATH='I29',
 DRAWING='@S9S_MB_2U_LIB.S9S_MB_2U(SCH_1):PAGE120',
 PHYS_PAGE='120',
 XY='(-2000,3275)',
 ROT='0',
 VER='1',
 PACK_TYPE='0402LF',
 CDS_LIB='pure_quanta',
 CDS_PART_NAME='Q_RES_0402LF-240,1%,1/16W,EMPTA',
 WATTAGE='1/16W',
 TOLERANCE='1%',
 MATERIAL='EMPTY',
 VALUE='240',
 PRIM_FILE='./archive_libs/logical/q_res/chips/chips.prt';

PART_NAME
 R251 'Q_RES_0402LF-240,1%,1/16W,EMPTA':;

SECTION_NUMBER 1
 '@S9S_MB_2U_LIB.S9S_MB_2U(SCH_1):PAGE120_I28@PURE_QUANTA.Q_RES(CHIPS)':
 C_PATH='@s9s_mb_2u_lib.s9s_mb_2u(sch_1):page120_i28@pure_quanta.q_res(chips)',
 P_PATH='@s9s_mb_2u_lib.s9s_mb_2u(sch_1):page120_i28@pure_quanta.q_res(chips)',
 PATH='I28',
 DRAWING='@S9S_MB_2U_LIB.S9S_MB_2U(SCH_1):PAGE120',
 PHYS_PAGE='120',
 XY='(-2000,2900)',
 ROT='0',
 VER='1',
 PACK_TYPE='0402LF',
 CDS_LIB='pure_quanta',
 CDS_PART_NAME='Q_RES_0402LF-240,1%,1/16W,EMPTA',
 WATTAGE='1/16W',
 TOLERANCE='1%',
 MATERIAL='EMPTY',
 VALUE='240',
 PRIM_FILE='./archive_libs/logical/q_res/chips/chips.prt';

PART_NAME
 R252 'Q_RES_0402LF-240,1%,1/16W,CHIPA':;

SECTION_NUMBER 1
 '@S9S_MB_2U_LIB.S9S_MB_2U(SCH_1):PAGE120_I30@PURE_QUANTA.Q_RES(CHIPS)':
 C_PATH='@s9s_mb_2u_lib.s9s_mb_2u(sch_1):page120_i30@pure_quanta.q_res(chips)',
 P_PATH='@s9s_mb_2u_lib.s9s_mb_2u(sch_1):page120_i30@pure_quanta.q_res(chips)',
 PATH='I30',
 DRAWING='@S9S_MB_2U_LIB.S9S_MB_2U(SCH_1):PAGE120',
 PHYS_PAGE='120',
 XY='(-2000,2775)',
 ROT='0',
 VER='1',
 PACK_TYPE='0402LF',
 CDS_LIB='pure_quanta',
 CDS_PART_NAME='Q_RES_0402LF-240,1%,1/16W,CHIPA',
 WATTAGE='1/16W',
 TOLERANCE='1%',
 MATERIAL='CHIP',
 VALUE='240',
 PRIM_FILE='./archive_libs/logical/q_res/chips/chips.prt';

PART_NAME
 R253 'Q_RES_0402LF-240,1%,1/16W,CHIPA':;

SECTION_NUMBER 1
 '@S9S_MB_2U_LIB.S9S_MB_2U(SCH_1):PAGE120_I31@PURE_QUANTA.Q_RES(CHIPS)':
 C_PATH='@s9s_mb_2u_lib.s9s_mb_2u(sch_1):page120_i31@pure_quanta.q_res(chips)',
 P_PATH='@s9s_mb_2u_lib.s9s_mb_2u(sch_1):page120_i31@pure_quanta.q_res(chips)',
 PATH='I31',
 DRAWING='@S9S_MB_2U_LIB.S9S_MB_2U(SCH_1):PAGE120',
 PHYS_PAGE='120',
 XY='(-2000,2650)',
 ROT='0',
 VER='1',
 PACK_TYPE='0402LF',
 CDS_LIB='pure_quanta',
 CDS_PART_NAME='Q_RES_0402LF-240,1%,1/16W,CHIPA',
 WATTAGE='1/16W',
 TOLERANCE='1%',
 MATERIAL='CHIP',
 VALUE='240',
 PRIM_FILE='./archive_libs/logical/q_res/chips/chips.prt';

PART_NAME
 R254 'Q_RES_0402LF-240,1%,1/16W,CHIPA':;

SECTION_NUMBER 1
 '@S9S_MB_2U_LIB.S9S_MB_2U(SCH_1):PAGE120_I32@PURE_QUANTA.Q_RES(CHIPS)':
 C_PATH='@s9s_mb_2u_lib.s9s_mb_2u(sch_1):page120_i32@pure_quanta.q_res(chips)',
 P_PATH='@s9s_mb_2u_lib.s9s_mb_2u(sch_1):page120_i32@pure_quanta.q_res(chips)',
 PATH='I32',
 DRAWING='@S9S_MB_2U_LIB.S9S_MB_2U(SCH_1):PAGE120',
 PHYS_PAGE='120',
 XY='(-2000,2525)',
 ROT='0',
 VER='1',
 PACK_TYPE='0402LF',
 CDS_LIB='pure_quanta',
 CDS_PART_NAME='Q_RES_0402LF-240,1%,1/16W,CHIPA',
 WATTAGE='1/16W',
 TOLERANCE='1%',
 MATERIAL='CHIP',
 VALUE='240',
 PRIM_FILE='./archive_libs/logical/q_res/chips/chips.prt';

PART_NAME
 R255 'Q_RES_0402LF-240,1%,1/16W,EMPTA':;

SECTION_NUMBER 1
 '@S9S_MB_2U_LIB.S9S_MB_2U(SCH_1):PAGE120_I42@PURE_QUANTA.Q_RES(CHIPS)':
 C_PATH='@s9s_mb_2u_lib.s9s_mb_2u(sch_1):page120_i42@pure_quanta.q_res(chips)',
 P_PATH='@s9s_mb_2u_lib.s9s_mb_2u(sch_1):page120_i42@pure_quanta.q_res(chips)',
 PATH='I42',
 DRAWING='@S9S_MB_2U_LIB.S9S_MB_2U(SCH_1):PAGE120',
 PHYS_PAGE='120',
 XY='(-2000,900)',
 ROT='0',
 VER='1',
 PACK_TYPE='0402LF',
 CDS_LIB='pure_quanta',
 CDS_PART_NAME='Q_RES_0402LF-240,1%,1/16W,EMPTA',
 WATTAGE='1/16W',
 TOLERANCE='1%',
 MATERIAL='EMPTY',
 VALUE='240',
 PRIM_FILE='./archive_libs/logical/q_res/chips/chips.prt';

PART_NAME
 R256 'Q_RES_0402LF-240,1%,1/16W,EMPTA':;

SECTION_NUMBER 1
 '@S9S_MB_2U_LIB.S9S_MB_2U(SCH_1):PAGE120_I48@PURE_QUANTA.Q_RES(CHIPS)':
 C_PATH='@s9s_mb_2u_lib.s9s_mb_2u(sch_1):page120_i48@pure_quanta.q_res(chips)',
 P_PATH='@s9s_mb_2u_lib.s9s_mb_2u(sch_1):page120_i48@pure_quanta.q_res(chips)',
 PATH='I48',
 DRAWING='@S9S_MB_2U_LIB.S9S_MB_2U(SCH_1):PAGE120',
 PHYS_PAGE='120',
 XY='(-2000,775)',
 ROT='0',
 VER='1',
 PACK_TYPE='0402LF',
 CDS_LIB='pure_quanta',
 CDS_PART_NAME='Q_RES_0402LF-240,1%,1/16W,EMPTA',
 WATTAGE='1/16W',
 TOLERANCE='1%',
 MATERIAL='EMPTY',
 VALUE='240',
 PRIM_FILE='./archive_libs/logical/q_res/chips/chips.prt';

PART_NAME
 R257 'Q_RES_0402LF-240,1%,1/16W,EMPTA':;

SECTION_NUMBER 1
 '@S9S_MB_2U_LIB.S9S_MB_2U(SCH_1):PAGE120_I43@PURE_QUANTA.Q_RES(CHIPS)':
 C_PATH='@s9s_mb_2u_lib.s9s_mb_2u(sch_1):page120_i43@pure_quanta.q_res(chips)',
 P_PATH='@s9s_mb_2u_lib.s9s_mb_2u(sch_1):page120_i43@pure_quanta.q_res(chips)',
 PATH='I43',
 DRAWING='@S9S_MB_2U_LIB.S9S_MB_2U(SCH_1):PAGE120',
 PHYS_PAGE='120',
 XY='(-2000,400)',
 ROT='0',
 VER='1',
 PACK_TYPE='0402LF',
 CDS_LIB='pure_quanta',
 CDS_PART_NAME='Q_RES_0402LF-240,1%,1/16W,EMPTA',
 WATTAGE='1/16W',
 TOLERANCE='1%',
 MATERIAL='EMPTY',
 VALUE='240',
 PRIM_FILE='./archive_libs/logical/q_res/chips/chips.prt';

PART_NAME
 R258 'Q_RES_0402LF-240,1%,1/16W,CHIPA':;

SECTION_NUMBER 1
 '@S9S_MB_2U_LIB.S9S_MB_2U(SCH_1):PAGE120_I44@PURE_QUANTA.Q_RES(CHIPS)':
 C_PATH='@s9s_mb_2u_lib.s9s_mb_2u(sch_1):page120_i44@pure_quanta.q_res(chips)',
 P_PATH='@s9s_mb_2u_lib.s9s_mb_2u(sch_1):page120_i44@pure_quanta.q_res(chips)',
 PATH='I44',
 DRAWING='@S9S_MB_2U_LIB.S9S_MB_2U(SCH_1):PAGE120',
 PHYS_PAGE='120',
 XY='(-2000,275)',
 ROT='0',
 VER='1',
 PACK_TYPE='0402LF',
 CDS_LIB='pure_quanta',
 CDS_PART_NAME='Q_RES_0402LF-240,1%,1/16W,CHIPA',
 WATTAGE='1/16W',
 TOLERANCE='1%',
 MATERIAL='CHIP',
 VALUE='240',
 PRIM_FILE='./archive_libs/logical/q_res/chips/chips.prt';

PART_NAME
 R259 'Q_RES_0402LF-240,1%,1/16W,CHIPA':;

SECTION_NUMBER 1
 '@S9S_MB_2U_LIB.S9S_MB_2U(SCH_1):PAGE120_I45@PURE_QUANTA.Q_RES(CHIPS)':
 C_PATH='@s9s_mb_2u_lib.s9s_mb_2u(sch_1):page120_i45@pure_quanta.q_res(chips)',
 P_PATH='@s9s_mb_2u_lib.s9s_mb_2u(sch_1):page120_i45@pure_quanta.q_res(chips)',
 PATH='I45',
 DRAWING='@S9S_MB_2U_LIB.S9S_MB_2U(SCH_1):PAGE120',
 PHYS_PAGE='120',
 XY='(-2000,150)',
 ROT='0',
 VER='1',
 PACK_TYPE='0402LF',
 CDS_LIB='pure_quanta',
 CDS_PART_NAME='Q_RES_0402LF-240,1%,1/16W,CHIPA',
 WATTAGE='1/16W',
 TOLERANCE='1%',
 MATERIAL='CHIP',
 VALUE='240',
 PRIM_FILE='./archive_libs/logical/q_res/chips/chips.prt';

PART_NAME
 R260 'Q_RES_0402LF-240,1%,1/16W,CHIPA':;

SECTION_NUMBER 1
 '@S9S_MB_2U_LIB.S9S_MB_2U(SCH_1):PAGE120_I46@PURE_QUANTA.Q_RES(CHIPS)':
 C_PATH='@s9s_mb_2u_lib.s9s_mb_2u(sch_1):page120_i46@pure_quanta.q_res(chips)',
 P_PATH='@s9s_mb_2u_lib.s9s_mb_2u(sch_1):page120_i46@pure_quanta.q_res(chips)',
 PATH='I46',
 DRAWING='@S9S_MB_2U_LIB.S9S_MB_2U(SCH_1):PAGE120',
 PHYS_PAGE='120',
 XY='(-2000,25)',
 ROT='0',
 VER='1',
 PACK_TYPE='0402LF',
 CDS_LIB='pure_quanta',
 CDS_PART_NAME='Q_RES_0402LF-240,1%,1/16W,CHIPA',
 WATTAGE='1/16W',
 TOLERANCE='1%',
 MATERIAL='CHIP',
 VALUE='240',
 PRIM_FILE='./archive_libs/logical/q_res/chips/chips.prt';

PART_NAME
 R261 'Q_RES_0402LF-240,1%,1/16W,EMPTA':;

SECTION_NUMBER 1
 '@S9S_MB_2U_LIB.S9S_MB_2U(SCH_1):PAGE119_I101@PURE_QUANTA.Q_RES(CHIPS)':
 C_PATH='@s9s_mb_2u_lib.s9s_mb_2u(sch_1):page119_i101@pure_quanta.q_res(chips)',
 P_PATH='@s9s_mb_2u_lib.s9s_mb_2u(sch_1):page119_i101@pure_quanta.q_res(chips)',
 PATH='I101',
 DRAWING='@S9S_MB_2U_LIB.S9S_MB_2U(SCH_1):PAGE119',
 PHYS_PAGE='119',
 XY='(-2100,600)',
 ROT='0',
 VER='1',
 PACK_TYPE='0402LF',
 CDS_LIB='pure_quanta',
 CDS_PART_NAME='Q_RES_0402LF-240,1%,1/16W,EMPTA',
 WATTAGE='1/16W',
 TOLERANCE='1%',
 MATERIAL='EMPTY',
 VALUE='240',
 PRIM_FILE='./archive_libs/logical/q_res/chips/chips.prt';

PART_NAME
 R262 'Q_RES_0402LF-240,1%,1/16W,EMPTA':;

SECTION_NUMBER 1
 '@S9S_MB_2U_LIB.S9S_MB_2U(SCH_1):PAGE119_I100@PURE_QUANTA.Q_RES(CHIPS)':
 C_PATH='@s9s_mb_2u_lib.s9s_mb_2u(sch_1):page119_i100@pure_quanta.q_res(chips)',
 P_PATH='@s9s_mb_2u_lib.s9s_mb_2u(sch_1):page119_i100@pure_quanta.q_res(chips)',
 PATH='I100',
 DRAWING='@S9S_MB_2U_LIB.S9S_MB_2U(SCH_1):PAGE119',
 PHYS_PAGE='119',
 XY='(-2100,475)',
 ROT='0',
 VER='1',
 PACK_TYPE='0402LF',
 CDS_LIB='pure_quanta',
 CDS_PART_NAME='Q_RES_0402LF-240,1%,1/16W,EMPTA',
 WATTAGE='1/16W',
 TOLERANCE='1%',
 MATERIAL='EMPTY',
 VALUE='240',
 PRIM_FILE='./archive_libs/logical/q_res/chips/chips.prt';

PART_NAME
 R263 'Q_RES_0402LF-240,1%,1/16W,EMPTA':;

SECTION_NUMBER 1
 '@S9S_MB_2U_LIB.S9S_MB_2U(SCH_1):PAGE119_I125@PURE_QUANTA.Q_RES(CHIPS)':
 C_PATH='@s9s_mb_2u_lib.s9s_mb_2u(sch_1):page119_i125@pure_quanta.q_res(chips)',
 P_PATH='@s9s_mb_2u_lib.s9s_mb_2u(sch_1):page119_i125@pure_quanta.q_res(chips)',
 PATH='I125',
 DRAWING='@S9S_MB_2U_LIB.S9S_MB_2U(SCH_1):PAGE119',
 PHYS_PAGE='119',
 XY='(-2100,350)',
 ROT='0',
 VER='1',
 PACK_TYPE='0402LF',
 CDS_LIB='pure_quanta',
 CDS_PART_NAME='Q_RES_0402LF-240,1%,1/16W,EMPTA',
 WATTAGE='1/16W',
 TOLERANCE='1%',
 MATERIAL='EMPTY',
 VALUE='240',
 PRIM_FILE='./archive_libs/logical/q_res/chips/chips.prt';

PART_NAME
 R264 'Q_RES_0402LF-240,1%,1/16W,EMPTA':;

SECTION_NUMBER 1
 '@S9S_MB_2U_LIB.S9S_MB_2U(SCH_1):PAGE119_I98@PURE_QUANTA.Q_RES(CHIPS)':
 C_PATH='@s9s_mb_2u_lib.s9s_mb_2u(sch_1):page119_i98@pure_quanta.q_res(chips)',
 P_PATH='@s9s_mb_2u_lib.s9s_mb_2u(sch_1):page119_i98@pure_quanta.q_res(chips)',
 PATH='I98',
 DRAWING='@S9S_MB_2U_LIB.S9S_MB_2U(SCH_1):PAGE119',
 PHYS_PAGE='119',
 XY='(-2100,225)',
 ROT='0',
 VER='1',
 PACK_TYPE='0402LF',
 CDS_LIB='pure_quanta',
 CDS_PART_NAME='Q_RES_0402LF-240,1%,1/16W,EMPTA',
 WATTAGE='1/16W',
 TOLERANCE='1%',
 MATERIAL='EMPTY',
 VALUE='240',
 PRIM_FILE='./archive_libs/logical/q_res/chips/chips.prt';

PART_NAME
 R265 'Q_RES_0402LF-240,1%,1/16W,CHIPA':;

SECTION_NUMBER 1
 '@S9S_MB_2U_LIB.S9S_MB_2U(SCH_1):PAGE119_I97@PURE_QUANTA.Q_RES(CHIPS)':
 C_PATH='@s9s_mb_2u_lib.s9s_mb_2u(sch_1):page119_i97@pure_quanta.q_res(chips)',
 P_PATH='@s9s_mb_2u_lib.s9s_mb_2u(sch_1):page119_i97@pure_quanta.q_res(chips)',
 PATH='I97',
 DRAWING='@S9S_MB_2U_LIB.S9S_MB_2U(SCH_1):PAGE119',
 PHYS_PAGE='119',
 XY='(-2100,100)',
 ROT='0',
 VER='1',
 PACK_TYPE='0402LF',
 CDS_LIB='pure_quanta',
 CDS_PART_NAME='Q_RES_0402LF-240,1%,1/16W,CHIPA',
 WATTAGE='1/16W',
 TOLERANCE='1%',
 MATERIAL='CHIP',
 VALUE='240',
 PRIM_FILE='./archive_libs/logical/q_res/chips/chips.prt';

PART_NAME
 R266 'Q_RES_0402LF-240,1%,1/16W,EMPTA':;

SECTION_NUMBER 1
 '@S9S_MB_2U_LIB.S9S_MB_2U(SCH_1):PAGE119_I96@PURE_QUANTA.Q_RES(CHIPS)':
 C_PATH='@s9s_mb_2u_lib.s9s_mb_2u(sch_1):page119_i96@pure_quanta.q_res(chips)',
 P_PATH='@s9s_mb_2u_lib.s9s_mb_2u(sch_1):page119_i96@pure_quanta.q_res(chips)',
 PATH='I96',
 DRAWING='@S9S_MB_2U_LIB.S9S_MB_2U(SCH_1):PAGE119',
 PHYS_PAGE='119',
 XY='(-2100,-25)',
 ROT='0',
 VER='1',
 PACK_TYPE='0402LF',
 CDS_LIB='pure_quanta',
 CDS_PART_NAME='Q_RES_0402LF-240,1%,1/16W,EMPTA',
 WATTAGE='1/16W',
 TOLERANCE='1%',
 MATERIAL='EMPTY',
 VALUE='240',
 PRIM_FILE='./archive_libs/logical/q_res/chips/chips.prt';

PART_NAME
 R267 'Q_RES_0402LF-240,1%,1/16W,EMPTA':;

SECTION_NUMBER 1
 '@S9S_MB_2U_LIB.S9S_MB_2U(SCH_1):PAGE119_I95@PURE_QUANTA.Q_RES(CHIPS)':
 C_PATH='@s9s_mb_2u_lib.s9s_mb_2u(sch_1):page119_i95@pure_quanta.q_res(chips)',
 P_PATH='@s9s_mb_2u_lib.s9s_mb_2u(sch_1):page119_i95@pure_quanta.q_res(chips)',
 PATH='I95',
 DRAWING='@S9S_MB_2U_LIB.S9S_MB_2U(SCH_1):PAGE119',
 PHYS_PAGE='119',
 XY='(-2100,-150)',
 ROT='0',
 VER='1',
 PACK_TYPE='0402LF',
 CDS_LIB='pure_quanta',
 CDS_PART_NAME='Q_RES_0402LF-240,1%,1/16W,EMPTA',
 WATTAGE='1/16W',
 TOLERANCE='1%',
 MATERIAL='EMPTY',
 VALUE='240',
 PRIM_FILE='./archive_libs/logical/q_res/chips/chips.prt';

PART_NAME
 R268 'Q_RES_0402LF-240,1%,1/16W,EMPTA':;

SECTION_NUMBER 1
 '@S9S_MB_2U_LIB.S9S_MB_2U(SCH_1):PAGE119_I94@PURE_QUANTA.Q_RES(CHIPS)':
 C_PATH='@s9s_mb_2u_lib.s9s_mb_2u(sch_1):page119_i94@pure_quanta.q_res(chips)',
 P_PATH='@s9s_mb_2u_lib.s9s_mb_2u(sch_1):page119_i94@pure_quanta.q_res(chips)',
 PATH='I94',
 DRAWING='@S9S_MB_2U_LIB.S9S_MB_2U(SCH_1):PAGE119',
 PHYS_PAGE='119',
 XY='(-2100,-275)',
 ROT='0',
 VER='1',
 PACK_TYPE='0402LF',
 CDS_LIB='pure_quanta',
 CDS_PART_NAME='Q_RES_0402LF-240,1%,1/16W,EMPTA',
 WATTAGE='1/16W',
 TOLERANCE='1%',
 MATERIAL='EMPTY',
 VALUE='240',
 PRIM_FILE='./archive_libs/logical/q_res/chips/chips.prt';

PART_NAME
 R269 'Q_RES_0402LF-33.2,1%,1/16W,CHIA':;

SECTION_NUMBER 1
 '@S9S_MB_2U_LIB.S9S_MB_2U(SCH_1):PAGE212_I91@PURE_QUANTA.Q_RES(CHIPS)':
 C_PATH='@s9s_mb_2u_lib.s9s_mb_2u(sch_1):page212_i91@pure_quanta.q_res(chips)',
 P_PATH='@s9s_mb_2u_lib.s9s_mb_2u(sch_1):page223_i91@pure_quanta.q_res(chips)',
 PATH='I91',
 DRAWING='@S9S_MB_2U_LIB.S9S_MB_2U(SCH_1):PAGE212',
 PHYS_PAGE='223',
 XY='(1875,-550)',
 ROT='0',
 VER='1',
 PACK_TYPE='0402LF',
 CDS_LIB='pure_quanta',
 CDS_PART_NAME='Q_RES_0402LF-33.2,1%,1/16W,CHIA',
 WATTAGE='1/16W',
 TOLERANCE='1%',
 MATERIAL='CHIP',
 VALUE='33.2',
 PRIM_FILE='./archive_libs/logical/q_res/chips/chips.prt';

PART_NAME
 R270 'Q_RES_0402LF-10K,1%,1/16W,CHIPA':;

SECTION_NUMBER 1
 '@S9S_MB_2U_LIB.S9S_MB_2U(SCH_1):PAGE119_I93@PURE_QUANTA.Q_RES(CHIPS)':
 C_PATH='@s9s_mb_2u_lib.s9s_mb_2u(sch_1):page119_i93@pure_quanta.q_res(chips)',
 P_PATH='@s9s_mb_2u_lib.s9s_mb_2u(sch_1):page119_i93@pure_quanta.q_res(chips)',
 PATH='I93',
 DRAWING='@S9S_MB_2U_LIB.S9S_MB_2U(SCH_1):PAGE119',
 PHYS_PAGE='119',
 XY='(225,-775)',
 ROT='0',
 VER='1',
 PACK_TYPE='0402LF',
 CDS_LIB='pure_quanta',
 CDS_PART_NAME='Q_RES_0402LF-10K,1%,1/16W,CHIPA',
 WATTAGE='1/16W',
 TOLERANCE='1%',
 MATERIAL='CHIP',
 VALUE='10K',
 PRIM_FILE='./archive_libs/logical/q_res/chips/chips.prt';

PART_NAME
 R271 'Q_RES_0402LF-10K,1%,1/16W,CHIPA':;

SECTION_NUMBER 1
 '@S9S_MB_2U_LIB.S9S_MB_2U(SCH_1):PAGE119_I92@PURE_QUANTA.Q_RES(CHIPS)':
 C_PATH='@s9s_mb_2u_lib.s9s_mb_2u(sch_1):page119_i92@pure_quanta.q_res(chips)',
 P_PATH='@s9s_mb_2u_lib.s9s_mb_2u(sch_1):page119_i92@pure_quanta.q_res(chips)',
 PATH='I92',
 DRAWING='@S9S_MB_2U_LIB.S9S_MB_2U(SCH_1):PAGE119',
 PHYS_PAGE='119',
 XY='(225,-900)',
 ROT='0',
 VER='1',
 PACK_TYPE='0402LF',
 CDS_LIB='pure_quanta',
 CDS_PART_NAME='Q_RES_0402LF-10K,1%,1/16W,CHIPA',
 WATTAGE='1/16W',
 TOLERANCE='1%',
 MATERIAL='CHIP',
 VALUE='10K',
 PRIM_FILE='./archive_libs/logical/q_res/chips/chips.prt';

PART_NAME
 R272 'Q_RES_0402LF-10K,1%,1/16W,CHIPA':;

SECTION_NUMBER 1
 '@S9S_MB_2U_LIB.S9S_MB_2U(SCH_1):PAGE119_I90@PURE_QUANTA.Q_RES(CHIPS)':
 C_PATH='@s9s_mb_2u_lib.s9s_mb_2u(sch_1):page119_i90@pure_quanta.q_res(chips)',
 P_PATH='@s9s_mb_2u_lib.s9s_mb_2u(sch_1):page119_i90@pure_quanta.q_res(chips)',
 PATH='I90',
 DRAWING='@S9S_MB_2U_LIB.S9S_MB_2U(SCH_1):PAGE119',
 PHYS_PAGE='119',
 XY='(225,-1025)',
 ROT='0',
 VER='1',
 PACK_TYPE='0402LF',
 CDS_LIB='pure_quanta',
 CDS_PART_NAME='Q_RES_0402LF-10K,1%,1/16W,CHIPA',
 WATTAGE='1/16W',
 TOLERANCE='1%',
 MATERIAL='CHIP',
 VALUE='10K',
 PRIM_FILE='./archive_libs/logical/q_res/chips/chips.prt';

PART_NAME
 R273 'Q_RES_0402LF-10K,1%,1/16W,CHIPA':;

SECTION_NUMBER 1
 '@S9S_MB_2U_LIB.S9S_MB_2U(SCH_1):PAGE119_I89@PURE_QUANTA.Q_RES(CHIPS)':
 C_PATH='@s9s_mb_2u_lib.s9s_mb_2u(sch_1):page119_i89@pure_quanta.q_res(chips)',
 P_PATH='@s9s_mb_2u_lib.s9s_mb_2u(sch_1):page119_i89@pure_quanta.q_res(chips)',
 PATH='I89',
 DRAWING='@S9S_MB_2U_LIB.S9S_MB_2U(SCH_1):PAGE119',
 PHYS_PAGE='119',
 XY='(225,-1150)',
 ROT='0',
 VER='1',
 PACK_TYPE='0402LF',
 CDS_LIB='pure_quanta',
 CDS_PART_NAME='Q_RES_0402LF-10K,1%,1/16W,CHIPA',
 WATTAGE='1/16W',
 TOLERANCE='1%',
 MATERIAL='CHIP',
 VALUE='10K',
 PRIM_FILE='./archive_libs/logical/q_res/chips/chips.prt';

PART_NAME
 R274 'Q_RES_0402LF-10K,1%,1/16W,CHIPA':;

SECTION_NUMBER 1
 '@S9S_MB_2U_LIB.S9S_MB_2U(SCH_1):PAGE119_I88@PURE_QUANTA.Q_RES(CHIPS)':
 C_PATH='@s9s_mb_2u_lib.s9s_mb_2u(sch_1):page119_i88@pure_quanta.q_res(chips)',
 P_PATH='@s9s_mb_2u_lib.s9s_mb_2u(sch_1):page119_i88@pure_quanta.q_res(chips)',
 PATH='I88',
 DRAWING='@S9S_MB_2U_LIB.S9S_MB_2U(SCH_1):PAGE119',
 PHYS_PAGE='119',
 XY='(225,-1275)',
 ROT='0',
 VER='1',
 PACK_TYPE='0402LF',
 CDS_LIB='pure_quanta',
 CDS_PART_NAME='Q_RES_0402LF-10K,1%,1/16W,CHIPA',
 WATTAGE='1/16W',
 TOLERANCE='1%',
 MATERIAL='CHIP',
 VALUE='10K',
 PRIM_FILE='./archive_libs/logical/q_res/chips/chips.prt';

PART_NAME
 R275 'Q_RES_0402LF-240,1%,1/16W,CHIPA':;

SECTION_NUMBER 1
 '@S9S_MB_2U_LIB.S9S_MB_2U(SCH_1):PAGE119_I68@PURE_QUANTA.Q_RES(CHIPS)':
 C_PATH='@s9s_mb_2u_lib.s9s_mb_2u(sch_1):page119_i68@pure_quanta.q_res(chips)',
 P_PATH='@s9s_mb_2u_lib.s9s_mb_2u(sch_1):page119_i68@pure_quanta.q_res(chips)',
 PATH='I68',
 DRAWING='@S9S_MB_2U_LIB.S9S_MB_2U(SCH_1):PAGE119',
 PHYS_PAGE='119',
 XY='(-2075,3575)',
 ROT='0',
 VER='1',
 PACK_TYPE='0402LF',
 CDS_LIB='pure_quanta',
 CDS_PART_NAME='Q_RES_0402LF-240,1%,1/16W,CHIPA',
 WATTAGE='1/16W',
 TOLERANCE='1%',
 MATERIAL='CHIP',
 VALUE='240',
 PRIM_FILE='./archive_libs/logical/q_res/chips/chips.prt';

PART_NAME
 R276 'Q_RES_0402LF-240,1%,1/16W,EMPTA':;

SECTION_NUMBER 1
 '@S9S_MB_2U_LIB.S9S_MB_2U(SCH_1):PAGE119_I66@PURE_QUANTA.Q_RES(CHIPS)':
 C_PATH='@s9s_mb_2u_lib.s9s_mb_2u(sch_1):page119_i66@pure_quanta.q_res(chips)',
 P_PATH='@s9s_mb_2u_lib.s9s_mb_2u(sch_1):page119_i66@pure_quanta.q_res(chips)',
 PATH='I66',
 DRAWING='@S9S_MB_2U_LIB.S9S_MB_2U(SCH_1):PAGE119',
 PHYS_PAGE='119',
 XY='(-2075,3450)',
 ROT='0',
 VER='1',
 PACK_TYPE='0402LF',
 CDS_LIB='pure_quanta',
 CDS_PART_NAME='Q_RES_0402LF-240,1%,1/16W,EMPTA',
 WATTAGE='1/16W',
 TOLERANCE='1%',
 MATERIAL='EMPTY',
 VALUE='240',
 PRIM_FILE='./archive_libs/logical/q_res/chips/chips.prt';

PART_NAME
 R277 'Q_RES_0402LF-240,1%,1/16W,CHIPA':;

SECTION_NUMBER 1
 '@S9S_MB_2U_LIB.S9S_MB_2U(SCH_1):PAGE119_I62@PURE_QUANTA.Q_RES(CHIPS)':
 C_PATH='@s9s_mb_2u_lib.s9s_mb_2u(sch_1):page119_i62@pure_quanta.q_res(chips)',
 P_PATH='@s9s_mb_2u_lib.s9s_mb_2u(sch_1):page119_i62@pure_quanta.q_res(chips)',
 PATH='I62',
 DRAWING='@S9S_MB_2U_LIB.S9S_MB_2U(SCH_1):PAGE119',
 PHYS_PAGE='119',
 XY='(-2075,3325)',
 ROT='0',
 VER='1',
 PACK_TYPE='0402LF',
 CDS_LIB='pure_quanta',
 CDS_PART_NAME='Q_RES_0402LF-240,1%,1/16W,CHIPA',
 WATTAGE='1/16W',
 TOLERANCE='1%',
 MATERIAL='CHIP',
 VALUE='240',
 PRIM_FILE='./archive_libs/logical/q_res/chips/chips.prt';

PART_NAME
 R278 'Q_RES_0402LF-240,1%,1/16W,EMPTA':;

SECTION_NUMBER 1
 '@S9S_MB_2U_LIB.S9S_MB_2U(SCH_1):PAGE119_I61@PURE_QUANTA.Q_RES(CHIPS)':
 C_PATH='@s9s_mb_2u_lib.s9s_mb_2u(sch_1):page119_i61@pure_quanta.q_res(chips)',
 P_PATH='@s9s_mb_2u_lib.s9s_mb_2u(sch_1):page119_i61@pure_quanta.q_res(chips)',
 PATH='I61',
 DRAWING='@S9S_MB_2U_LIB.S9S_MB_2U(SCH_1):PAGE119',
 PHYS_PAGE='119',
 XY='(-2075,3200)',
 ROT='0',
 VER='1',
 PACK_TYPE='0402LF',
 CDS_LIB='pure_quanta',
 CDS_PART_NAME='Q_RES_0402LF-240,1%,1/16W,EMPTA',
 WATTAGE='1/16W',
 TOLERANCE='1%',
 MATERIAL='EMPTY',
 VALUE='240',
 PRIM_FILE='./archive_libs/logical/q_res/chips/chips.prt';

PART_NAME
 R279 'Q_RES_0402LF-240,1%,1/16W,EMPTA':;

SECTION_NUMBER 1
 '@S9S_MB_2U_LIB.S9S_MB_2U(SCH_1):PAGE119_I54@PURE_QUANTA.Q_RES(CHIPS)':
 C_PATH='@s9s_mb_2u_lib.s9s_mb_2u(sch_1):page119_i54@pure_quanta.q_res(chips)',
 P_PATH='@s9s_mb_2u_lib.s9s_mb_2u(sch_1):page119_i54@pure_quanta.q_res(chips)',
 PATH='I54',
 DRAWING='@S9S_MB_2U_LIB.S9S_MB_2U(SCH_1):PAGE119',
 PHYS_PAGE='119',
 XY='(-2075,3075)',
 ROT='0',
 VER='1',
 PACK_TYPE='0402LF',
 CDS_LIB='pure_quanta',
 CDS_PART_NAME='Q_RES_0402LF-240,1%,1/16W,EMPTA',
 WATTAGE='1/16W',
 TOLERANCE='1%',
 MATERIAL='EMPTY',
 VALUE='240',
 PRIM_FILE='./archive_libs/logical/q_res/chips/chips.prt';

PART_NAME
 R280 'Q_RES_0402LF-240,1%,1/16W,EMPTA':;

SECTION_NUMBER 1
 '@S9S_MB_2U_LIB.S9S_MB_2U(SCH_1):PAGE119_I57@PURE_QUANTA.Q_RES(CHIPS)':
 C_PATH='@s9s_mb_2u_lib.s9s_mb_2u(sch_1):page119_i57@pure_quanta.q_res(chips)',
 P_PATH='@s9s_mb_2u_lib.s9s_mb_2u(sch_1):page119_i57@pure_quanta.q_res(chips)',
 PATH='I57',
 DRAWING='@S9S_MB_2U_LIB.S9S_MB_2U(SCH_1):PAGE119',
 PHYS_PAGE='119',
 XY='(-2075,2950)',
 ROT='0',
 VER='1',
 PACK_TYPE='0402LF',
 CDS_LIB='pure_quanta',
 CDS_PART_NAME='Q_RES_0402LF-240,1%,1/16W,EMPTA',
 WATTAGE='1/16W',
 TOLERANCE='1%',
 MATERIAL='EMPTY',
 VALUE='240',
 PRIM_FILE='./archive_libs/logical/q_res/chips/chips.prt';

PART_NAME
 R281 'Q_RES_0402LF-240,1%,1/16W,EMPTA':;

SECTION_NUMBER 1
 '@S9S_MB_2U_LIB.S9S_MB_2U(SCH_1):PAGE119_I58@PURE_QUANTA.Q_RES(CHIPS)':
 C_PATH='@s9s_mb_2u_lib.s9s_mb_2u(sch_1):page119_i58@pure_quanta.q_res(chips)',
 P_PATH='@s9s_mb_2u_lib.s9s_mb_2u(sch_1):page119_i58@pure_quanta.q_res(chips)',
 PATH='I58',
 DRAWING='@S9S_MB_2U_LIB.S9S_MB_2U(SCH_1):PAGE119',
 PHYS_PAGE='119',
 XY='(-2075,2825)',
 ROT='0',
 VER='1',
 PACK_TYPE='0402LF',
 CDS_LIB='pure_quanta',
 CDS_PART_NAME='Q_RES_0402LF-240,1%,1/16W,EMPTA',
 WATTAGE='1/16W',
 TOLERANCE='1%',
 MATERIAL='EMPTY',
 VALUE='240',
 PRIM_FILE='./archive_libs/logical/q_res/chips/chips.prt';

PART_NAME
 R282 'Q_RES_0402LF-240,1%,1/16W,CHIPA':;

SECTION_NUMBER 1
 '@S9S_MB_2U_LIB.S9S_MB_2U(SCH_1):PAGE119_I53@PURE_QUANTA.Q_RES(CHIPS)':
 C_PATH='@s9s_mb_2u_lib.s9s_mb_2u(sch_1):page119_i53@pure_quanta.q_res(chips)',
 P_PATH='@s9s_mb_2u_lib.s9s_mb_2u(sch_1):page119_i53@pure_quanta.q_res(chips)',
 PATH='I53',
 DRAWING='@S9S_MB_2U_LIB.S9S_MB_2U(SCH_1):PAGE119',
 PHYS_PAGE='119',
 XY='(-2075,2700)',
 ROT='0',
 VER='1',
 PACK_TYPE='0402LF',
 CDS_LIB='pure_quanta',
 CDS_PART_NAME='Q_RES_0402LF-240,1%,1/16W,CHIPA',
 WATTAGE='1/16W',
 TOLERANCE='1%',
 MATERIAL='CHIP',
 VALUE='240',
 PRIM_FILE='./archive_libs/logical/q_res/chips/chips.prt';

PART_NAME
 R283 'Q_RES_0402LF-10K,1%,1/16W,CHIPA':;

SECTION_NUMBER 1
 '@S9S_MB_2U_LIB.S9S_MB_2U(SCH_1):PAGE119_I147@PURE_QUANTA.Q_RES(CHIPS)':
 C_PATH='@s9s_mb_2u_lib.s9s_mb_2u(sch_1):page119_i147@pure_quanta.q_res(chips)',
 P_PATH='@s9s_mb_2u_lib.s9s_mb_2u(sch_1):page119_i147@pure_quanta.q_res(chips)',
 PATH='I147',
 DRAWING='@S9S_MB_2U_LIB.S9S_MB_2U(SCH_1):PAGE119',
 PHYS_PAGE='119',
 XY='(250,2250)',
 ROT='0',
 VER='1',
 PACK_TYPE='0402LF',
 CDS_LIB='pure_quanta',
 CDS_PART_NAME='Q_RES_0402LF-10K,1%,1/16W,CHIPA',
 WATTAGE='1/16W',
 TOLERANCE='1%',
 MATERIAL='CHIP',
 VALUE='10K',
 PRIM_FILE='./archive_libs/logical/q_res/chips/chips.prt';

PART_NAME
 R284 'Q_RES_0402LF-10K,1%,1/16W,CHIPA':;

SECTION_NUMBER 1
 '@S9S_MB_2U_LIB.S9S_MB_2U(SCH_1):PAGE119_I148@PURE_QUANTA.Q_RES(CHIPS)':
 C_PATH='@s9s_mb_2u_lib.s9s_mb_2u(sch_1):page119_i148@pure_quanta.q_res(chips)',
 P_PATH='@s9s_mb_2u_lib.s9s_mb_2u(sch_1):page119_i148@pure_quanta.q_res(chips)',
 PATH='I148',
 DRAWING='@S9S_MB_2U_LIB.S9S_MB_2U(SCH_1):PAGE119',
 PHYS_PAGE='119',
 XY='(250,2125)',
 ROT='0',
 VER='1',
 PACK_TYPE='0402LF',
 CDS_LIB='pure_quanta',
 CDS_PART_NAME='Q_RES_0402LF-10K,1%,1/16W,CHIPA',
 WATTAGE='1/16W',
 TOLERANCE='1%',
 MATERIAL='CHIP',
 VALUE='10K',
 PRIM_FILE='./archive_libs/logical/q_res/chips/chips.prt';

PART_NAME
 R285 'Q_RES_0402LF-10K,1%,1/16W,CHIPA':;

SECTION_NUMBER 1
 '@S9S_MB_2U_LIB.S9S_MB_2U(SCH_1):PAGE119_I150@PURE_QUANTA.Q_RES(CHIPS)':
 C_PATH='@s9s_mb_2u_lib.s9s_mb_2u(sch_1):page119_i150@pure_quanta.q_res(chips)',
 P_PATH='@s9s_mb_2u_lib.s9s_mb_2u(sch_1):page119_i150@pure_quanta.q_res(chips)',
 PATH='I150',
 DRAWING='@S9S_MB_2U_LIB.S9S_MB_2U(SCH_1):PAGE119',
 PHYS_PAGE='119',
 XY='(250,2000)',
 ROT='0',
 VER='1',
 PACK_TYPE='0402LF',
 CDS_LIB='pure_quanta',
 CDS_PART_NAME='Q_RES_0402LF-10K,1%,1/16W,CHIPA',
 WATTAGE='1/16W',
 TOLERANCE='1%',
 MATERIAL='CHIP',
 VALUE='10K',
 PRIM_FILE='./archive_libs/logical/q_res/chips/chips.prt';

PART_NAME
 R286 'Q_RES_0402LF-10K,1%,1/16W,CHIPA':;

SECTION_NUMBER 1
 '@S9S_MB_2U_LIB.S9S_MB_2U(SCH_1):PAGE119_I151@PURE_QUANTA.Q_RES(CHIPS)':
 C_PATH='@s9s_mb_2u_lib.s9s_mb_2u(sch_1):page119_i151@pure_quanta.q_res(chips)',
 P_PATH='@s9s_mb_2u_lib.s9s_mb_2u(sch_1):page119_i151@pure_quanta.q_res(chips)',
 PATH='I151',
 DRAWING='@S9S_MB_2U_LIB.S9S_MB_2U(SCH_1):PAGE119',
 PHYS_PAGE='119',
 XY='(250,1875)',
 ROT='0',
 VER='1',
 PACK_TYPE='0402LF',
 CDS_LIB='pure_quanta',
 CDS_PART_NAME='Q_RES_0402LF-10K,1%,1/16W,CHIPA',
 WATTAGE='1/16W',
 TOLERANCE='1%',
 MATERIAL='CHIP',
 VALUE='10K',
 PRIM_FILE='./archive_libs/logical/q_res/chips/chips.prt';

PART_NAME
 R287 'Q_RES_0402LF-10K,1%,1/16W,CHIPA':;

SECTION_NUMBER 1
 '@S9S_MB_2U_LIB.S9S_MB_2U(SCH_1):PAGE119_I152@PURE_QUANTA.Q_RES(CHIPS)':
 C_PATH='@s9s_mb_2u_lib.s9s_mb_2u(sch_1):page119_i152@pure_quanta.q_res(chips)',
 P_PATH='@s9s_mb_2u_lib.s9s_mb_2u(sch_1):page119_i152@pure_quanta.q_res(chips)',
 PATH='I152',
 DRAWING='@S9S_MB_2U_LIB.S9S_MB_2U(SCH_1):PAGE119',
 PHYS_PAGE='119',
 XY='(250,1750)',
 ROT='0',
 VER='1',
 PACK_TYPE='0402LF',
 CDS_LIB='pure_quanta',
 CDS_PART_NAME='Q_RES_0402LF-10K,1%,1/16W,CHIPA',
 WATTAGE='1/16W',
 TOLERANCE='1%',
 MATERIAL='CHIP',
 VALUE='10K',
 PRIM_FILE='./archive_libs/logical/q_res/chips/chips.prt';

PART_NAME
 R288 'Q_RES_0402LF-240,1%,1/16W,EMPTA':;

SECTION_NUMBER 1
 '@S9S_MB_2U_LIB.S9S_MB_2U(SCH_1):PAGE119_I224@PURE_QUANTA.Q_RES(CHIPS)':
 C_PATH='@s9s_mb_2u_lib.s9s_mb_2u(sch_1):page119_i224@pure_quanta.q_res(chips)',
 P_PATH='@s9s_mb_2u_lib.s9s_mb_2u(sch_1):page119_i224@pure_quanta.q_res(chips)',
 PATH='I224',
 DRAWING='@S9S_MB_2U_LIB.S9S_MB_2U(SCH_1):PAGE119',
 PHYS_PAGE='119',
 XY='(2950,-925)',
 ROT='5',
 VER='1',
 PACK_TYPE='0402LF',
 LOCATION='R288',
 CDS_LIB='pure_quanta',
 CDS_PART_NAME='Q_RES_0402LF-240,1%,1/16W,EMPTA',
 WATTAGE='1/16W',
 TOLERANCE='1%',
 MATERIAL='EMPTY',
 VALUE='240',
 PRIM_FILE='./archive_libs/logical/q_res/chips/chips.prt';

PART_NAME
 R289 'Q_RES_0402LF-240,1%,1/16W,EMPTA':;

SECTION_NUMBER 1
 '@S9S_MB_2U_LIB.S9S_MB_2U(SCH_1):PAGE119_I225@PURE_QUANTA.Q_RES(CHIPS)':
 C_PATH='@s9s_mb_2u_lib.s9s_mb_2u(sch_1):page119_i225@pure_quanta.q_res(chips)',
 P_PATH='@s9s_mb_2u_lib.s9s_mb_2u(sch_1):page119_i225@pure_quanta.q_res(chips)',
 PATH='I225',
 DRAWING='@S9S_MB_2U_LIB.S9S_MB_2U(SCH_1):PAGE119',
 PHYS_PAGE='119',
 XY='(2950,-1250)',
 ROT='5',
 VER='1',
 PACK_TYPE='0402LF',
 LOCATION='R289',
 CDS_LIB='pure_quanta',
 CDS_PART_NAME='Q_RES_0402LF-240,1%,1/16W,EMPTA',
 WATTAGE='1/16W',
 TOLERANCE='1%',
 MATERIAL='EMPTY',
 VALUE='240',
 PRIM_FILE='./archive_libs/logical/q_res/chips/chips.prt';

PART_NAME
 R290 'Q_RES_0402LF-240,1%,1/16W,CHIPA':;

SECTION_NUMBER 1
 '@S9S_MB_2U_LIB.S9S_MB_2U(SCH_1):PAGE119_I135@PURE_QUANTA.Q_RES(CHIPS)':
 C_PATH='@s9s_mb_2u_lib.s9s_mb_2u(sch_1):page119_i135@pure_quanta.q_res(chips)',
 P_PATH='@s9s_mb_2u_lib.s9s_mb_2u(sch_1):page119_i135@pure_quanta.q_res(chips)',
 PATH='I135',
 DRAWING='@S9S_MB_2U_LIB.S9S_MB_2U(SCH_1):PAGE119',
 PHYS_PAGE='119',
 XY='(250,375)',
 ROT='0',
 VER='1',
 PACK_TYPE='0402LF',
 CDS_LIB='pure_quanta',
 CDS_PART_NAME='Q_RES_0402LF-240,1%,1/16W,CHIPA',
 WATTAGE='1/16W',
 TOLERANCE='1%',
 MATERIAL='CHIP',
 VALUE='240',
 PRIM_FILE='./archive_libs/logical/q_res/chips/chips.prt';

PART_NAME
 R291 'Q_RES_0402LF-240,1%,1/16W,EMPTA':;

SECTION_NUMBER 1
 '@S9S_MB_2U_LIB.S9S_MB_2U(SCH_1):PAGE119_I116@PURE_QUANTA.Q_RES(CHIPS)':
 C_PATH='@s9s_mb_2u_lib.s9s_mb_2u(sch_1):page119_i116@pure_quanta.q_res(chips)',
 P_PATH='@s9s_mb_2u_lib.s9s_mb_2u(sch_1):page119_i116@pure_quanta.q_res(chips)',
 PATH='I116',
 DRAWING='@S9S_MB_2U_LIB.S9S_MB_2U(SCH_1):PAGE119',
 PHYS_PAGE='119',
 XY='(250,250)',
 ROT='0',
 VER='1',
 PACK_TYPE='0402LF',
 CDS_LIB='pure_quanta',
 CDS_PART_NAME='Q_RES_0402LF-240,1%,1/16W,EMPTA',
 WATTAGE='1/16W',
 TOLERANCE='1%',
 MATERIAL='EMPTY',
 VALUE='240',
 PRIM_FILE='./archive_libs/logical/q_res/chips/chips.prt';

PART_NAME
 R292 'Q_RES_0402LF-240,1%,1/16W,EMPTA':;

SECTION_NUMBER 1
 '@S9S_MB_2U_LIB.S9S_MB_2U(SCH_1):PAGE119_I196@PURE_QUANTA.Q_RES(CHIPS)':
 C_PATH='@s9s_mb_2u_lib.s9s_mb_2u(sch_1):page119_i196@pure_quanta.q_res(chips)',
 P_PATH='@s9s_mb_2u_lib.s9s_mb_2u(sch_1):page119_i196@pure_quanta.q_res(chips)',
 PATH='I196',
 DRAWING='@S9S_MB_2U_LIB.S9S_MB_2U(SCH_1):PAGE119',
 PHYS_PAGE='119',
 XY='(2975,3375)',
 ROT='5',
 VER='1',
 PACK_TYPE='0402LF',
 CDS_LIB='pure_quanta',
 CDS_PART_NAME='Q_RES_0402LF-240,1%,1/16W,EMPTA',
 WATTAGE='1/16W',
 TOLERANCE='1%',
 MATERIAL='EMPTY',
 VALUE='240',
 PRIM_FILE='./archive_libs/logical/q_res/chips/chips.prt';

PART_NAME
 R293 'Q_RES_0402LF-240,1%,1/16W,EMPTA':;

SECTION_NUMBER 1
 '@S9S_MB_2U_LIB.S9S_MB_2U(SCH_1):PAGE119_I211@PURE_QUANTA.Q_RES(CHIPS)':
 C_PATH='@s9s_mb_2u_lib.s9s_mb_2u(sch_1):page119_i211@pure_quanta.q_res(chips)',
 P_PATH='@s9s_mb_2u_lib.s9s_mb_2u(sch_1):page119_i211@pure_quanta.q_res(chips)',
 PATH='I211',
 DRAWING='@S9S_MB_2U_LIB.S9S_MB_2U(SCH_1):PAGE119',
 PHYS_PAGE='119',
 XY='(2975,3050)',
 ROT='5',
 VER='1',
 PACK_TYPE='0402LF',
 LOCATION='R293',
 CDS_LIB='pure_quanta',
 CDS_PART_NAME='Q_RES_0402LF-240,1%,1/16W,EMPTA',
 WATTAGE='1/16W',
 TOLERANCE='1%',
 MATERIAL='EMPTY',
 VALUE='240',
 PRIM_FILE='./archive_libs/logical/q_res/chips/chips.prt';

PART_NAME
 R294 'Q_RES_0402LF-240,1%,1/16W,EMPTA':;

SECTION_NUMBER 1
 '@S9S_MB_2U_LIB.S9S_MB_2U(SCH_1):PAGE119_I71@PURE_QUANTA.Q_RES(CHIPS)':
 C_PATH='@s9s_mb_2u_lib.s9s_mb_2u(sch_1):page119_i71@pure_quanta.q_res(chips)',
 P_PATH='@s9s_mb_2u_lib.s9s_mb_2u(sch_1):page119_i71@pure_quanta.q_res(chips)',
 PATH='I71',
 DRAWING='@S9S_MB_2U_LIB.S9S_MB_2U(SCH_1):PAGE119',
 PHYS_PAGE='119',
 XY='(275,3350)',
 ROT='0',
 VER='1',
 PACK_TYPE='0402LF',
 CDS_LIB='pure_quanta',
 CDS_PART_NAME='Q_RES_0402LF-240,1%,1/16W,EMPTA',
 WATTAGE='1/16W',
 TOLERANCE='1%',
 MATERIAL='EMPTY',
 VALUE='240',
 PRIM_FILE='./archive_libs/logical/q_res/chips/chips.prt';

PART_NAME
 R295 'Q_RES_0402LF-240,1%,1/16W,EMPTA':;

SECTION_NUMBER 1
 '@S9S_MB_2U_LIB.S9S_MB_2U(SCH_1):PAGE119_I72@PURE_QUANTA.Q_RES(CHIPS)':
 C_PATH='@s9s_mb_2u_lib.s9s_mb_2u(sch_1):page119_i72@pure_quanta.q_res(chips)',
 P_PATH='@s9s_mb_2u_lib.s9s_mb_2u(sch_1):page119_i72@pure_quanta.q_res(chips)',
 PATH='I72',
 DRAWING='@S9S_MB_2U_LIB.S9S_MB_2U(SCH_1):PAGE119',
 PHYS_PAGE='119',
 XY='(275,3225)',
 ROT='0',
 VER='1',
 PACK_TYPE='0402LF',
 CDS_LIB='pure_quanta',
 CDS_PART_NAME='Q_RES_0402LF-240,1%,1/16W,EMPTA',
 WATTAGE='1/16W',
 TOLERANCE='1%',
 MATERIAL='EMPTY',
 VALUE='240',
 PRIM_FILE='./archive_libs/logical/q_res/chips/chips.prt';

PART_NAME
 R296 'Q_RES_0402LF-301,1%,1/16W,CHIPA':;

SECTION_NUMBER 1
 '@S9S_MB_2U_LIB.S9S_MB_2U(SCH_1):PAGE118_I65@PURE_QUANTA.Q_RES(CHIPS)':
 C_PATH='@s9s_mb_2u_lib.s9s_mb_2u(sch_1):page118_i65@pure_quanta.q_res(chips)',
 P_PATH='@s9s_mb_2u_lib.s9s_mb_2u(sch_1):page118_i65@pure_quanta.q_res(chips)',
 PATH='I65',
 DRAWING='@S9S_MB_2U_LIB.S9S_MB_2U(SCH_1):PAGE118',
 PHYS_PAGE='118',
 XY='(-1400,1250)',
 ROT='0',
 VER='1',
 PACK_TYPE='0402LF',
 CDS_LIB='pure_quanta',
 CDS_PART_NAME='Q_RES_0402LF-301,1%,1/16W,CHIPA',
 WATTAGE='1/16W',
 TOLERANCE='1%',
 MATERIAL='CHIP',
 VALUE='301',
 PRIM_FILE='./archive_libs/logical/q_res/chips/chips.prt';

PART_NAME
 R297 'Q_RES_0402LF-0,5%,1/16W,CHIP,CA':;

SECTION_NUMBER 1
 '@S9S_MB_2U_LIB.S9S_MB_2U(SCH_1):PAGE118_I23@PURE_QUANTA.Q_RES(CHIPS)':
 C_PATH='@s9s_mb_2u_lib.s9s_mb_2u(sch_1):page118_i23@pure_quanta.q_res(chips)',
 P_PATH='@s9s_mb_2u_lib.s9s_mb_2u(sch_1):page118_i23@pure_quanta.q_res(chips)',
 PATH='I23',
 DRAWING='@S9S_MB_2U_LIB.S9S_MB_2U(SCH_1):PAGE118',
 PHYS_PAGE='118',
 XY='(-1400,1050)',
 ROT='0',
 VER='1',
 PACK_TYPE='0402LF',
 CDS_LIB='pure_quanta',
 CDS_PART_NAME='Q_RES_0402LF-0,5%,1/16W,CHIP,CA',
 WATTAGE='1/16W',
 TOLERANCE='5%',
 MATERIAL='CHIP',
 VALUE='0',
 PRIM_FILE='./archive_libs/logical/q_res/chips/chips.prt';

PART_NAME
 R298 'Q_RES_0402LF-301,1%,1/16W,CHIPA':;

SECTION_NUMBER 1
 '@S9S_MB_2U_LIB.S9S_MB_2U(SCH_1):PAGE118_I67@PURE_QUANTA.Q_RES(CHIPS)':
 C_PATH='@s9s_mb_2u_lib.s9s_mb_2u(sch_1):page118_i67@pure_quanta.q_res(chips)',
 P_PATH='@s9s_mb_2u_lib.s9s_mb_2u(sch_1):page118_i67@pure_quanta.q_res(chips)',
 PATH='I67',
 DRAWING='@S9S_MB_2U_LIB.S9S_MB_2U(SCH_1):PAGE118',
 PHYS_PAGE='118',
 XY='(-1400,775)',
 ROT='0',
 VER='1',
 PACK_TYPE='0402LF',
 CDS_LIB='pure_quanta',
 CDS_PART_NAME='Q_RES_0402LF-301,1%,1/16W,CHIPA',
 WATTAGE='1/16W',
 TOLERANCE='1%',
 MATERIAL='CHIP',
 VALUE='301',
 PRIM_FILE='./archive_libs/logical/q_res/chips/chips.prt';

PART_NAME
 R299 'Q_RES_0402LF-0,5%,1/16W,CHIP,CA':;

SECTION_NUMBER 1
 '@S9S_MB_2U_LIB.S9S_MB_2U(SCH_1):PAGE118_I63@PURE_QUANTA.Q_RES(CHIPS)':
 C_PATH='@s9s_mb_2u_lib.s9s_mb_2u(sch_1):page118_i63@pure_quanta.q_res(chips)',
 P_PATH='@s9s_mb_2u_lib.s9s_mb_2u(sch_1):page118_i63@pure_quanta.q_res(chips)',
 PATH='I63',
 DRAWING='@S9S_MB_2U_LIB.S9S_MB_2U(SCH_1):PAGE118',
 PHYS_PAGE='118',
 XY='(-1400,575)',
 ROT='0',
 VER='1',
 PACK_TYPE='0402LF',
 CDS_LIB='pure_quanta',
 CDS_PART_NAME='Q_RES_0402LF-0,5%,1/16W,CHIP,CA',
 WATTAGE='1/16W',
 TOLERANCE='5%',
 MATERIAL='CHIP',
 VALUE='0',
 PRIM_FILE='./archive_libs/logical/q_res/chips/chips.prt';

PART_NAME
 R301 'Q_RES_0402LF-301,1%,1/16W,CHIPA':;

SECTION_NUMBER 1
 '@S9S_MB_2U_LIB.S9S_MB_2U(SCH_1):PAGE118_I73@PURE_QUANTA.Q_RES(CHIPS)':
 C_PATH='@s9s_mb_2u_lib.s9s_mb_2u(sch_1):page118_i73@pure_quanta.q_res(chips)',
 P_PATH='@s9s_mb_2u_lib.s9s_mb_2u(sch_1):page118_i73@pure_quanta.q_res(chips)',
 PATH='I73',
 DRAWING='@S9S_MB_2U_LIB.S9S_MB_2U(SCH_1):PAGE118',
 PHYS_PAGE='118',
 XY='(-1400,-25)',
 ROT='0',
 VER='1',
 PACK_TYPE='0402LF',
 CDS_LIB='pure_quanta',
 CDS_PART_NAME='Q_RES_0402LF-301,1%,1/16W,CHIPA',
 WATTAGE='1/16W',
 TOLERANCE='1%',
 MATERIAL='CHIP',
 VALUE='301',
 PRIM_FILE='./archive_libs/logical/q_res/chips/chips.prt';

PART_NAME
 R302 'Q_RES_0402LF-0,5%,1/16W,CHIP,CA':;

SECTION_NUMBER 1
 '@S9S_MB_2U_LIB.S9S_MB_2U(SCH_1):PAGE118_I101@PURE_QUANTA.Q_RES(CHIPS)':
 C_PATH='@s9s_mb_2u_lib.s9s_mb_2u(sch_1):page118_i101@pure_quanta.q_res(chips)',
 P_PATH='@s9s_mb_2u_lib.s9s_mb_2u(sch_1):page118_i101@pure_quanta.q_res(chips)',
 PATH='I101',
 DRAWING='@S9S_MB_2U_LIB.S9S_MB_2U(SCH_1):PAGE118',
 PHYS_PAGE='118',
 XY='(-1400,-225)',
 ROT='0',
 VER='1',
 PACK_TYPE='0402LF',
 LOCATION='R302',
 CDS_LIB='pure_quanta',
 CDS_PART_NAME='Q_RES_0402LF-0,5%,1/16W,CHIP,CA',
 WATTAGE='1/16W',
 TOLERANCE='5%',
 MATERIAL='CHIP',
 VALUE='0',
 PRIM_FILE='./archive_libs/logical/q_res/chips/chips.prt';

PART_NAME
 R303 'Q_RES_0402LF-301,1%,1/16W,CHIPA':;

SECTION_NUMBER 1
 '@S9S_MB_2U_LIB.S9S_MB_2U(SCH_1):PAGE118_I76@PURE_QUANTA.Q_RES(CHIPS)':
 C_PATH='@s9s_mb_2u_lib.s9s_mb_2u(sch_1):page118_i76@pure_quanta.q_res(chips)',
 P_PATH='@s9s_mb_2u_lib.s9s_mb_2u(sch_1):page118_i76@pure_quanta.q_res(chips)',
 PATH='I76',
 DRAWING='@S9S_MB_2U_LIB.S9S_MB_2U(SCH_1):PAGE118',
 PHYS_PAGE='118',
 XY='(-1400,-500)',
 ROT='0',
 VER='1',
 PACK_TYPE='0402LF',
 CDS_LIB='pure_quanta',
 CDS_PART_NAME='Q_RES_0402LF-301,1%,1/16W,CHIPA',
 WATTAGE='1/16W',
 TOLERANCE='1%',
 MATERIAL='CHIP',
 VALUE='301',
 PRIM_FILE='./archive_libs/logical/q_res/chips/chips.prt';

PART_NAME
 R304 'Q_RES_0402LF-0,5%,1/16W,CHIP,CA':;

SECTION_NUMBER 1
 '@S9S_MB_2U_LIB.S9S_MB_2U(SCH_1):PAGE118_I102@PURE_QUANTA.Q_RES(CHIPS)':
 C_PATH='@s9s_mb_2u_lib.s9s_mb_2u(sch_1):page118_i102@pure_quanta.q_res(chips)',
 P_PATH='@s9s_mb_2u_lib.s9s_mb_2u(sch_1):page118_i102@pure_quanta.q_res(chips)',
 PATH='I102',
 DRAWING='@S9S_MB_2U_LIB.S9S_MB_2U(SCH_1):PAGE118',
 PHYS_PAGE='118',
 XY='(-1400,-700)',
 ROT='0',
 VER='1',
 PACK_TYPE='0402LF',
 LOCATION='R304',
 CDS_LIB='pure_quanta',
 CDS_PART_NAME='Q_RES_0402LF-0,5%,1/16W,CHIP,CA',
 WATTAGE='1/16W',
 TOLERANCE='5%',
 MATERIAL='CHIP',
 VALUE='0',
 PRIM_FILE='./archive_libs/logical/q_res/chips/chips.prt';

PART_NAME
 R307 'Q_RES_0402LF-1K,1%,1/16W,CHIP,A':;

SECTION_NUMBER 1
 '@S9S_MB_2U_LIB.S9S_MB_2U(SCH_1):PAGE270_I61@PURE_QUANTA.Q_RES(CHIPS)':
 C_PATH='@s9s_mb_2u_lib.s9s_mb_2u(sch_1):page270_i61@pure_quanta.q_res(chips)',
 P_PATH='@s9s_mb_2u_lib.s9s_mb_2u(sch_1):page284_i61@pure_quanta.q_res(chips)',
 PATH='I61',
 DRAWING='@S9S_MB_2U_LIB.S9S_MB_2U(SCH_1):PAGE270',
 PHYS_PAGE='284',
 XY='(-2175,3175)',
 ROT='0',
 VER='1',
 PACK_TYPE='0402LF',
 LOCATION='R307',
 CDS_LIB='pure_quanta',
 CDS_PART_NAME='Q_RES_0402LF-1K,1%,1/16W,CHIP,A',
 WATTAGE='1/16W',
 TOLERANCE='1%',
 MATERIAL='CHIP',
 VALUE='1K',
 PRIM_FILE='./archive_libs/logical/q_res/chips/chips.prt';

PART_NAME
 R308 'Q_RES_0402LF-0,5%,1/16W,CHIP,CA':;

SECTION_NUMBER 1
 '@S9S_MB_2U_LIB.S9S_MB_2U(SCH_1):PAGE270_I60@PURE_QUANTA.Q_RES(CHIPS)':
 C_PATH='@s9s_mb_2u_lib.s9s_mb_2u(sch_1):page270_i60@pure_quanta.q_res(chips)',
 P_PATH='@s9s_mb_2u_lib.s9s_mb_2u(sch_1):page284_i60@pure_quanta.q_res(chips)',
 PATH='I60',
 DRAWING='@S9S_MB_2U_LIB.S9S_MB_2U(SCH_1):PAGE270',
 PHYS_PAGE='284',
 XY='(-2175,3025)',
 ROT='0',
 VER='1',
 PACK_TYPE='0402LF',
 LOCATION='R308',
 CDS_LIB='pure_quanta',
 CDS_PART_NAME='Q_RES_0402LF-0,5%,1/16W,CHIP,CA',
 WATTAGE='1/16W',
 TOLERANCE='5%',
 MATERIAL='CHIP',
 VALUE='0',
 PRIM_FILE='./archive_libs/logical/q_res/chips/chips.prt';

PART_NAME
 R309 'Q_RES_0402LF-0,5%,1/16W,CHIP,CA':;

SECTION_NUMBER 1
 '@S9S_MB_2U_LIB.S9S_MB_2U(SCH_1):PAGE270_I59@PURE_QUANTA.Q_RES(CHIPS)':
 C_PATH='@s9s_mb_2u_lib.s9s_mb_2u(sch_1):page270_i59@pure_quanta.q_res(chips)',
 P_PATH='@s9s_mb_2u_lib.s9s_mb_2u(sch_1):page284_i59@pure_quanta.q_res(chips)',
 PATH='I59',
 DRAWING='@S9S_MB_2U_LIB.S9S_MB_2U(SCH_1):PAGE270',
 PHYS_PAGE='284',
 XY='(-2175,2875)',
 ROT='0',
 VER='1',
 PACK_TYPE='0402LF',
 LOCATION='R309',
 CDS_LIB='pure_quanta',
 CDS_PART_NAME='Q_RES_0402LF-0,5%,1/16W,CHIP,CA',
 WATTAGE='1/16W',
 TOLERANCE='5%',
 MATERIAL='CHIP',
 VALUE='0',
 PRIM_FILE='./archive_libs/logical/q_res/chips/chips.prt';

PART_NAME
 R310 'Q_RES_0402LF-150,1%,1/16W,CHIPA':;

SECTION_NUMBER 1
 '@S9S_MB_2U_LIB.S9S_MB_2U(SCH_1):PAGE270_I58@PURE_QUANTA.Q_RES(CHIPS)':
 C_PATH='@s9s_mb_2u_lib.s9s_mb_2u(sch_1):page270_i58@pure_quanta.q_res(chips)',
 P_PATH='@s9s_mb_2u_lib.s9s_mb_2u(sch_1):page284_i58@pure_quanta.q_res(chips)',
 PATH='I58',
 DRAWING='@S9S_MB_2U_LIB.S9S_MB_2U(SCH_1):PAGE270',
 PHYS_PAGE='284',
 XY='(-2175,2575)',
 ROT='0',
 VER='1',
 PACK_TYPE='0402LF',
 LOCATION='R310',
 CDS_LIB='pure_quanta',
 CDS_PART_NAME='Q_RES_0402LF-150,1%,1/16W,CHIPA',
 WATTAGE='1/16W',
 TOLERANCE='1%',
 MATERIAL='CHIP',
 VALUE='150',
 PRIM_FILE='./archive_libs/logical/q_res/chips/chips.prt';

PART_NAME
 R311 'Q_RES_0402LF-0,5%,1/16W,CHIP,CA':;

SECTION_NUMBER 1
 '@S9S_MB_2U_LIB.S9S_MB_2U(SCH_1):PAGE270_I56@PURE_QUANTA.Q_RES(CHIPS)':
 C_PATH='@s9s_mb_2u_lib.s9s_mb_2u(sch_1):page270_i56@pure_quanta.q_res(chips)',
 P_PATH='@s9s_mb_2u_lib.s9s_mb_2u(sch_1):page284_i56@pure_quanta.q_res(chips)',
 PATH='I56',
 DRAWING='@S9S_MB_2U_LIB.S9S_MB_2U(SCH_1):PAGE270',
 PHYS_PAGE='284',
 XY='(-2175,2425)',
 ROT='0',
 VER='1',
 PACK_TYPE='0402LF',
 LOCATION='R311',
 CDS_LIB='pure_quanta',
 CDS_PART_NAME='Q_RES_0402LF-0,5%,1/16W,CHIP,CA',
 WATTAGE='1/16W',
 TOLERANCE='5%',
 MATERIAL='CHIP',
 VALUE='0',
 PRIM_FILE='./archive_libs/logical/q_res/chips/chips.prt';

PART_NAME
 R312 'Q_RES_0402LF-0,5%,1/16W,CHIP,CA':;

SECTION_NUMBER 1
 '@S9S_MB_2U_LIB.S9S_MB_2U(SCH_1):PAGE270_I57@PURE_QUANTA.Q_RES(CHIPS)':
 C_PATH='@s9s_mb_2u_lib.s9s_mb_2u(sch_1):page270_i57@pure_quanta.q_res(chips)',
 P_PATH='@s9s_mb_2u_lib.s9s_mb_2u(sch_1):page284_i57@pure_quanta.q_res(chips)',
 PATH='I57',
 DRAWING='@S9S_MB_2U_LIB.S9S_MB_2U(SCH_1):PAGE270',
 PHYS_PAGE='284',
 XY='(-2175,2275)',
 ROT='0',
 VER='1',
 PACK_TYPE='0402LF',
 LOCATION='R312',
 CDS_LIB='pure_quanta',
 CDS_PART_NAME='Q_RES_0402LF-0,5%,1/16W,CHIP,CA',
 WATTAGE='1/16W',
 TOLERANCE='5%',
 MATERIAL='CHIP',
 VALUE='0',
 PRIM_FILE='./archive_libs/logical/q_res/chips/chips.prt';

PART_NAME
 R315 'Q_RES_0402LF-33.2,1%,1/16W,CHIA':;

SECTION_NUMBER 1
 '@S9S_MB_2U_LIB.S9S_MB_2U(SCH_1):PAGE118_I92@PURE_QUANTA.Q_RES(CHIPS)':
 C_PATH='@s9s_mb_2u_lib.s9s_mb_2u(sch_1):page118_i92@pure_quanta.q_res(chips)',
 P_PATH='@s9s_mb_2u_lib.s9s_mb_2u(sch_1):page118_i92@pure_quanta.q_res(chips)',
 PATH='I92',
 DRAWING='@S9S_MB_2U_LIB.S9S_MB_2U(SCH_1):PAGE118',
 PHYS_PAGE='118',
 XY='(-775,-1400)',
 ROT='0',
 VER='1',
 PACK_TYPE='0402LF',
 CDS_LIB='pure_quanta',
 CDS_PART_NAME='Q_RES_0402LF-33.2,1%,1/16W,CHIA',
 WATTAGE='1/16W',
 TOLERANCE='1%',
 MATERIAL='CHIP',
 VALUE='33.2',
 PRIM_FILE='./archive_libs/logical/q_res/chips/chips.prt';

PART_NAME
 R318 'Q_RES_0402LF-10K,1%,1/16W,CHIPA':;

SECTION_NUMBER 1
 '@S9S_MB_2U_LIB.S9S_MB_2U(SCH_1):PAGE217_I42@PURE_QUANTA.Q_RES(CHIPS)':
 C_PATH='@s9s_mb_2u_lib.s9s_mb_2u(sch_1):page217_i42@pure_quanta.q_res(chips)',
 P_PATH='@s9s_mb_2u_lib.s9s_mb_2u(sch_1):page229_i42@pure_quanta.q_res(chips)',
 PATH='I42',
 DRAWING='@S9S_MB_2U_LIB.S9S_MB_2U(SCH_1):PAGE217',
 PHYS_PAGE='229',
 XY='(1600,525)',
 ROT='0',
 VER='2',
 PACK_TYPE='0402LF',
 CDS_LIB='pure_quanta',
 CDS_PART_NAME='Q_RES_0402LF-10K,1%,1/16W,CHIPA',
 WATTAGE='1/16W',
 TOLERANCE='1%',
 MATERIAL='CHIP',
 VALUE='10K',
 PRIM_FILE='./archive_libs/logical/q_res/chips/chips.prt';

PART_NAME
 R319 'Q_RES_0402LF-10K,1%,1/16W,CHIPA':;

SECTION_NUMBER 1
 '@S9S_MB_2U_LIB.S9S_MB_2U(SCH_1):PAGE80_I8@PURE_QUANTA.Q_RES(CHIPS)':
 C_PATH='@s9s_mb_2u_lib.s9s_mb_2u(sch_1):page80_i8@pure_quanta.q_res(chips)',
 P_PATH='@s9s_mb_2u_lib.s9s_mb_2u(sch_1):page80_i8@pure_quanta.q_res(chips)',
 PATH='I8',
 DRAWING='@S9S_MB_2U_LIB.S9S_MB_2U(SCH_1):PAGE80',
 PHYS_PAGE='80',
 XY='(-2375,-850)',
 ROT='0',
 VER='1',
 PACK_TYPE='0402LF',
 CDS_LIB='pure_quanta',
 CDS_PART_NAME='Q_RES_0402LF-10K,1%,1/16W,CHIPA',
 WATTAGE='1/16W',
 TOLERANCE='1%',
 MATERIAL='CHIP',
 VALUE='10K',
 PRIM_FILE='./archive_libs/logical/q_res/chips/chips.prt';

PART_NAME
 R320 'Q_RES_0402LF-10K,1%,1/16W,CHIPA':;

SECTION_NUMBER 1
 '@S9S_MB_2U_LIB.S9S_MB_2U(SCH_1):PAGE80_I7@PURE_QUANTA.Q_RES(CHIPS)':
 C_PATH='@s9s_mb_2u_lib.s9s_mb_2u(sch_1):page80_i7@pure_quanta.q_res(chips)',
 P_PATH='@s9s_mb_2u_lib.s9s_mb_2u(sch_1):page80_i7@pure_quanta.q_res(chips)',
 PATH='I7',
 DRAWING='@S9S_MB_2U_LIB.S9S_MB_2U(SCH_1):PAGE80',
 PHYS_PAGE='80',
 XY='(-2375,-975)',
 ROT='0',
 VER='1',
 PACK_TYPE='0402LF',
 CDS_LIB='pure_quanta',
 CDS_PART_NAME='Q_RES_0402LF-10K,1%,1/16W,CHIPA',
 WATTAGE='1/16W',
 TOLERANCE='1%',
 MATERIAL='CHIP',
 VALUE='10K',
 PRIM_FILE='./archive_libs/logical/q_res/chips/chips.prt';

PART_NAME
 R321 'Q_RES_0402LF-10K,1%,1/16W,CHIPA':;

SECTION_NUMBER 1
 '@S9S_MB_2U_LIB.S9S_MB_2U(SCH_1):PAGE80_I2@PURE_QUANTA.Q_RES(CHIPS)':
 C_PATH='@s9s_mb_2u_lib.s9s_mb_2u(sch_1):page80_i2@pure_quanta.q_res(chips)',
 P_PATH='@s9s_mb_2u_lib.s9s_mb_2u(sch_1):page80_i2@pure_quanta.q_res(chips)',
 PATH='I2',
 DRAWING='@S9S_MB_2U_LIB.S9S_MB_2U(SCH_1):PAGE80',
 PHYS_PAGE='80',
 XY='(-2375,-1100)',
 ROT='0',
 VER='1',
 PACK_TYPE='0402LF',
 CDS_LIB='pure_quanta',
 CDS_PART_NAME='Q_RES_0402LF-10K,1%,1/16W,CHIPA',
 WATTAGE='1/16W',
 TOLERANCE='1%',
 MATERIAL='CHIP',
 VALUE='10K',
 PRIM_FILE='./archive_libs/logical/q_res/chips/chips.prt';

PART_NAME
 R322 'Q_RES_0402LF-33.2,1%,1/16W,CHIA':;

SECTION_NUMBER 1
 '@S9S_MB_2U_LIB.S9S_MB_2U(SCH_1):PAGE14_I90@PURE_QUANTA.Q_RES(CHIPS)':
 C_PATH='@s9s_mb_2u_lib.s9s_mb_2u(sch_1):page14_i90@pure_quanta.q_res(chips)',
 P_PATH='@s9s_mb_2u_lib.s9s_mb_2u(sch_1):page14_i90@pure_quanta.q_res(chips)',
 PATH='I90',
 DRAWING='@S9S_MB_2U_LIB.S9S_MB_2U(SCH_1):PAGE14',
 PHYS_PAGE='14',
 XY='(-1600,-475)',
 ROT='0',
 VER='1',
 PACK_TYPE='0402LF',
 CDS_LIB='pure_quanta',
 CDS_PART_NAME='Q_RES_0402LF-33.2,1%,1/16W,CHIA',
 WATTAGE='1/16W',
 TOLERANCE='1%',
 MATERIAL='CHIP',
 VALUE='33.2',
 PRIM_FILE='./archive_libs/logical/q_res/chips/chips.prt';

PART_NAME
 R323 'Q_RES_1206LF-0,,1/2W,EMPTY,CS0A':;

SECTION_NUMBER 1
 '@S9S_MB_2U_LIB.S9S_MB_2U(SCH_1):PAGE80_I13@PURE_QUANTA.Q_RES(CHIPS)':
 C_PATH='@s9s_mb_2u_lib.s9s_mb_2u(sch_1):page80_i13@pure_quanta.q_res(chips)',
 P_PATH='@s9s_mb_2u_lib.s9s_mb_2u(sch_1):page80_i13@pure_quanta.q_res(chips)',
 PATH='I13',
 DRAWING='@S9S_MB_2U_LIB.S9S_MB_2U(SCH_1):PAGE80',
 PHYS_PAGE='80',
 XY='(-1800,1750)',
 ROT='0',
 VER='1',
 PACK_TYPE='1206LF',
 CDS_LIB='pure_quanta',
 CDS_PART_NAME='Q_RES_1206LF-0,,1/2W,EMPTY,CS0A',
 WATTAGE='1/2W',
 TOLERANCE='',
 MATERIAL='EMPTY',
 VALUE='0',
 PRIM_FILE='./archive_libs/logical/q_res/chips/chips.prt';

PART_NAME
 R324 'Q_RES_1206LF-0,,1/2W,CHIP,CS00A':;

SECTION_NUMBER 1
 '@S9S_MB_2U_LIB.S9S_MB_2U(SCH_1):PAGE80_I12@PURE_QUANTA.Q_RES(CHIPS)':
 C_PATH='@s9s_mb_2u_lib.s9s_mb_2u(sch_1):page80_i12@pure_quanta.q_res(chips)',
 P_PATH='@s9s_mb_2u_lib.s9s_mb_2u(sch_1):page80_i12@pure_quanta.q_res(chips)',
 PATH='I12',
 DRAWING='@S9S_MB_2U_LIB.S9S_MB_2U(SCH_1):PAGE80',
 PHYS_PAGE='80',
 XY='(-1800,1500)',
 ROT='0',
 VER='1',
 PACK_TYPE='1206LF',
 CDS_LIB='pure_quanta',
 CDS_PART_NAME='Q_RES_1206LF-0,,1/2W,CHIP,CS00A',
 WATTAGE='1/2W',
 TOLERANCE='',
 MATERIAL='CHIP',
 VALUE='0',
 PRIM_FILE='./archive_libs/logical/q_res/chips/chips.prt';

PART_NAME
 R325 'Q_RES_0402LF-10K,1%,1/16W,CHIPA':;

SECTION_NUMBER 1
 '@S9S_MB_2U_LIB.S9S_MB_2U(SCH_1):PAGE80_I27@PURE_QUANTA.Q_RES(CHIPS)':
 C_PATH='@s9s_mb_2u_lib.s9s_mb_2u(sch_1):page80_i27@pure_quanta.q_res(chips)',
 P_PATH='@s9s_mb_2u_lib.s9s_mb_2u(sch_1):page80_i27@pure_quanta.q_res(chips)',
 PATH='I27',
 DRAWING='@S9S_MB_2U_LIB.S9S_MB_2U(SCH_1):PAGE80',
 PHYS_PAGE='80',
 XY='(775,-850)',
 ROT='0',
 VER='1',
 PACK_TYPE='0402LF',
 CDS_LIB='pure_quanta',
 CDS_PART_NAME='Q_RES_0402LF-10K,1%,1/16W,CHIPA',
 WATTAGE='1/16W',
 TOLERANCE='1%',
 MATERIAL='CHIP',
 VALUE='10K',
 PRIM_FILE='./archive_libs/logical/q_res/chips/chips.prt';

PART_NAME
 R326 'Q_RES_0402LF-10K,1%,1/16W,CHIPA':;

SECTION_NUMBER 1
 '@S9S_MB_2U_LIB.S9S_MB_2U(SCH_1):PAGE80_I26@PURE_QUANTA.Q_RES(CHIPS)':
 C_PATH='@s9s_mb_2u_lib.s9s_mb_2u(sch_1):page80_i26@pure_quanta.q_res(chips)',
 P_PATH='@s9s_mb_2u_lib.s9s_mb_2u(sch_1):page80_i26@pure_quanta.q_res(chips)',
 PATH='I26',
 DRAWING='@S9S_MB_2U_LIB.S9S_MB_2U(SCH_1):PAGE80',
 PHYS_PAGE='80',
 XY='(775,-975)',
 ROT='0',
 VER='1',
 PACK_TYPE='0402LF',
 CDS_LIB='pure_quanta',
 CDS_PART_NAME='Q_RES_0402LF-10K,1%,1/16W,CHIPA',
 WATTAGE='1/16W',
 TOLERANCE='1%',
 MATERIAL='CHIP',
 VALUE='10K',
 PRIM_FILE='./archive_libs/logical/q_res/chips/chips.prt';

PART_NAME
 R327 'Q_RES_0402LF-10K,1%,1/16W,CHIPA':;

SECTION_NUMBER 1
 '@S9S_MB_2U_LIB.S9S_MB_2U(SCH_1):PAGE80_I25@PURE_QUANTA.Q_RES(CHIPS)':
 C_PATH='@s9s_mb_2u_lib.s9s_mb_2u(sch_1):page80_i25@pure_quanta.q_res(chips)',
 P_PATH='@s9s_mb_2u_lib.s9s_mb_2u(sch_1):page80_i25@pure_quanta.q_res(chips)',
 PATH='I25',
 DRAWING='@S9S_MB_2U_LIB.S9S_MB_2U(SCH_1):PAGE80',
 PHYS_PAGE='80',
 XY='(775,-1100)',
 ROT='0',
 VER='1',
 PACK_TYPE='0402LF',
 CDS_LIB='pure_quanta',
 CDS_PART_NAME='Q_RES_0402LF-10K,1%,1/16W,CHIPA',
 WATTAGE='1/16W',
 TOLERANCE='1%',
 MATERIAL='CHIP',
 VALUE='10K',
 PRIM_FILE='./archive_libs/logical/q_res/chips/chips.prt';

PART_NAME
 R328 'Q_RES_0402LF-100,1%,1/16W,CHIPA':;

SECTION_NUMBER 1
 '@S9S_MB_2U_LIB.S9S_MB_2U(SCH_1):PAGE14_I93@PURE_QUANTA.Q_RES(CHIPS)':
 C_PATH='@s9s_mb_2u_lib.s9s_mb_2u(sch_1):page14_i93@pure_quanta.q_res(chips)',
 P_PATH='@s9s_mb_2u_lib.s9s_mb_2u(sch_1):page14_i93@pure_quanta.q_res(chips)',
 PATH='I93',
 DRAWING='@S9S_MB_2U_LIB.S9S_MB_2U(SCH_1):PAGE14',
 PHYS_PAGE='14',
 XY='(2975,375)',
 ROT='0',
 VER='1',
 PACK_TYPE='0402LF',
 CDS_LIB='pure_quanta',
 CDS_PART_NAME='Q_RES_0402LF-100,1%,1/16W,CHIPA',
 WATTAGE='1/16W',
 TOLERANCE='1%',
 MATERIAL='CHIP',
 VALUE='100',
 PRIM_FILE='./archive_libs/logical/q_res/chips/chips.prt';

PART_NAME
 R329 'Q_RES_1206LF-0,,1/2W,EMPTY,CS0A':;

SECTION_NUMBER 1
 '@S9S_MB_2U_LIB.S9S_MB_2U(SCH_1):PAGE80_I35@PURE_QUANTA.Q_RES(CHIPS)':
 C_PATH='@s9s_mb_2u_lib.s9s_mb_2u(sch_1):page80_i35@pure_quanta.q_res(chips)',
 P_PATH='@s9s_mb_2u_lib.s9s_mb_2u(sch_1):page80_i35@pure_quanta.q_res(chips)',
 PATH='I35',
 DRAWING='@S9S_MB_2U_LIB.S9S_MB_2U(SCH_1):PAGE80',
 PHYS_PAGE='80',
 XY='(1350,1750)',
 ROT='0',
 VER='1',
 PACK_TYPE='1206LF',
 CDS_LIB='pure_quanta',
 CDS_PART_NAME='Q_RES_1206LF-0,,1/2W,EMPTY,CS0A',
 WATTAGE='1/2W',
 TOLERANCE='',
 MATERIAL='EMPTY',
 VALUE='0',
 PRIM_FILE='./archive_libs/logical/q_res/chips/chips.prt';

PART_NAME
 R330 'Q_RES_1206LF-0,,1/2W,CHIP,CS00A':;

SECTION_NUMBER 1
 '@S9S_MB_2U_LIB.S9S_MB_2U(SCH_1):PAGE80_I34@PURE_QUANTA.Q_RES(CHIPS)':
 C_PATH='@s9s_mb_2u_lib.s9s_mb_2u(sch_1):page80_i34@pure_quanta.q_res(chips)',
 P_PATH='@s9s_mb_2u_lib.s9s_mb_2u(sch_1):page80_i34@pure_quanta.q_res(chips)',
 PATH='I34',
 DRAWING='@S9S_MB_2U_LIB.S9S_MB_2U(SCH_1):PAGE80',
 PHYS_PAGE='80',
 XY='(1350,1500)',
 ROT='0',
 VER='1',
 PACK_TYPE='1206LF',
 CDS_LIB='pure_quanta',
 CDS_PART_NAME='Q_RES_1206LF-0,,1/2W,CHIP,CS00A',
 WATTAGE='1/2W',
 TOLERANCE='',
 MATERIAL='CHIP',
 VALUE='0',
 PRIM_FILE='./archive_libs/logical/q_res/chips/chips.prt';

PART_NAME
 R331 'Q_RES_0402LF-1K,1%,1/16W,EMPTYA':;

SECTION_NUMBER 1
 '@S9S_MB_2U_LIB.S9S_MB_2U(SCH_1):PAGE127_I20@PURE_QUANTA.Q_RES(CHIPS)':
 C_PATH='@s9s_mb_2u_lib.s9s_mb_2u(sch_1):page127_i20@pure_quanta.q_res(chips)',
 P_PATH='@s9s_mb_2u_lib.s9s_mb_2u(sch_1):page127_i20@pure_quanta.q_res(chips)',
 PATH='I20',
 DRAWING='@S9S_MB_2U_LIB.S9S_MB_2U(SCH_1):PAGE127',
 PHYS_PAGE='127',
 XY='(-2175,3625)',
 ROT='0',
 VER='2',
 PACK_TYPE='0402LF',
 CDS_LIB='pure_quanta',
 CDS_PART_NAME='Q_RES_0402LF-1K,1%,1/16W,EMPTYA',
 WATTAGE='1/16W',
 TOLERANCE='1%',
 MATERIAL='EMPTY',
 VALUE='1K',
 PRIM_FILE='./archive_libs/logical/q_res/chips/chips.prt';

PART_NAME
 R332 'Q_RES_0402LF-10K,1%,1/16W,CHIPA':;

SECTION_NUMBER 1
 '@S9S_MB_2U_LIB.S9S_MB_2U(SCH_1):PAGE127_I21@PURE_QUANTA.Q_RES(CHIPS)':
 C_PATH='@s9s_mb_2u_lib.s9s_mb_2u(sch_1):page127_i21@pure_quanta.q_res(chips)',
 P_PATH='@s9s_mb_2u_lib.s9s_mb_2u(sch_1):page127_i21@pure_quanta.q_res(chips)',
 PATH='I21',
 DRAWING='@S9S_MB_2U_LIB.S9S_MB_2U(SCH_1):PAGE127',
 PHYS_PAGE='127',
 XY='(-2175,2975)',
 ROT='0',
 VER='2',
 PACK_TYPE='0402LF',
 CDS_LIB='pure_quanta',
 CDS_PART_NAME='Q_RES_0402LF-10K,1%,1/16W,CHIPA',
 WATTAGE='1/16W',
 TOLERANCE='1%',
 MATERIAL='CHIP',
 VALUE='10K',
 PRIM_FILE='./archive_libs/logical/q_res/chips/chips.prt';

PART_NAME
 R333 'Q_RES_0402LF-1K,1%,1/16W,EMPTYA':;

SECTION_NUMBER 1
 '@S9S_MB_2U_LIB.S9S_MB_2U(SCH_1):PAGE127_I6@PURE_QUANTA.Q_RES(CHIPS)':
 C_PATH='@s9s_mb_2u_lib.s9s_mb_2u(sch_1):page127_i6@pure_quanta.q_res(chips)',
 P_PATH='@s9s_mb_2u_lib.s9s_mb_2u(sch_1):page127_i6@pure_quanta.q_res(chips)',
 PATH='I6',
 DRAWING='@S9S_MB_2U_LIB.S9S_MB_2U(SCH_1):PAGE127',
 PHYS_PAGE='127',
 XY='(-1900,3625)',
 ROT='0',
 VER='2',
 PACK_TYPE='0402LF',
 CDS_LIB='pure_quanta',
 CDS_PART_NAME='Q_RES_0402LF-1K,1%,1/16W,EMPTYA',
 WATTAGE='1/16W',
 TOLERANCE='1%',
 MATERIAL='EMPTY',
 VALUE='1K',
 PRIM_FILE='./archive_libs/logical/q_res/chips/chips.prt';

PART_NAME
 R334 'Q_RES_0402LF-10K,1%,1/16W,CHIPA':;

SECTION_NUMBER 1
 '@S9S_MB_2U_LIB.S9S_MB_2U(SCH_1):PAGE127_I1@PURE_QUANTA.Q_RES(CHIPS)':
 C_PATH='@s9s_mb_2u_lib.s9s_mb_2u(sch_1):page127_i1@pure_quanta.q_res(chips)',
 P_PATH='@s9s_mb_2u_lib.s9s_mb_2u(sch_1):page127_i1@pure_quanta.q_res(chips)',
 PATH='I1',
 DRAWING='@S9S_MB_2U_LIB.S9S_MB_2U(SCH_1):PAGE127',
 PHYS_PAGE='127',
 XY='(-1900,2975)',
 ROT='0',
 VER='2',
 PACK_TYPE='0402LF',
 CDS_LIB='pure_quanta',
 CDS_PART_NAME='Q_RES_0402LF-10K,1%,1/16W,CHIPA',
 WATTAGE='1/16W',
 TOLERANCE='1%',
 MATERIAL='CHIP',
 VALUE='10K',
 PRIM_FILE='./archive_libs/logical/q_res/chips/chips.prt';

PART_NAME
 R335 'Q_RES_0402LF-1K,1%,1/16W,EMPTYA':;

SECTION_NUMBER 1
 '@S9S_MB_2U_LIB.S9S_MB_2U(SCH_1):PAGE127_I5@PURE_QUANTA.Q_RES(CHIPS)':
 C_PATH='@s9s_mb_2u_lib.s9s_mb_2u(sch_1):page127_i5@pure_quanta.q_res(chips)',
 P_PATH='@s9s_mb_2u_lib.s9s_mb_2u(sch_1):page127_i5@pure_quanta.q_res(chips)',
 PATH='I5',
 DRAWING='@S9S_MB_2U_LIB.S9S_MB_2U(SCH_1):PAGE127',
 PHYS_PAGE='127',
 XY='(-1625,3625)',
 ROT='0',
 VER='2',
 PACK_TYPE='0402LF',
 CDS_LIB='pure_quanta',
 CDS_PART_NAME='Q_RES_0402LF-1K,1%,1/16W,EMPTYA',
 WATTAGE='1/16W',
 TOLERANCE='1%',
 MATERIAL='EMPTY',
 VALUE='1K',
 PRIM_FILE='./archive_libs/logical/q_res/chips/chips.prt';

PART_NAME
 R336 'Q_RES_0402LF-0,5%,1/16W,CHIP,CA':;

SECTION_NUMBER 1
 '@S9S_MB_2U_LIB.S9S_MB_2U(SCH_1):PAGE322_I159@PURE_QUANTA.Q_RES(CHIPS)':
 C_PATH='@s9s_mb_2u_lib.s9s_mb_2u(sch_1):page322_i159@pure_quanta.q_res(chips)',
 P_PATH='@s9s_mb_2u_lib.s9s_mb_2u(sch_1):page225_i159@pure_quanta.q_res(chips)',
 PATH='I159',
 DRAWING='@S9S_MB_2U_LIB.S9S_MB_2U(SCH_1):PAGE322',
 PHYS_PAGE='225',
 XY='(-12450,-1325)',
 ROT='0',
 VER='1',
 PACK_TYPE='0402LF',
 CDS_LIB='pure_quanta',
 CDS_PART_NAME='Q_RES_0402LF-0,5%,1/16W,CHIP,CA',
 WATTAGE='1/16W',
 TOLERANCE='5%',
 MATERIAL='CHIP',
 VALUE='0',
 PRIM_FILE='./archive_libs/logical/q_res/chips/chips.prt';

PART_NAME
 R337 'Q_RES_0402LF-0,5%,1/16W,CHIP,CA':;

SECTION_NUMBER 1
 '@S9S_MB_2U_LIB.S9S_MB_2U(SCH_1):PAGE322_I160@PURE_QUANTA.Q_RES(CHIPS)':
 C_PATH='@s9s_mb_2u_lib.s9s_mb_2u(sch_1):page322_i160@pure_quanta.q_res(chips)',
 P_PATH='@s9s_mb_2u_lib.s9s_mb_2u(sch_1):page225_i160@pure_quanta.q_res(chips)',
 PATH='I160',
 DRAWING='@S9S_MB_2U_LIB.S9S_MB_2U(SCH_1):PAGE322',
 PHYS_PAGE='225',
 XY='(-12450,-1375)',
 ROT='0',
 VER='1',
 PACK_TYPE='0402LF',
 CDS_LIB='pure_quanta',
 CDS_PART_NAME='Q_RES_0402LF-0,5%,1/16W,CHIP,CA',
 WATTAGE='1/16W',
 TOLERANCE='5%',
 MATERIAL='CHIP',
 VALUE='0',
 PRIM_FILE='./archive_libs/logical/q_res/chips/chips.prt';

PART_NAME
 R338 'Q_RES_0402LF-0,5%,1/16W,CHIP,CA':;

SECTION_NUMBER 1
 '@S9S_MB_2U_LIB.S9S_MB_2U(SCH_1):PAGE322_I173@PURE_QUANTA.Q_RES(CHIPS)':
 C_PATH='@s9s_mb_2u_lib.s9s_mb_2u(sch_1):page322_i173@pure_quanta.q_res(chips)',
 P_PATH='@s9s_mb_2u_lib.s9s_mb_2u(sch_1):page225_i173@pure_quanta.q_res(chips)',
 PATH='I173',
 DRAWING='@S9S_MB_2U_LIB.S9S_MB_2U(SCH_1):PAGE322',
 PHYS_PAGE='225',
 XY='(-11325,-1375)',
 ROT='0',
 VER='1',
 PACK_TYPE='0402LF',
 LOCATION='R338',
 CDS_LIB='pure_quanta',
 CDS_PART_NAME='Q_RES_0402LF-0,5%,1/16W,CHIP,CA',
 WATTAGE='1/16W',
 TOLERANCE='5%',
 MATERIAL='CHIP',
 VALUE='0',
 PRIM_FILE='./archive_libs/logical/q_res/chips/chips.prt';

PART_NAME
 R340 'Q_RES_0402LF-0,5%,1/16W,CHIP,CA':;

SECTION_NUMBER 1
 '@S9S_MB_2U_LIB.S9S_MB_2U(SCH_1):PAGE322_I164@PURE_QUANTA.Q_RES(CHIPS)':
 C_PATH='@s9s_mb_2u_lib.s9s_mb_2u(sch_1):page322_i164@pure_quanta.q_res(chips)',
 P_PATH='@s9s_mb_2u_lib.s9s_mb_2u(sch_1):page225_i164@pure_quanta.q_res(chips)',
 PATH='I164',
 DRAWING='@S9S_MB_2U_LIB.S9S_MB_2U(SCH_1):PAGE322',
 PHYS_PAGE='225',
 XY='(-12475,-2250)',
 ROT='0',
 VER='1',
 PACK_TYPE='0402LF',
 CDS_LIB='pure_quanta',
 CDS_PART_NAME='Q_RES_0402LF-0,5%,1/16W,CHIP,CA',
 WATTAGE='1/16W',
 TOLERANCE='5%',
 MATERIAL='CHIP',
 VALUE='0',
 PRIM_FILE='./archive_libs/logical/q_res/chips/chips.prt';

PART_NAME
 R341 'Q_RES_0402LF-0,5%,1/16W,CHIP,CA':;

SECTION_NUMBER 1
 '@S9S_MB_2U_LIB.S9S_MB_2U(SCH_1):PAGE322_I163@PURE_QUANTA.Q_RES(CHIPS)':
 C_PATH='@s9s_mb_2u_lib.s9s_mb_2u(sch_1):page322_i163@pure_quanta.q_res(chips)',
 P_PATH='@s9s_mb_2u_lib.s9s_mb_2u(sch_1):page225_i163@pure_quanta.q_res(chips)',
 PATH='I163',
 DRAWING='@S9S_MB_2U_LIB.S9S_MB_2U(SCH_1):PAGE322',
 PHYS_PAGE='225',
 XY='(-12475,-2300)',
 ROT='0',
 VER='1',
 PACK_TYPE='0402LF',
 CDS_LIB='pure_quanta',
 CDS_PART_NAME='Q_RES_0402LF-0,5%,1/16W,CHIP,CA',
 WATTAGE='1/16W',
 TOLERANCE='5%',
 MATERIAL='CHIP',
 VALUE='0',
 PRIM_FILE='./archive_libs/logical/q_res/chips/chips.prt';

PART_NAME
 R342 'Q_RES_0402LF-0,5%,1/16W,CHIP,CA':;

SECTION_NUMBER 1
 '@S9S_MB_2U_LIB.S9S_MB_2U(SCH_1):PAGE322_I172@PURE_QUANTA.Q_RES(CHIPS)':
 C_PATH='@s9s_mb_2u_lib.s9s_mb_2u(sch_1):page322_i172@pure_quanta.q_res(chips)',
 P_PATH='@s9s_mb_2u_lib.s9s_mb_2u(sch_1):page225_i172@pure_quanta.q_res(chips)',
 PATH='I172',
 DRAWING='@S9S_MB_2U_LIB.S9S_MB_2U(SCH_1):PAGE322',
 PHYS_PAGE='225',
 XY='(-11325,-2300)',
 ROT='0',
 VER='1',
 PACK_TYPE='0402LF',
 LOCATION='R342',
 CDS_LIB='pure_quanta',
 CDS_PART_NAME='Q_RES_0402LF-0,5%,1/16W,CHIP,CA',
 WATTAGE='1/16W',
 TOLERANCE='5%',
 MATERIAL='CHIP',
 VALUE='0',
 PRIM_FILE='./archive_libs/logical/q_res/chips/chips.prt';

PART_NAME
 R344 'Q_RES_0402LF-0,5%,1/16W,CHIP,CA':;

SECTION_NUMBER 1
 '@S9S_MB_2U_LIB.S9S_MB_2U(SCH_1):PAGE322_I157@PURE_QUANTA.Q_RES(CHIPS)':
 C_PATH='@s9s_mb_2u_lib.s9s_mb_2u(sch_1):page322_i157@pure_quanta.q_res(chips)',
 P_PATH='@s9s_mb_2u_lib.s9s_mb_2u(sch_1):page225_i157@pure_quanta.q_res(chips)',
 PATH='I157',
 DRAWING='@S9S_MB_2U_LIB.S9S_MB_2U(SCH_1):PAGE322',
 PHYS_PAGE='225',
 XY='(-12400,-3100)',
 ROT='0',
 VER='1',
 PACK_TYPE='0402LF',
 CDS_LIB='pure_quanta',
 CDS_PART_NAME='Q_RES_0402LF-0,5%,1/16W,CHIP,CA',
 WATTAGE='1/16W',
 TOLERANCE='5%',
 MATERIAL='CHIP',
 VALUE='0',
 PRIM_FILE='./archive_libs/logical/q_res/chips/chips.prt';

PART_NAME
 R345 'Q_RES_0402LF-0,5%,1/16W,CHIP,CA':;

SECTION_NUMBER 1
 '@S9S_MB_2U_LIB.S9S_MB_2U(SCH_1):PAGE322_I158@PURE_QUANTA.Q_RES(CHIPS)':
 C_PATH='@s9s_mb_2u_lib.s9s_mb_2u(sch_1):page322_i158@pure_quanta.q_res(chips)',
 P_PATH='@s9s_mb_2u_lib.s9s_mb_2u(sch_1):page225_i158@pure_quanta.q_res(chips)',
 PATH='I158',
 DRAWING='@S9S_MB_2U_LIB.S9S_MB_2U(SCH_1):PAGE322',
 PHYS_PAGE='225',
 XY='(-12400,-3150)',
 ROT='0',
 VER='1',
 PACK_TYPE='0402LF',
 CDS_LIB='pure_quanta',
 CDS_PART_NAME='Q_RES_0402LF-0,5%,1/16W,CHIP,CA',
 WATTAGE='1/16W',
 TOLERANCE='5%',
 MATERIAL='CHIP',
 VALUE='0',
 PRIM_FILE='./archive_libs/logical/q_res/chips/chips.prt';

PART_NAME
 R346 'Q_RES_0402LF-0,5%,1/16W,CHIP,CA':;

SECTION_NUMBER 1
 '@S9S_MB_2U_LIB.S9S_MB_2U(SCH_1):PAGE322_I171@PURE_QUANTA.Q_RES(CHIPS)':
 C_PATH='@s9s_mb_2u_lib.s9s_mb_2u(sch_1):page322_i171@pure_quanta.q_res(chips)',
 P_PATH='@s9s_mb_2u_lib.s9s_mb_2u(sch_1):page225_i171@pure_quanta.q_res(chips)',
 PATH='I171',
 DRAWING='@S9S_MB_2U_LIB.S9S_MB_2U(SCH_1):PAGE322',
 PHYS_PAGE='225',
 XY='(-11325,-3150)',
 ROT='0',
 VER='1',
 PACK_TYPE='0402LF',
 LOCATION='R346',
 CDS_LIB='pure_quanta',
 CDS_PART_NAME='Q_RES_0402LF-0,5%,1/16W,CHIP,CA',
 WATTAGE='1/16W',
 TOLERANCE='5%',
 MATERIAL='CHIP',
 VALUE='0',
 PRIM_FILE='./archive_libs/logical/q_res/chips/chips.prt';

PART_NAME
 R361 'Q_RES_0402LF-1K,1%,1/16W,CHIP,A':;

SECTION_NUMBER 1
 '@S9S_MB_2U_LIB.S9S_MB_2U(SCH_1):PAGE264_I46@PURE_QUANTA.Q_RES(CHIPS)':
 C_PATH='@s9s_mb_2u_lib.s9s_mb_2u(sch_1):page264_i46@pure_quanta.q_res(chips)',
 P_PATH='@s9s_mb_2u_lib.s9s_mb_2u(sch_1):page278_i46@pure_quanta.q_res(chips)',
 PATH='I46',
 DRAWING='@S9S_MB_2U_LIB.S9S_MB_2U(SCH_1):PAGE264',
 PHYS_PAGE='278',
 XY='(-9850,9100)',
 ROT='0',
 VER='1',
 PACK_TYPE='0402LF',
 LOCATION='R361',
 CDS_LIB='pure_quanta',
 CDS_PART_NAME='Q_RES_0402LF-1K,1%,1/16W,CHIP,A',
 WATTAGE='1/16W',
 TOLERANCE='1%',
 MATERIAL='CHIP',
 VALUE='1K',
 PRIM_FILE='./archive_libs/logical/q_res/chips/chips.prt';

PART_NAME
 R362 'Q_RES_0402LF-0,5%,1/16W,CHIP,CA':;

SECTION_NUMBER 1
 '@S9S_MB_2U_LIB.S9S_MB_2U(SCH_1):PAGE264_I44@PURE_QUANTA.Q_RES(CHIPS)':
 C_PATH='@s9s_mb_2u_lib.s9s_mb_2u(sch_1):page264_i44@pure_quanta.q_res(chips)',
 P_PATH='@s9s_mb_2u_lib.s9s_mb_2u(sch_1):page278_i44@pure_quanta.q_res(chips)',
 PATH='I44',
 DRAWING='@S9S_MB_2U_LIB.S9S_MB_2U(SCH_1):PAGE264',
 PHYS_PAGE='278',
 XY='(-9850,8950)',
 ROT='0',
 VER='1',
 PACK_TYPE='0402LF',
 LOCATION='R362',
 CDS_LIB='pure_quanta',
 CDS_PART_NAME='Q_RES_0402LF-0,5%,1/16W,CHIP,CA',
 WATTAGE='1/16W',
 TOLERANCE='5%',
 MATERIAL='CHIP',
 VALUE='0',
 PRIM_FILE='./archive_libs/logical/q_res/chips/chips.prt';

PART_NAME
 R363 'Q_RES_0402LF-0,5%,1/16W,CHIP,CA':;

SECTION_NUMBER 1
 '@S9S_MB_2U_LIB.S9S_MB_2U(SCH_1):PAGE264_I45@PURE_QUANTA.Q_RES(CHIPS)':
 C_PATH='@s9s_mb_2u_lib.s9s_mb_2u(sch_1):page264_i45@pure_quanta.q_res(chips)',
 P_PATH='@s9s_mb_2u_lib.s9s_mb_2u(sch_1):page278_i45@pure_quanta.q_res(chips)',
 PATH='I45',
 DRAWING='@S9S_MB_2U_LIB.S9S_MB_2U(SCH_1):PAGE264',
 PHYS_PAGE='278',
 XY='(-9850,8800)',
 ROT='0',
 VER='1',
 PACK_TYPE='0402LF',
 LOCATION='R363',
 CDS_LIB='pure_quanta',
 CDS_PART_NAME='Q_RES_0402LF-0,5%,1/16W,CHIP,CA',
 WATTAGE='1/16W',
 TOLERANCE='5%',
 MATERIAL='CHIP',
 VALUE='0',
 PRIM_FILE='./archive_libs/logical/q_res/chips/chips.prt';

PART_NAME
 R365 'Q_RES_0402LF-0,5%,1/16W,CHIP,CA':;

SECTION_NUMBER 1
 '@S9S_MB_2U_LIB.S9S_MB_2U(SCH_1):PAGE207_I273@PURE_QUANTA.Q_RES(CHIPS)':
 C_PATH='@s9s_mb_2u_lib.s9s_mb_2u(sch_1):page207_i273@pure_quanta.q_res(chips)',
 P_PATH='@s9s_mb_2u_lib.s9s_mb_2u(sch_1):page218_i273@pure_quanta.q_res(chips)',
 PATH='I273',
 DRAWING='@S9S_MB_2U_LIB.S9S_MB_2U(SCH_1):PAGE207',
 PHYS_PAGE='218',
 XY='(-3150,1325)',
 ROT='0',
 VER='1',
 PACK_TYPE='0402LF',
 CDS_LIB='pure_quanta',
 CDS_PART_NAME='Q_RES_0402LF-0,5%,1/16W,CHIP,CA',
 WATTAGE='1/16W',
 TOLERANCE='5%',
 MATERIAL='CHIP',
 VALUE='0',
 PRIM_FILE='./archive_libs/logical/q_res/chips/chips.prt';

PART_NAME
 R366 'Q_RES_0402LF-249,1%,1/16W,CHIPA':;

SECTION_NUMBER 1
 '@S9S_MB_2U_LIB.S9S_MB_2U(SCH_1):PAGE207_I280@PURE_QUANTA.Q_RES(CHIPS)':
 C_PATH='@s9s_mb_2u_lib.s9s_mb_2u(sch_1):page207_i280@pure_quanta.q_res(chips)',
 P_PATH='@s9s_mb_2u_lib.s9s_mb_2u(sch_1):page218_i280@pure_quanta.q_res(chips)',
 PATH='I280',
 DRAWING='@S9S_MB_2U_LIB.S9S_MB_2U(SCH_1):PAGE207',
 PHYS_PAGE='218',
 XY='(-1425,2000)',
 ROT='0',
 VER='2',
 PACK_TYPE='0402LF',
 LOCATION='R366',
 CDS_LIB='pure_quanta',
 CDS_PART_NAME='Q_RES_0402LF-249,1%,1/16W,CHIPA',
 WATTAGE='1/16W',
 TOLERANCE='1%',
 MATERIAL='CHIP',
 VALUE='249',
 PRIM_FILE='./archive_libs/logical/q_res/chips/chips.prt';

PART_NAME
 R367 'Q_RES_0402LF-1K,1%,1/16W,EMPTYA':;

SECTION_NUMBER 1
 '@S9S_MB_2U_LIB.S9S_MB_2U(SCH_1):PAGE186_I11@PURE_QUANTA.Q_RES(CHIPS)':
 C_PATH='@s9s_mb_2u_lib.s9s_mb_2u(sch_1):page186_i11@pure_quanta.q_res(chips)',
 P_PATH='@s9s_mb_2u_lib.s9s_mb_2u(sch_1):page198_i11@pure_quanta.q_res(chips)',
 PATH='I11',
 DRAWING='@S9S_MB_2U_LIB.S9S_MB_2U(SCH_1):PAGE186',
 PHYS_PAGE='198',
 XY='(-3475,1275)',
 ROT='0',
 VER='2',
 PACK_TYPE='0402LF',
 CDS_LIB='pure_quanta',
 CDS_PART_NAME='Q_RES_0402LF-1K,1%,1/16W,EMPTYA',
 WATTAGE='1/16W',
 TOLERANCE='1%',
 MATERIAL='EMPTY',
 VALUE='1K',
 PRIM_FILE='./archive_libs/logical/q_res/chips/chips.prt';

PART_NAME
 R369 'Q_RES_0402LF-1K,1%,1/16W,CHIP,A':;

SECTION_NUMBER 1
 '@S9S_MB_2U_LIB.S9S_MB_2U(SCH_1):PAGE186_I16@PURE_QUANTA.Q_RES(CHIPS)':
 C_PATH='@s9s_mb_2u_lib.s9s_mb_2u(sch_1):page186_i16@pure_quanta.q_res(chips)',
 P_PATH='@s9s_mb_2u_lib.s9s_mb_2u(sch_1):page198_i16@pure_quanta.q_res(chips)',
 PATH='I16',
 DRAWING='@S9S_MB_2U_LIB.S9S_MB_2U(SCH_1):PAGE186',
 PHYS_PAGE='198',
 XY='(-3475,-800)',
 ROT='0',
 VER='2',
 PACK_TYPE='0402LF',
 CDS_LIB='pure_quanta',
 CDS_PART_NAME='Q_RES_0402LF-1K,1%,1/16W,CHIP,A',
 WATTAGE='1/16W',
 TOLERANCE='1%',
 MATERIAL='CHIP',
 VALUE='1K',
 PRIM_FILE='./archive_libs/logical/q_res/chips/chips.prt';

PART_NAME
 R371 'Q_RES_0402LF-1K,1%,1/16W,EMPTYA':;

SECTION_NUMBER 1
 '@S9S_MB_2U_LIB.S9S_MB_2U(SCH_1):PAGE186_I45@PURE_QUANTA.Q_RES(CHIPS)':
 C_PATH='@s9s_mb_2u_lib.s9s_mb_2u(sch_1):page186_i45@pure_quanta.q_res(chips)',
 P_PATH='@s9s_mb_2u_lib.s9s_mb_2u(sch_1):page198_i45@pure_quanta.q_res(chips)',
 PATH='I45',
 DRAWING='@S9S_MB_2U_LIB.S9S_MB_2U(SCH_1):PAGE186',
 PHYS_PAGE='198',
 XY='(-350,3300)',
 ROT='0',
 VER='2',
 PACK_TYPE='0402LF',
 CDS_LIB='pure_quanta',
 CDS_PART_NAME='Q_RES_0402LF-1K,1%,1/16W,EMPTYA',
 WATTAGE='1/16W',
 TOLERANCE='1%',
 MATERIAL='EMPTY',
 VALUE='1K',
 PRIM_FILE='./archive_libs/logical/q_res/chips/chips.prt';

PART_NAME
 R372 'Q_RES_0402LF-10K,1%,1/16W,CHIPA':;

SECTION_NUMBER 1
 '@S9S_MB_2U_LIB.S9S_MB_2U(SCH_1):PAGE186_I46@PURE_QUANTA.Q_RES(CHIPS)':
 C_PATH='@s9s_mb_2u_lib.s9s_mb_2u(sch_1):page186_i46@pure_quanta.q_res(chips)',
 P_PATH='@s9s_mb_2u_lib.s9s_mb_2u(sch_1):page198_i46@pure_quanta.q_res(chips)',
 PATH='I46',
 DRAWING='@S9S_MB_2U_LIB.S9S_MB_2U(SCH_1):PAGE186',
 PHYS_PAGE='198',
 XY='(-350,2775)',
 ROT='0',
 VER='2',
 PACK_TYPE='0402LF',
 CDS_LIB='pure_quanta',
 CDS_PART_NAME='Q_RES_0402LF-10K,1%,1/16W,CHIPA',
 WATTAGE='1/16W',
 TOLERANCE='1%',
 MATERIAL='CHIP',
 VALUE='10K',
 PRIM_FILE='./archive_libs/logical/q_res/chips/chips.prt';

PART_NAME
 R374 'Q_RES_0402LF-1K,1%,1/16W,EMPTYA':;

SECTION_NUMBER 1
 '@S9S_MB_2U_LIB.S9S_MB_2U(SCH_1):PAGE186_I60@PURE_QUANTA.Q_RES(CHIPS)':
 C_PATH='@s9s_mb_2u_lib.s9s_mb_2u(sch_1):page186_i60@pure_quanta.q_res(chips)',
 P_PATH='@s9s_mb_2u_lib.s9s_mb_2u(sch_1):page198_i60@pure_quanta.q_res(chips)',
 PATH='I60',
 DRAWING='@S9S_MB_2U_LIB.S9S_MB_2U(SCH_1):PAGE186',
 PHYS_PAGE='198',
 XY='(-350,-800)',
 ROT='0',
 VER='2',
 PACK_TYPE='0402LF',
 CDS_LIB='pure_quanta',
 CDS_PART_NAME='Q_RES_0402LF-1K,1%,1/16W,EMPTYA',
 WATTAGE='1/16W',
 TOLERANCE='1%',
 MATERIAL='EMPTY',
 VALUE='1K',
 PRIM_FILE='./archive_libs/logical/q_res/chips/chips.prt';

PART_NAME
 R375 'Q_RES_0402LF-10K,1%,1/16W,CHIPA':;

SECTION_NUMBER 1
 '@S9S_MB_2U_LIB.S9S_MB_2U(SCH_1):PAGE186_I61@PURE_QUANTA.Q_RES(CHIPS)':
 C_PATH='@s9s_mb_2u_lib.s9s_mb_2u(sch_1):page186_i61@pure_quanta.q_res(chips)',
 P_PATH='@s9s_mb_2u_lib.s9s_mb_2u(sch_1):page198_i61@pure_quanta.q_res(chips)',
 PATH='I61',
 DRAWING='@S9S_MB_2U_LIB.S9S_MB_2U(SCH_1):PAGE186',
 PHYS_PAGE='198',
 XY='(-350,-1275)',
 ROT='0',
 VER='2',
 PACK_TYPE='0402LF',
 CDS_LIB='pure_quanta',
 CDS_PART_NAME='Q_RES_0402LF-10K,1%,1/16W,CHIPA',
 WATTAGE='1/16W',
 TOLERANCE='1%',
 MATERIAL='CHIP',
 VALUE='10K',
 PRIM_FILE='./archive_libs/logical/q_res/chips/chips.prt';

PART_NAME
 R378 'Q_RES_0402LF-1K,1%,1/16W,EMPTYA':;

SECTION_NUMBER 1
 '@S9S_MB_2U_LIB.S9S_MB_2U(SCH_1):PAGE186_I77@PURE_QUANTA.Q_RES(CHIPS)':
 C_PATH='@s9s_mb_2u_lib.s9s_mb_2u(sch_1):page186_i77@pure_quanta.q_res(chips)',
 P_PATH='@s9s_mb_2u_lib.s9s_mb_2u(sch_1):page198_i77@pure_quanta.q_res(chips)',
 PATH='I77',
 DRAWING='@S9S_MB_2U_LIB.S9S_MB_2U(SCH_1):PAGE186',
 PHYS_PAGE='198',
 XY='(2800,1250)',
 ROT='0',
 VER='2',
 PACK_TYPE='0402LF',
 CDS_LIB='pure_quanta',
 CDS_PART_NAME='Q_RES_0402LF-1K,1%,1/16W,EMPTYA',
 WATTAGE='1/16W',
 TOLERANCE='1%',
 MATERIAL='EMPTY',
 VALUE='1K',
 PRIM_FILE='./archive_libs/logical/q_res/chips/chips.prt';

PART_NAME
 R379 'Q_RES_0402LF-1K,1%,1/16W,CHIP,A':;

SECTION_NUMBER 1
 '@S9S_MB_2U_LIB.S9S_MB_2U(SCH_1):PAGE186_I76@PURE_QUANTA.Q_RES(CHIPS)':
 C_PATH='@s9s_mb_2u_lib.s9s_mb_2u(sch_1):page186_i76@pure_quanta.q_res(chips)',
 P_PATH='@s9s_mb_2u_lib.s9s_mb_2u(sch_1):page198_i76@pure_quanta.q_res(chips)',
 PATH='I76',
 DRAWING='@S9S_MB_2U_LIB.S9S_MB_2U(SCH_1):PAGE186',
 PHYS_PAGE='198',
 XY='(2800,775)',
 ROT='0',
 VER='2',
 PACK_TYPE='0402LF',
 CDS_LIB='pure_quanta',
 CDS_PART_NAME='Q_RES_0402LF-1K,1%,1/16W,CHIP,A',
 WATTAGE='1/16W',
 TOLERANCE='1%',
 MATERIAL='CHIP',
 VALUE='1K',
 PRIM_FILE='./archive_libs/logical/q_res/chips/chips.prt';

PART_NAME
 R380 'Q_RES_0402LF-1K,1%,1/16W,EMPTYA':;

SECTION_NUMBER 1
 '@S9S_MB_2U_LIB.S9S_MB_2U(SCH_1):PAGE186_I78@PURE_QUANTA.Q_RES(CHIPS)':
 C_PATH='@s9s_mb_2u_lib.s9s_mb_2u(sch_1):page186_i78@pure_quanta.q_res(chips)',
 P_PATH='@s9s_mb_2u_lib.s9s_mb_2u(sch_1):page198_i78@pure_quanta.q_res(chips)',
 PATH='I78',
 DRAWING='@S9S_MB_2U_LIB.S9S_MB_2U(SCH_1):PAGE186',
 PHYS_PAGE='198',
 XY='(2800,-775)',
 ROT='0',
 VER='2',
 PACK_TYPE='0402LF',
 CDS_LIB='pure_quanta',
 CDS_PART_NAME='Q_RES_0402LF-1K,1%,1/16W,EMPTYA',
 WATTAGE='1/16W',
 TOLERANCE='1%',
 MATERIAL='EMPTY',
 VALUE='1K',
 PRIM_FILE='./archive_libs/logical/q_res/chips/chips.prt';

PART_NAME
 R381 'Q_RES_0402LF-10K,1%,1/16W,CHIPA':;

SECTION_NUMBER 1
 '@S9S_MB_2U_LIB.S9S_MB_2U(SCH_1):PAGE186_I81@PURE_QUANTA.Q_RES(CHIPS)':
 C_PATH='@s9s_mb_2u_lib.s9s_mb_2u(sch_1):page186_i81@pure_quanta.q_res(chips)',
 P_PATH='@s9s_mb_2u_lib.s9s_mb_2u(sch_1):page198_i81@pure_quanta.q_res(chips)',
 PATH='I81',
 DRAWING='@S9S_MB_2U_LIB.S9S_MB_2U(SCH_1):PAGE186',
 PHYS_PAGE='198',
 XY='(2800,-1300)',
 ROT='0',
 VER='2',
 PACK_TYPE='0402LF',
 CDS_LIB='pure_quanta',
 CDS_PART_NAME='Q_RES_0402LF-10K,1%,1/16W,CHIPA',
 WATTAGE='1/16W',
 TOLERANCE='1%',
 MATERIAL='CHIP',
 VALUE='10K',
 PRIM_FILE='./archive_libs/logical/q_res/chips/chips.prt';

PART_NAME
 R401 'Q_RES_0402LF-10K,1%,1/16W,EMPTA':;

SECTION_NUMBER 1
 '@S9S_MB_2U_LIB.S9S_MB_2U(SCH_1):PAGE192_I69@PURE_QUANTA.Q_RES(CHIPS)':
 C_PATH='@s9s_mb_2u_lib.s9s_mb_2u(sch_1):page192_i69@pure_quanta.q_res(chips)',
 P_PATH='@s9s_mb_2u_lib.s9s_mb_2u(sch_1):page204_i69@pure_quanta.q_res(chips)',
 PATH='I69',
 DRAWING='@S9S_MB_2U_LIB.S9S_MB_2U(SCH_1):PAGE192',
 PHYS_PAGE='204',
 XY='(-4925,-850)',
 ROT='0',
 VER='1',
 PACK_TYPE='0402LF',
 CDS_LIB='pure_quanta',
 CDS_PART_NAME='Q_RES_0402LF-10K,1%,1/16W,EMPTA',
 WATTAGE='1/16W',
 TOLERANCE='1%',
 MATERIAL='EMPTY',
 VALUE='10K',
 PRIM_FILE='./archive_libs/logical/q_res/chips/chips.prt';

PART_NAME
 R409 'Q_RES_0402LF-4.7K,1%,1/16W,EMPA':;

SECTION_NUMBER 1
 '@S9S_MB_2U_LIB.S9S_MB_2U(SCH_1):PAGE150_I5@PURE_QUANTA.Q_RES(CHIPS)':
 C_PATH='@s9s_mb_2u_lib.s9s_mb_2u(sch_1):page150_i5@pure_quanta.q_res(chips)',
 P_PATH='@s9s_mb_2u_lib.s9s_mb_2u(sch_1):page153_i5@pure_quanta.q_res(chips)',
 PATH='I5',
 DRAWING='@S9S_MB_2U_LIB.S9S_MB_2U(SCH_1):PAGE150',
 PHYS_PAGE='153',
 XY='(-4325,2250)',
 ROT='0',
 VER='2',
 PACK_TYPE='0402LF',
 CDS_LIB='pure_quanta',
 CDS_PART_NAME='Q_RES_0402LF-4.7K,1%,1/16W,EMPA',
 WATTAGE='1/16W',
 TOLERANCE='1%',
 MATERIAL='EMPTY',
 VALUE='4.7K',
 PRIM_FILE='./archive_libs/logical/q_res/chips/chips.prt';

PART_NAME
 R410 'Q_RES_0402LF-4.7K,1%,1/16W,CHIA':;

SECTION_NUMBER 1
 '@S9S_MB_2U_LIB.S9S_MB_2U(SCH_1):PAGE150_I2@PURE_QUANTA.Q_RES(CHIPS)':
 C_PATH='@s9s_mb_2u_lib.s9s_mb_2u(sch_1):page150_i2@pure_quanta.q_res(chips)',
 P_PATH='@s9s_mb_2u_lib.s9s_mb_2u(sch_1):page153_i2@pure_quanta.q_res(chips)',
 PATH='I2',
 DRAWING='@S9S_MB_2U_LIB.S9S_MB_2U(SCH_1):PAGE150',
 PHYS_PAGE='153',
 XY='(-4325,1725)',
 ROT='0',
 VER='2',
 PACK_TYPE='0402LF',
 CDS_LIB='pure_quanta',
 CDS_PART_NAME='Q_RES_0402LF-4.7K,1%,1/16W,CHIA',
 WATTAGE='1/16W',
 TOLERANCE='1%',
 MATERIAL='CHIP',
 VALUE='4.7K',
 PRIM_FILE='./archive_libs/logical/q_res/chips/chips.prt';

PART_NAME
 R413 'Q_RES_0402LF-100K,1%,1/16W,CHIA':;

SECTION_NUMBER 1
 '@S9S_MB_2U_LIB.S9S_MB_2U(SCH_1):PAGE146_I43@PURE_QUANTA.Q_RES(CHIPS)':
 C_PATH='@s9s_mb_2u_lib.s9s_mb_2u(sch_1):page146_i43@pure_quanta.q_res(chips)',
 P_PATH='@s9s_mb_2u_lib.s9s_mb_2u(sch_1):page159_i43@pure_quanta.q_res(chips)',
 PATH='I43',
 DRAWING='@S9S_MB_2U_LIB.S9S_MB_2U(SCH_1):PAGE146',
 PHYS_PAGE='159',
 XY='(800,2600)',
 ROT='0',
 VER='1',
 PACK_TYPE='0402LF',
 LOCATION='R413',
 CDS_LIB='pure_quanta',
 CDS_PART_NAME='Q_RES_0402LF-100K,1%,1/16W,CHIA',
 WATTAGE='1/16W',
 TOLERANCE='1%',
 MATERIAL='CHIP',
 VALUE='100K',
 PRIM_FILE='./archive_libs/logical/q_res/chips/chips.prt';

PART_NAME
 R414 'Q_RES_0402LF-4.7K,1%,1/16W,EMPA':;

SECTION_NUMBER 1
 '@S9S_MB_2U_LIB.S9S_MB_2U(SCH_1):PAGE150_I6@PURE_QUANTA.Q_RES(CHIPS)':
 C_PATH='@s9s_mb_2u_lib.s9s_mb_2u(sch_1):page150_i6@pure_quanta.q_res(chips)',
 P_PATH='@s9s_mb_2u_lib.s9s_mb_2u(sch_1):page153_i6@pure_quanta.q_res(chips)',
 PATH='I6',
 DRAWING='@S9S_MB_2U_LIB.S9S_MB_2U(SCH_1):PAGE150',
 PHYS_PAGE='153',
 XY='(-3850,2250)',
 ROT='0',
 VER='2',
 PACK_TYPE='0402LF',
 CDS_LIB='pure_quanta',
 CDS_PART_NAME='Q_RES_0402LF-4.7K,1%,1/16W,EMPA',
 WATTAGE='1/16W',
 TOLERANCE='1%',
 MATERIAL='EMPTY',
 VALUE='4.7K',
 PRIM_FILE='./archive_libs/logical/q_res/chips/chips.prt';

PART_NAME
 R415 'Q_RES_0402LF-4.7K,1%,1/16W,CHIA':;

SECTION_NUMBER 1
 '@S9S_MB_2U_LIB.S9S_MB_2U(SCH_1):PAGE150_I4@PURE_QUANTA.Q_RES(CHIPS)':
 C_PATH='@s9s_mb_2u_lib.s9s_mb_2u(sch_1):page150_i4@pure_quanta.q_res(chips)',
 P_PATH='@s9s_mb_2u_lib.s9s_mb_2u(sch_1):page153_i4@pure_quanta.q_res(chips)',
 PATH='I4',
 DRAWING='@S9S_MB_2U_LIB.S9S_MB_2U(SCH_1):PAGE150',
 PHYS_PAGE='153',
 XY='(-3850,1725)',
 ROT='0',
 VER='2',
 PACK_TYPE='0402LF',
 CDS_LIB='pure_quanta',
 CDS_PART_NAME='Q_RES_0402LF-4.7K,1%,1/16W,CHIA',
 WATTAGE='1/16W',
 TOLERANCE='1%',
 MATERIAL='CHIP',
 VALUE='4.7K',
 PRIM_FILE='./archive_libs/logical/q_res/chips/chips.prt';

PART_NAME
 R416 'Q_RES_0402LF-0,5%,1/16W,CHIP,CA':;

SECTION_NUMBER 1
 '@S9S_MB_2U_LIB.S9S_MB_2U(SCH_1):PAGE150_I54@PURE_QUANTA.Q_RES(CHIPS)':
 C_PATH='@s9s_mb_2u_lib.s9s_mb_2u(sch_1):page150_i54@pure_quanta.q_res(chips)',
 P_PATH='@s9s_mb_2u_lib.s9s_mb_2u(sch_1):page153_i54@pure_quanta.q_res(chips)',
 PATH='I54',
 DRAWING='@S9S_MB_2U_LIB.S9S_MB_2U(SCH_1):PAGE150',
 PHYS_PAGE='153',
 XY='(-2900,6000)',
 ROT='0',
 VER='1',
 PACK_TYPE='0402LF',
 CDS_LIB='pure_quanta',
 CDS_PART_NAME='Q_RES_0402LF-0,5%,1/16W,CHIP,CA',
 WATTAGE='1/16W',
 TOLERANCE='5%',
 MATERIAL='CHIP',
 VALUE='0',
 PRIM_FILE='./archive_libs/logical/q_res/chips/chips.prt';

PART_NAME
 R417 'Q_RES_0402LF-0,5%,1/16W,CHIP,CA':;

SECTION_NUMBER 1
 '@S9S_MB_2U_LIB.S9S_MB_2U(SCH_1):PAGE150_I53@PURE_QUANTA.Q_RES(CHIPS)':
 C_PATH='@s9s_mb_2u_lib.s9s_mb_2u(sch_1):page150_i53@pure_quanta.q_res(chips)',
 P_PATH='@s9s_mb_2u_lib.s9s_mb_2u(sch_1):page153_i53@pure_quanta.q_res(chips)',
 PATH='I53',
 DRAWING='@S9S_MB_2U_LIB.S9S_MB_2U(SCH_1):PAGE150',
 PHYS_PAGE='153',
 XY='(-2900,5950)',
 ROT='0',
 VER='1',
 PACK_TYPE='0402LF',
 CDS_LIB='pure_quanta',
 CDS_PART_NAME='Q_RES_0402LF-0,5%,1/16W,CHIP,CA',
 WATTAGE='1/16W',
 TOLERANCE='5%',
 MATERIAL='CHIP',
 VALUE='0',
 PRIM_FILE='./archive_libs/logical/q_res/chips/chips.prt';

PART_NAME
 R418 'Q_RES_0402LF-0,5%,1/16W,CHIP,CA':;

SECTION_NUMBER 1
 '@S9S_MB_2U_LIB.S9S_MB_2U(SCH_1):PAGE150_I52@PURE_QUANTA.Q_RES(CHIPS)':
 C_PATH='@s9s_mb_2u_lib.s9s_mb_2u(sch_1):page150_i52@pure_quanta.q_res(chips)',
 P_PATH='@s9s_mb_2u_lib.s9s_mb_2u(sch_1):page153_i52@pure_quanta.q_res(chips)',
 PATH='I52',
 DRAWING='@S9S_MB_2U_LIB.S9S_MB_2U(SCH_1):PAGE150',
 PHYS_PAGE='153',
 XY='(-2900,5900)',
 ROT='0',
 VER='1',
 PACK_TYPE='0402LF',
 CDS_LIB='pure_quanta',
 CDS_PART_NAME='Q_RES_0402LF-0,5%,1/16W,CHIP,CA',
 WATTAGE='1/16W',
 TOLERANCE='5%',
 MATERIAL='CHIP',
 VALUE='0',
 PRIM_FILE='./archive_libs/logical/q_res/chips/chips.prt';

PART_NAME
 R419 'Q_RES_0402LF-33.2,1%,1/16W,CHIA':;

SECTION_NUMBER 1
 '@S9S_MB_2U_LIB.S9S_MB_2U(SCH_1):PAGE152_I6@PURE_QUANTA.Q_RES(CHIPS)':
 C_PATH='@s9s_mb_2u_lib.s9s_mb_2u(sch_1):page152_i6@pure_quanta.q_res(chips)',
 P_PATH='@s9s_mb_2u_lib.s9s_mb_2u(sch_1):page155_i6@pure_quanta.q_res(chips)',
 PATH='I6',
 DRAWING='@S9S_MB_2U_LIB.S9S_MB_2U(SCH_1):PAGE152',
 PHYS_PAGE='155',
 XY='(-6250,7225)',
 ROT='0',
 VER='1',
 PACK_TYPE='0402LF',
 CDS_LIB='pure_quanta',
 CDS_PART_NAME='Q_RES_0402LF-33.2,1%,1/16W,CHIA',
 WATTAGE='1/16W',
 TOLERANCE='1%',
 MATERIAL='CHIP',
 VALUE='33.2',
 PRIM_FILE='./archive_libs/logical/q_res/chips/chips.prt';

PART_NAME
 R420 'Q_RES_0402LF-1K,1%,1/16W,CHIP,A':;

SECTION_NUMBER 1
 '@S9S_MB_2U_LIB.S9S_MB_2U(SCH_1):PAGE150_I218@PURE_QUANTA.Q_RES(CHIPS)':
 C_PATH='@s9s_mb_2u_lib.s9s_mb_2u(sch_1):page150_i218@pure_quanta.q_res(chips)',
 P_PATH='@s9s_mb_2u_lib.s9s_mb_2u(sch_1):page153_i218@pure_quanta.q_res(chips)',
 PATH='I218',
 DRAWING='@S9S_MB_2U_LIB.S9S_MB_2U(SCH_1):PAGE150',
 PHYS_PAGE='153',
 XY='(-775,1975)',
 ROT='0',
 VER='1',
 PACK_TYPE='0402LF',
 LOCATION='R420',
 CDS_LIB='pure_quanta',
 CDS_PART_NAME='Q_RES_0402LF-1K,1%,1/16W,CHIP,A',
 WATTAGE='1/16W',
 TOLERANCE='1%',
 MATERIAL='CHIP',
 VALUE='1K',
 PRIM_FILE='./archive_libs/logical/q_res/chips/chips.prt';

PART_NAME
 R421 'Q_RES_0402LF-10K,1%,1/16W,CHIPA':;

SECTION_NUMBER 1
 '@S9S_MB_2U_LIB.S9S_MB_2U(SCH_1):PAGE150_I217@PURE_QUANTA.Q_RES(CHIPS)':
 C_PATH='@s9s_mb_2u_lib.s9s_mb_2u(sch_1):page150_i217@pure_quanta.q_res(chips)',
 P_PATH='@s9s_mb_2u_lib.s9s_mb_2u(sch_1):page153_i217@pure_quanta.q_res(chips)',
 PATH='I217',
 DRAWING='@S9S_MB_2U_LIB.S9S_MB_2U(SCH_1):PAGE150',
 PHYS_PAGE='153',
 XY='(-775,1800)',
 ROT='0',
 VER='1',
 PACK_TYPE='0402LF',
 LOCATION='R421',
 CDS_LIB='pure_quanta',
 CDS_PART_NAME='Q_RES_0402LF-10K,1%,1/16W,CHIPA',
 WATTAGE='1/16W',
 TOLERANCE='1%',
 MATERIAL='CHIP',
 VALUE='10K',
 PRIM_FILE='./archive_libs/logical/q_res/chips/chips.prt';

PART_NAME
 R422 'Q_RES_0402LF-10K,1%,1/16W,CHIPA':;

SECTION_NUMBER 1
 '@S9S_MB_2U_LIB.S9S_MB_2U(SCH_1):PAGE150_I215@PURE_QUANTA.Q_RES(CHIPS)':
 C_PATH='@s9s_mb_2u_lib.s9s_mb_2u(sch_1):page150_i215@pure_quanta.q_res(chips)',
 P_PATH='@s9s_mb_2u_lib.s9s_mb_2u(sch_1):page153_i215@pure_quanta.q_res(chips)',
 PATH='I215',
 DRAWING='@S9S_MB_2U_LIB.S9S_MB_2U(SCH_1):PAGE150',
 PHYS_PAGE='153',
 XY='(-775,1450)',
 ROT='0',
 VER='1',
 PACK_TYPE='0402LF',
 LOCATION='R422',
 CDS_LIB='pure_quanta',
 CDS_PART_NAME='Q_RES_0402LF-10K,1%,1/16W,CHIPA',
 WATTAGE='1/16W',
 TOLERANCE='1%',
 MATERIAL='CHIP',
 VALUE='10K',
 PRIM_FILE='./archive_libs/logical/q_res/chips/chips.prt';

PART_NAME
 R423 'Q_RES_0402LF-1K,1%,1/16W,CHIP,A':;

SECTION_NUMBER 1
 '@S9S_MB_2U_LIB.S9S_MB_2U(SCH_1):PAGE150_I212@PURE_QUANTA.Q_RES(CHIPS)':
 C_PATH='@s9s_mb_2u_lib.s9s_mb_2u(sch_1):page150_i212@pure_quanta.q_res(chips)',
 P_PATH='@s9s_mb_2u_lib.s9s_mb_2u(sch_1):page153_i212@pure_quanta.q_res(chips)',
 PATH='I212',
 DRAWING='@S9S_MB_2U_LIB.S9S_MB_2U(SCH_1):PAGE150',
 PHYS_PAGE='153',
 XY='(-775,1625)',
 ROT='0',
 VER='1',
 PACK_TYPE='0402LF',
 LOCATION='R423',
 CDS_LIB='pure_quanta',
 CDS_PART_NAME='Q_RES_0402LF-1K,1%,1/16W,CHIP,A',
 WATTAGE='1/16W',
 TOLERANCE='1%',
 MATERIAL='CHIP',
 VALUE='1K',
 PRIM_FILE='./archive_libs/logical/q_res/chips/chips.prt';

PART_NAME
 R424 'Q_RES_0402LF-33.2,1%,1/16W,CHIA':;

SECTION_NUMBER 1
 '@S9S_MB_2U_LIB.S9S_MB_2U(SCH_1):PAGE150_I151@PURE_QUANTA.Q_RES(CHIPS)':
 C_PATH='@s9s_mb_2u_lib.s9s_mb_2u(sch_1):page150_i151@pure_quanta.q_res(chips)',
 P_PATH='@s9s_mb_2u_lib.s9s_mb_2u(sch_1):page153_i151@pure_quanta.q_res(chips)',
 PATH='I151',
 DRAWING='@S9S_MB_2U_LIB.S9S_MB_2U(SCH_1):PAGE150',
 PHYS_PAGE='153',
 XY='(1750,6000)',
 ROT='0',
 VER='1',
 PACK_TYPE='0402LF',
 CDS_LIB='pure_quanta',
 CDS_PART_NAME='Q_RES_0402LF-33.2,1%,1/16W,CHIA',
 WATTAGE='1/16W',
 TOLERANCE='1%',
 MATERIAL='CHIP',
 VALUE='33.2',
 PRIM_FILE='./archive_libs/logical/q_res/chips/chips.prt';

PART_NAME
 R425 'Q_RES_0402LF-200,1%,1/16W,CHIPA':;

SECTION_NUMBER 1
 '@S9S_MB_2U_LIB.S9S_MB_2U(SCH_1):PAGE150_I220@PURE_QUANTA.Q_RES(CHIPS)':
 C_PATH='@s9s_mb_2u_lib.s9s_mb_2u(sch_1):page150_i220@pure_quanta.q_res(chips)',
 P_PATH='@s9s_mb_2u_lib.s9s_mb_2u(sch_1):page153_i220@pure_quanta.q_res(chips)',
 PATH='I220',
 DRAWING='@S9S_MB_2U_LIB.S9S_MB_2U(SCH_1):PAGE150',
 PHYS_PAGE='153',
 XY='(1750,5950)',
 ROT='0',
 VER='1',
 PACK_TYPE='0402LF',
 LOCATION='R425',
 CDS_LIB='pure_quanta',
 CDS_PART_NAME='Q_RES_0402LF-200,1%,1/16W,CHIPA',
 WATTAGE='1/16W',
 TOLERANCE='1%',
 MATERIAL='CHIP',
 VALUE='200',
 PRIM_FILE='./archive_libs/logical/q_res/chips/chips.prt';

PART_NAME
 R429 'Q_RES_0402LF-0,5%,1/16W,CHIP,CA':;

SECTION_NUMBER 1
 '@S9S_MB_2U_LIB.S9S_MB_2U(SCH_1):PAGE150_I58@PURE_QUANTA.Q_RES(CHIPS)':
 C_PATH='@s9s_mb_2u_lib.s9s_mb_2u(sch_1):page150_i58@pure_quanta.q_res(chips)',
 P_PATH='@s9s_mb_2u_lib.s9s_mb_2u(sch_1):page153_i58@pure_quanta.q_res(chips)',
 PATH='I58',
 DRAWING='@S9S_MB_2U_LIB.S9S_MB_2U(SCH_1):PAGE150',
 PHYS_PAGE='153',
 XY='(-2900,7050)',
 ROT='0',
 VER='1',
 PACK_TYPE='0402LF',
 CDS_LIB='pure_quanta',
 CDS_PART_NAME='Q_RES_0402LF-0,5%,1/16W,CHIP,CA',
 WATTAGE='1/16W',
 TOLERANCE='5%',
 MATERIAL='CHIP',
 VALUE='0',
 PRIM_FILE='./archive_libs/logical/q_res/chips/chips.prt';

PART_NAME
 R435 'Q_RES_0402LF-33.2,1%,1/16W,CHIA':;

SECTION_NUMBER 1
 '@S9S_MB_2U_LIB.S9S_MB_2U(SCH_1):PAGE152_I8@PURE_QUANTA.Q_RES(CHIPS)':
 C_PATH='@s9s_mb_2u_lib.s9s_mb_2u(sch_1):page152_i8@pure_quanta.q_res(chips)',
 P_PATH='@s9s_mb_2u_lib.s9s_mb_2u(sch_1):page155_i8@pure_quanta.q_res(chips)',
 PATH='I8',
 DRAWING='@S9S_MB_2U_LIB.S9S_MB_2U(SCH_1):PAGE152',
 PHYS_PAGE='155',
 XY='(-6250,7000)',
 ROT='0',
 VER='1',
 PACK_TYPE='0402LF',
 CDS_LIB='pure_quanta',
 CDS_PART_NAME='Q_RES_0402LF-33.2,1%,1/16W,CHIA',
 WATTAGE='1/16W',
 TOLERANCE='1%',
 MATERIAL='CHIP',
 VALUE='33.2',
 PRIM_FILE='./archive_libs/logical/q_res/chips/chips.prt';

PART_NAME
 R442 'Q_RES_0603LF-1,1%,1/10W,CHIP,CA':;

SECTION_NUMBER 1
 '@S9S_MB_2U_LIB.S9S_MB_2U(SCH_1):PAGE199_I36@PURE_QUANTA.Q_RES(CHIPS)':
 C_PATH='@s9s_mb_2u_lib.s9s_mb_2u(sch_1):page199_i36@pure_quanta.q_res(chips)',
 P_PATH='@s9s_mb_2u_lib.s9s_mb_2u(sch_1):page210_i36@pure_quanta.q_res(chips)',
 PATH='I36',
 DRAWING='@S9S_MB_2U_LIB.S9S_MB_2U(SCH_1):PAGE199',
 PHYS_PAGE='210',
 XY='(-9775,6450)',
 ROT='0',
 VER='1',
 PACK_TYPE='0603LF',
 CDS_LIB='pure_quanta',
 CDS_PART_NAME='Q_RES_0603LF-1,1%,1/10W,CHIP,CA',
 WATTAGE='1/10W',
 TOLERANCE='1%',
 MATERIAL='CHIP',
 VALUE='1',
 PRIM_FILE='./archive_libs/logical/q_res/chips/chips.prt';

PART_NAME
 R444 'Q_RES_0402LF-0,5%,1/16W,CHIP,CA':;

SECTION_NUMBER 1
 '@S9S_MB_2U_LIB.S9S_MB_2U(SCH_1):PAGE150_I118@PURE_QUANTA.Q_RES(CHIPS)':
 C_PATH='@s9s_mb_2u_lib.s9s_mb_2u(sch_1):page150_i118@pure_quanta.q_res(chips)',
 P_PATH='@s9s_mb_2u_lib.s9s_mb_2u(sch_1):page153_i118@pure_quanta.q_res(chips)',
 PATH='I118',
 DRAWING='@S9S_MB_2U_LIB.S9S_MB_2U(SCH_1):PAGE150',
 PHYS_PAGE='153',
 XY='(1500,2750)',
 ROT='0',
 VER='1',
 PACK_TYPE='0402LF',
 CDS_LIB='pure_quanta',
 CDS_PART_NAME='Q_RES_0402LF-0,5%,1/16W,CHIP,CA',
 WATTAGE='1/16W',
 TOLERANCE='5%',
 MATERIAL='CHIP',
 VALUE='0',
 PRIM_FILE='./archive_libs/logical/q_res/chips/chips.prt';

PART_NAME
 R445 'Q_RES_0402LF-0,5%,1/16W,CHIP,CA':;

SECTION_NUMBER 1
 '@S9S_MB_2U_LIB.S9S_MB_2U(SCH_1):PAGE150_I119@PURE_QUANTA.Q_RES(CHIPS)':
 C_PATH='@s9s_mb_2u_lib.s9s_mb_2u(sch_1):page150_i119@pure_quanta.q_res(chips)',
 P_PATH='@s9s_mb_2u_lib.s9s_mb_2u(sch_1):page153_i119@pure_quanta.q_res(chips)',
 PATH='I119',
 DRAWING='@S9S_MB_2U_LIB.S9S_MB_2U(SCH_1):PAGE150',
 PHYS_PAGE='153',
 XY='(1500,2700)',
 ROT='0',
 VER='1',
 PACK_TYPE='0402LF',
 CDS_LIB='pure_quanta',
 CDS_PART_NAME='Q_RES_0402LF-0,5%,1/16W,CHIP,CA',
 WATTAGE='1/16W',
 TOLERANCE='5%',
 MATERIAL='CHIP',
 VALUE='0',
 PRIM_FILE='./archive_libs/logical/q_res/chips/chips.prt';

PART_NAME
 R447 'Q_RES_0603LF-1,1%,1/10W,CHIP,CA':;

SECTION_NUMBER 1
 '@S9S_MB_2U_LIB.S9S_MB_2U(SCH_1):PAGE199_I55@PURE_QUANTA.Q_RES(CHIPS)':
 C_PATH='@s9s_mb_2u_lib.s9s_mb_2u(sch_1):page199_i55@pure_quanta.q_res(chips)',
 P_PATH='@s9s_mb_2u_lib.s9s_mb_2u(sch_1):page210_i55@pure_quanta.q_res(chips)',
 PATH='I55',
 DRAWING='@S9S_MB_2U_LIB.S9S_MB_2U(SCH_1):PAGE199',
 PHYS_PAGE='210',
 XY='(-9775,5150)',
 ROT='0',
 VER='1',
 PACK_TYPE='0603LF',
 CDS_LIB='pure_quanta',
 CDS_PART_NAME='Q_RES_0603LF-1,1%,1/10W,CHIP,CA',
 WATTAGE='1/10W',
 TOLERANCE='1%',
 MATERIAL='CHIP',
 VALUE='1',
 PRIM_FILE='./archive_libs/logical/q_res/chips/chips.prt';

PART_NAME
 R448 'Q_RES_0402LF-0,5%,1/16W,EMPTY,A':;

SECTION_NUMBER 1
 '@S9S_MB_2U_LIB.S9S_MB_2U(SCH_1):PAGE224_I13@PURE_QUANTA.Q_RES(CHIPS)':
 C_PATH='@s9s_mb_2u_lib.s9s_mb_2u(sch_1):page224_i13@pure_quanta.q_res(chips)',
 P_PATH='@s9s_mb_2u_lib.s9s_mb_2u(sch_1):page236_i13@pure_quanta.q_res(chips)',
 PATH='I13',
 DRAWING='@S9S_MB_2U_LIB.S9S_MB_2U(SCH_1):PAGE224',
 PHYS_PAGE='236',
 XY='(1750,4800)',
 ROT='0',
 VER='2',
 PACK_TYPE='0402LF',
 CDS_LIB='pure_quanta',
 CDS_PART_NAME='Q_RES_0402LF-0,5%,1/16W,EMPTY,A',
 WATTAGE='1/16W',
 TOLERANCE='5%',
 MATERIAL='EMPTY',
 VALUE='0',
 PRIM_FILE='./archive_libs/logical/q_res/chips/chips.prt';

PART_NAME
 R453 'Q_RES_0402LF-10K,1%,1/16W,CHIPA':;

SECTION_NUMBER 1
 '@S9S_MB_2U_LIB.S9S_MB_2U(SCH_1):PAGE174_I77@PURE_QUANTA.Q_RES(CHIPS)':
 C_PATH='@s9s_mb_2u_lib.s9s_mb_2u(sch_1):page174_i77@pure_quanta.q_res(chips)',
 P_PATH='@s9s_mb_2u_lib.s9s_mb_2u(sch_1):page182_i77@pure_quanta.q_res(chips)',
 PATH='I77',
 DRAWING='@S9S_MB_2U_LIB.S9S_MB_2U(SCH_1):PAGE174',
 PHYS_PAGE='182',
 XY='(-1375,2475)',
 ROT='0',
 VER='1',
 PACK_TYPE='0402LF',
 CDS_LIB='pure_quanta',
 CDS_PART_NAME='Q_RES_0402LF-10K,1%,1/16W,CHIPA',
 WATTAGE='1/16W',
 TOLERANCE='1%',
 MATERIAL='CHIP',
 VALUE='10K',
 PRIM_FILE='./archive_libs/logical/q_res/chips/chips.prt';

PART_NAME
 R456 'Q_RES_0402LF-10K,1%,1/16W,CHIPA':;

SECTION_NUMBER 1
 '@S9S_MB_2U_LIB.S9S_MB_2U(SCH_1):PAGE192_I66@PURE_QUANTA.Q_RES(CHIPS)':
 C_PATH='@s9s_mb_2u_lib.s9s_mb_2u(sch_1):page192_i66@pure_quanta.q_res(chips)',
 P_PATH='@s9s_mb_2u_lib.s9s_mb_2u(sch_1):page204_i66@pure_quanta.q_res(chips)',
 PATH='I66',
 DRAWING='@S9S_MB_2U_LIB.S9S_MB_2U(SCH_1):PAGE192',
 PHYS_PAGE='204',
 XY='(-1850,1300)',
 ROT='0',
 VER='1',
 PACK_TYPE='0402LF',
 CDS_LIB='pure_quanta',
 CDS_PART_NAME='Q_RES_0402LF-10K,1%,1/16W,CHIPA',
 WATTAGE='1/16W',
 TOLERANCE='1%',
 MATERIAL='CHIP',
 VALUE='10K',
 PRIM_FILE='./archive_libs/logical/q_res/chips/chips.prt';

PART_NAME
 R474 'Q_RES_0402LF-33.2,1%,1/16W,CHIA':;

SECTION_NUMBER 1
 '@S9S_MB_2U_LIB.S9S_MB_2U(SCH_1):PAGE175_I213@PURE_QUANTA.Q_RES(CHIPS)':
 C_PATH='@s9s_mb_2u_lib.s9s_mb_2u(sch_1):page175_i213@pure_quanta.q_res(chips)',
 P_PATH='@s9s_mb_2u_lib.s9s_mb_2u(sch_1):page183_i213@pure_quanta.q_res(chips)',
 PATH='I213',
 DRAWING='@S9S_MB_2U_LIB.S9S_MB_2U(SCH_1):PAGE175',
 PHYS_PAGE='183',
 XY='(2950,650)',
 ROT='0',
 VER='1',
 PACK_TYPE='0402LF',
 CDS_LIB='pure_quanta',
 CDS_PART_NAME='Q_RES_0402LF-33.2,1%,1/16W,CHIA',
 WATTAGE='1/16W',
 TOLERANCE='1%',
 MATERIAL='CHIP',
 VALUE='33.2',
 PRIM_FILE='./archive_libs/logical/q_res/chips/chips.prt';

PART_NAME
 R477 'Q_RES_0402LF-60.4,1%,1/16W,CHIA':;

SECTION_NUMBER 1
 '@S9S_MB_2U_LIB.S9S_MB_2U(SCH_1):PAGE171_I69@PURE_QUANTA.Q_RES(CHIPS)':
 C_PATH='@s9s_mb_2u_lib.s9s_mb_2u(sch_1):page171_i69@pure_quanta.q_res(chips)',
 P_PATH='@s9s_mb_2u_lib.s9s_mb_2u(sch_1):page179_i69@pure_quanta.q_res(chips)',
 PATH='I69',
 DRAWING='@S9S_MB_2U_LIB.S9S_MB_2U(SCH_1):PAGE171',
 PHYS_PAGE='179',
 XY='(-1775,3850)',
 ROT='0',
 VER='2',
 PACK_TYPE='0402LF',
 CDS_LIB='pure_quanta',
 CDS_PART_NAME='Q_RES_0402LF-60.4,1%,1/16W,CHIA',
 WATTAGE='1/16W',
 TOLERANCE='1%',
 MATERIAL='CHIP',
 VALUE='60.4',
 PRIM_FILE='./archive_libs/logical/q_res/chips/chips.prt';

PART_NAME
 R478 'Q_RES_0402LF-4.7K,1%,1/16W,CHIA':;

SECTION_NUMBER 1
 '@S9S_MB_2U_LIB.S9S_MB_2U(SCH_1):PAGE182_I176@PURE_QUANTA.Q_RES(CHIPS)':
 C_PATH='@s9s_mb_2u_lib.s9s_mb_2u(sch_1):page182_i176@pure_quanta.q_res(chips)',
 P_PATH='@s9s_mb_2u_lib.s9s_mb_2u(sch_1):page190_i176@pure_quanta.q_res(chips)',
 PATH='I176',
 DRAWING='@S9S_MB_2U_LIB.S9S_MB_2U(SCH_1):PAGE182',
 PHYS_PAGE='190',
 XY='(6975,2700)',
 ROT='0',
 VER='2',
 PACK_TYPE='0402LF',
 CDS_LIB='pure_quanta',
 CDS_PART_NAME='Q_RES_0402LF-4.7K,1%,1/16W,CHIA',
 WATTAGE='1/16W',
 TOLERANCE='1%',
 MATERIAL='CHIP',
 VALUE='4.7K',
 PRIM_FILE='./archive_libs/logical/q_res/chips/chips.prt';

PART_NAME
 R480 'Q_RES_0402LF-0,5%,1/16W,CHIP,CA':;

SECTION_NUMBER 1
 '@S9S_MB_2U_LIB.S9S_MB_2U(SCH_1):PAGE226_I59@PURE_QUANTA.Q_RES(CHIPS)':
 C_PATH='@s9s_mb_2u_lib.s9s_mb_2u(sch_1):page226_i59@pure_quanta.q_res(chips)',
 P_PATH='@s9s_mb_2u_lib.s9s_mb_2u(sch_1):page239_i59@pure_quanta.q_res(chips)',
 PATH='I59',
 DRAWING='@S9S_MB_2U_LIB.S9S_MB_2U(SCH_1):PAGE226',
 PHYS_PAGE='239',
 XY='(-13050,3200)',
 ROT='0',
 VER='1',
 PACK_TYPE='0402LF',
 CDS_LIB='pure_quanta',
 CDS_PART_NAME='Q_RES_0402LF-0,5%,1/16W,CHIP,CA',
 WATTAGE='1/16W',
 TOLERANCE='5%',
 MATERIAL='CHIP',
 VALUE='0',
 PRIM_FILE='./archive_libs/logical/q_res/chips/chips.prt';

PART_NAME
 R481 'Q_RES_0402LF-0,5%,1/16W,CHIP,CA':;

SECTION_NUMBER 1
 '@S9S_MB_2U_LIB.S9S_MB_2U(SCH_1):PAGE226_I58@PURE_QUANTA.Q_RES(CHIPS)':
 C_PATH='@s9s_mb_2u_lib.s9s_mb_2u(sch_1):page226_i58@pure_quanta.q_res(chips)',
 P_PATH='@s9s_mb_2u_lib.s9s_mb_2u(sch_1):page239_i58@pure_quanta.q_res(chips)',
 PATH='I58',
 DRAWING='@S9S_MB_2U_LIB.S9S_MB_2U(SCH_1):PAGE226',
 PHYS_PAGE='239',
 XY='(-13050,3150)',
 ROT='0',
 VER='1',
 PACK_TYPE='0402LF',
 CDS_LIB='pure_quanta',
 CDS_PART_NAME='Q_RES_0402LF-0,5%,1/16W,CHIP,CA',
 WATTAGE='1/16W',
 TOLERANCE='5%',
 MATERIAL='CHIP',
 VALUE='0',
 PRIM_FILE='./archive_libs/logical/q_res/chips/chips.prt';

PART_NAME
 R482 'Q_RES_0402LF-0,5%,1/16W,CHIP,CA':;

SECTION_NUMBER 1
 '@S9S_MB_2U_LIB.S9S_MB_2U(SCH_1):PAGE226_I57@PURE_QUANTA.Q_RES(CHIPS)':
 C_PATH='@s9s_mb_2u_lib.s9s_mb_2u(sch_1):page226_i57@pure_quanta.q_res(chips)',
 P_PATH='@s9s_mb_2u_lib.s9s_mb_2u(sch_1):page239_i57@pure_quanta.q_res(chips)',
 PATH='I57',
 DRAWING='@S9S_MB_2U_LIB.S9S_MB_2U(SCH_1):PAGE226',
 PHYS_PAGE='239',
 XY='(-13050,3050)',
 ROT='0',
 VER='1',
 PACK_TYPE='0402LF',
 CDS_LIB='pure_quanta',
 CDS_PART_NAME='Q_RES_0402LF-0,5%,1/16W,CHIP,CA',
 WATTAGE='1/16W',
 TOLERANCE='5%',
 MATERIAL='CHIP',
 VALUE='0',
 PRIM_FILE='./archive_libs/logical/q_res/chips/chips.prt';

PART_NAME
 R483 'Q_RES_0402LF-0,5%,1/16W,CHIP,CA':;

SECTION_NUMBER 1
 '@S9S_MB_2U_LIB.S9S_MB_2U(SCH_1):PAGE226_I37@PURE_QUANTA.Q_RES(CHIPS)':
 C_PATH='@s9s_mb_2u_lib.s9s_mb_2u(sch_1):page226_i37@pure_quanta.q_res(chips)',
 P_PATH='@s9s_mb_2u_lib.s9s_mb_2u(sch_1):page239_i37@pure_quanta.q_res(chips)',
 PATH='I37',
 DRAWING='@S9S_MB_2U_LIB.S9S_MB_2U(SCH_1):PAGE226',
 PHYS_PAGE='239',
 XY='(-9950,1625)',
 ROT='0',
 VER='1',
 PACK_TYPE='0402LF',
 CDS_LIB='pure_quanta',
 CDS_PART_NAME='Q_RES_0402LF-0,5%,1/16W,CHIP,CA',
 WATTAGE='1/16W',
 TOLERANCE='5%',
 MATERIAL='CHIP',
 VALUE='0',
 PRIM_FILE='./archive_libs/logical/q_res/chips/chips.prt';

PART_NAME
 R486 'Q_RES_0402LF-0,5%,1/16W,CHIP,CA':;

SECTION_NUMBER 1
 '@S9S_MB_2U_LIB.S9S_MB_2U(SCH_1):PAGE182_I162@PURE_QUANTA.Q_RES(CHIPS)':
 C_PATH='@s9s_mb_2u_lib.s9s_mb_2u(sch_1):page182_i162@pure_quanta.q_res(chips)',
 P_PATH='@s9s_mb_2u_lib.s9s_mb_2u(sch_1):page190_i162@pure_quanta.q_res(chips)',
 PATH='I162',
 DRAWING='@S9S_MB_2U_LIB.S9S_MB_2U(SCH_1):PAGE182',
 PHYS_PAGE='190',
 XY='(6425,3350)',
 ROT='0',
 VER='1',
 PACK_TYPE='0402LF',
 CDS_LIB='pure_quanta',
 CDS_PART_NAME='Q_RES_0402LF-0,5%,1/16W,CHIP,CA',
 WATTAGE='1/16W',
 TOLERANCE='5%',
 MATERIAL='CHIP',
 VALUE='0',
 PRIM_FILE='./archive_libs/logical/q_res/chips/chips.prt';

PART_NAME
 R487 'Q_RES_0402LF-1K,1%,1/16W,CHIP,A':;

SECTION_NUMBER 1
 '@S9S_MB_2U_LIB.S9S_MB_2U(SCH_1):PAGE182_I173@PURE_QUANTA.Q_RES(CHIPS)':
 C_PATH='@s9s_mb_2u_lib.s9s_mb_2u(sch_1):page182_i173@pure_quanta.q_res(chips)',
 P_PATH='@s9s_mb_2u_lib.s9s_mb_2u(sch_1):page190_i173@pure_quanta.q_res(chips)',
 PATH='I173',
 DRAWING='@S9S_MB_2U_LIB.S9S_MB_2U(SCH_1):PAGE182',
 PHYS_PAGE='190',
 XY='(6975,3925)',
 ROT='2',
 VER='2',
 PACK_TYPE='0402LF',
 CDS_LIB='pure_quanta',
 CDS_PART_NAME='Q_RES_0402LF-1K,1%,1/16W,CHIP,A',
 WATTAGE='1/16W',
 TOLERANCE='1%',
 MATERIAL='CHIP',
 VALUE='1K',
 PRIM_FILE='./archive_libs/logical/q_res/chips/chips.prt';

PART_NAME
 R491 'Q_RES_0402LF-4.7K,1%,1/16W,EMPA':;

SECTION_NUMBER 1
 '@S9S_MB_2U_LIB.S9S_MB_2U(SCH_1):PAGE182_I164@PURE_QUANTA.Q_RES(CHIPS)':
 C_PATH='@s9s_mb_2u_lib.s9s_mb_2u(sch_1):page182_i164@pure_quanta.q_res(chips)',
 P_PATH='@s9s_mb_2u_lib.s9s_mb_2u(sch_1):page190_i164@pure_quanta.q_res(chips)',
 PATH='I164',
 DRAWING='@S9S_MB_2U_LIB.S9S_MB_2U(SCH_1):PAGE182',
 PHYS_PAGE='190',
 XY='(5450,3075)',
 ROT='0',
 VER='2',
 PACK_TYPE='0402LF',
 CDS_LIB='pure_quanta',
 CDS_PART_NAME='Q_RES_0402LF-4.7K,1%,1/16W,EMPA',
 WATTAGE='1/16W',
 TOLERANCE='1%',
 MATERIAL='EMPTY',
 VALUE='4.7K',
 PRIM_FILE='./archive_libs/logical/q_res/chips/chips.prt';

PART_NAME
 R494 'Q_RES_0402LF-1K,1%,1/16W,CHIP,A':;

SECTION_NUMBER 1
 '@S9S_MB_2U_LIB.S9S_MB_2U(SCH_1):PAGE174_I98@PURE_QUANTA.Q_RES(CHIPS)':
 C_PATH='@s9s_mb_2u_lib.s9s_mb_2u(sch_1):page174_i98@pure_quanta.q_res(chips)',
 P_PATH='@s9s_mb_2u_lib.s9s_mb_2u(sch_1):page182_i98@pure_quanta.q_res(chips)',
 PATH='I98',
 DRAWING='@S9S_MB_2U_LIB.S9S_MB_2U(SCH_1):PAGE174',
 PHYS_PAGE='182',
 XY='(-125,3375)',
 ROT='0',
 VER='2',
 PACK_TYPE='0402LF',
 LOCATION='R494',
 CDS_LIB='pure_quanta',
 CDS_PART_NAME='Q_RES_0402LF-1K,1%,1/16W,CHIP,A',
 WATTAGE='1/16W',
 TOLERANCE='1%',
 MATERIAL='CHIP',
 VALUE='1K',
 PRIM_FILE='./archive_libs/logical/q_res/chips/chips.prt';

PART_NAME
 R495 'Q_RES_0402LF-100,1%,1/16W,CHIPA':;

SECTION_NUMBER 1
 '@S9S_MB_2U_LIB.S9S_MB_2U(SCH_1):PAGE173_I1@PURE_QUANTA.Q_RES(CHIPS)':
 C_PATH='@s9s_mb_2u_lib.s9s_mb_2u(sch_1):page173_i1@pure_quanta.q_res(chips)',
 P_PATH='@s9s_mb_2u_lib.s9s_mb_2u(sch_1):page181_i1@pure_quanta.q_res(chips)',
 PATH='I1',
 DRAWING='@S9S_MB_2U_LIB.S9S_MB_2U(SCH_1):PAGE173',
 PHYS_PAGE='181',
 XY='(-2975,550)',
 ROT='0',
 VER='2',
 PACK_TYPE='0402LF',
 CDS_LIB='pure_quanta',
 CDS_PART_NAME='Q_RES_0402LF-100,1%,1/16W,CHIPA',
 WATTAGE='1/16W',
 TOLERANCE='1%',
 MATERIAL='CHIP',
 VALUE='100',
 PRIM_FILE='./archive_libs/logical/q_res/chips/chips.prt';

PART_NAME
 R496 'Q_RES_0402LF-113,1%,1/16W,CHIPA':;

SECTION_NUMBER 1
 '@S9S_MB_2U_LIB.S9S_MB_2U(SCH_1):PAGE172_I10@PURE_QUANTA.Q_RES(CHIPS)':
 C_PATH='@s9s_mb_2u_lib.s9s_mb_2u(sch_1):page172_i10@pure_quanta.q_res(chips)',
 P_PATH='@s9s_mb_2u_lib.s9s_mb_2u(sch_1):page180_i10@pure_quanta.q_res(chips)',
 PATH='I10',
 DRAWING='@S9S_MB_2U_LIB.S9S_MB_2U(SCH_1):PAGE172',
 PHYS_PAGE='180',
 XY='(-7300,3900)',
 ROT='0',
 VER='2',
 PACK_TYPE='0402LF',
 CDS_LIB='pure_quanta',
 CDS_PART_NAME='Q_RES_0402LF-113,1%,1/16W,CHIPA',
 WATTAGE='1/16W',
 TOLERANCE='1%',
 MATERIAL='CHIP',
 VALUE='113',
 PRIM_FILE='./archive_libs/logical/q_res/chips/chips.prt';

PART_NAME
 R497 'Q_RES_0402LF-200,1%,1/16W,CHIPA':;

SECTION_NUMBER 1
 '@S9S_MB_2U_LIB.S9S_MB_2U(SCH_1):PAGE179_I2@PURE_QUANTA.Q_RES(CHIPS)':
 C_PATH='@s9s_mb_2u_lib.s9s_mb_2u(sch_1):page179_i2@pure_quanta.q_res(chips)',
 P_PATH='@s9s_mb_2u_lib.s9s_mb_2u(sch_1):page187_i2@pure_quanta.q_res(chips)',
 PATH='I2',
 DRAWING='@S9S_MB_2U_LIB.S9S_MB_2U(SCH_1):PAGE179',
 PHYS_PAGE='187',
 XY='(3475,2850)',
 ROT='0',
 VER='2',
 PACK_TYPE='0402LF',
 CDS_LIB='pure_quanta',
 CDS_PART_NAME='Q_RES_0402LF-200,1%,1/16W,CHIPA',
 WATTAGE='1/16W',
 TOLERANCE='1%',
 MATERIAL='CHIP',
 VALUE='200',
 PRIM_FILE='./archive_libs/logical/q_res/chips/chips.prt';

PART_NAME
 R498 'Q_RES_0402LF-10K,1%,1/16W,CHIPA':;

SECTION_NUMBER 1
 '@S9S_MB_2U_LIB.S9S_MB_2U(SCH_1):PAGE177_I24@PURE_QUANTA.Q_RES(CHIPS)':
 C_PATH='@s9s_mb_2u_lib.s9s_mb_2u(sch_1):page177_i24@pure_quanta.q_res(chips)',
 P_PATH='@s9s_mb_2u_lib.s9s_mb_2u(sch_1):page185_i24@pure_quanta.q_res(chips)',
 PATH='I24',
 DRAWING='@S9S_MB_2U_LIB.S9S_MB_2U(SCH_1):PAGE177',
 PHYS_PAGE='185',
 XY='(3625,3550)',
 ROT='0',
 VER='2',
 PACK_TYPE='0402LF',
 CDS_LIB='pure_quanta',
 CDS_PART_NAME='Q_RES_0402LF-10K,1%,1/16W,CHIPA',
 WATTAGE='1/16W',
 TOLERANCE='1%',
 MATERIAL='CHIP',
 VALUE='10K',
 PRIM_FILE='./archive_libs/logical/q_res/chips/chips.prt';

PART_NAME
 R499 'Q_RES_0402LF-33.2,1%,1/16W,CHIA':;

SECTION_NUMBER 1
 '@S9S_MB_2U_LIB.S9S_MB_2U(SCH_1):PAGE177_I106@PURE_QUANTA.Q_RES(CHIPS)':
 C_PATH='@s9s_mb_2u_lib.s9s_mb_2u(sch_1):page177_i106@pure_quanta.q_res(chips)',
 P_PATH='@s9s_mb_2u_lib.s9s_mb_2u(sch_1):page185_i106@pure_quanta.q_res(chips)',
 PATH='I106',
 DRAWING='@S9S_MB_2U_LIB.S9S_MB_2U(SCH_1):PAGE177',
 PHYS_PAGE='185',
 XY='(4200,-1475)',
 ROT='0',
 VER='1',
 PACK_TYPE='0402LF',
 CDS_LIB='pure_quanta',
 CDS_PART_NAME='Q_RES_0402LF-33.2,1%,1/16W,CHIA',
 WATTAGE='1/16W',
 TOLERANCE='1%',
 MATERIAL='CHIP',
 VALUE='33.2',
 PRIM_FILE='./archive_libs/logical/q_res/chips/chips.prt';

PART_NAME
 R501 'Q_RES_0402LF-33.2,1%,1/16W,CHIA':;

SECTION_NUMBER 1
 '@S9S_MB_2U_LIB.S9S_MB_2U(SCH_1):PAGE177_I100@PURE_QUANTA.Q_RES(CHIPS)':
 C_PATH='@s9s_mb_2u_lib.s9s_mb_2u(sch_1):page177_i100@pure_quanta.q_res(chips)',
 P_PATH='@s9s_mb_2u_lib.s9s_mb_2u(sch_1):page185_i100@pure_quanta.q_res(chips)',
 PATH='I100',
 DRAWING='@S9S_MB_2U_LIB.S9S_MB_2U(SCH_1):PAGE177',
 PHYS_PAGE='185',
 XY='(4225,-750)',
 ROT='0',
 VER='1',
 PACK_TYPE='0402LF',
 CDS_LIB='pure_quanta',
 CDS_PART_NAME='Q_RES_0402LF-33.2,1%,1/16W,CHIA',
 WATTAGE='1/16W',
 TOLERANCE='1%',
 MATERIAL='CHIP',
 VALUE='33.2',
 PRIM_FILE='./archive_libs/logical/q_res/chips/chips.prt';

PART_NAME
 R502 'Q_RES_0402LF-20K,1%,1/16W,CHIPA':;

SECTION_NUMBER 1
 '@S9S_MB_2U_LIB.S9S_MB_2U(SCH_1):PAGE186_I68@PURE_QUANTA.Q_RES(CHIPS)':
 C_PATH='@s9s_mb_2u_lib.s9s_mb_2u(sch_1):page186_i68@pure_quanta.q_res(chips)',
 P_PATH='@s9s_mb_2u_lib.s9s_mb_2u(sch_1):page198_i68@pure_quanta.q_res(chips)',
 PATH='I68',
 DRAWING='@S9S_MB_2U_LIB.S9S_MB_2U(SCH_1):PAGE186',
 PHYS_PAGE='198',
 XY='(2825,3250)',
 ROT='0',
 VER='2',
 PACK_TYPE='0402LF',
 CDS_LIB='pure_quanta',
 CDS_PART_NAME='Q_RES_0402LF-20K,1%,1/16W,CHIPA',
 WATTAGE='1/16W',
 TOLERANCE='1%',
 MATERIAL='CHIP',
 VALUE='20K',
 PRIM_FILE='./archive_libs/logical/q_res/chips/chips.prt';

PART_NAME
 R506 'Q_RES_0402LF-0,5%,1/16W,CHIP,CA':;

SECTION_NUMBER 1
 '@S9S_MB_2U_LIB.S9S_MB_2U(SCH_1):PAGE227_I18@PURE_QUANTA.Q_RES(CHIPS)':
 C_PATH='@s9s_mb_2u_lib.s9s_mb_2u(sch_1):page227_i18@pure_quanta.q_res(chips)',
 P_PATH='@s9s_mb_2u_lib.s9s_mb_2u(sch_1):page240_i18@pure_quanta.q_res(chips)',
 PATH='I18',
 DRAWING='@S9S_MB_2U_LIB.S9S_MB_2U(SCH_1):PAGE227',
 PHYS_PAGE='240',
 XY='(-13325,-1575)',
 ROT='0',
 VER='1',
 PACK_TYPE='0402LF',
 CDS_LIB='pure_quanta',
 CDS_PART_NAME='Q_RES_0402LF-0,5%,1/16W,CHIP,CA',
 WATTAGE='1/16W',
 TOLERANCE='5%',
 MATERIAL='CHIP',
 VALUE='0',
 PRIM_FILE='./archive_libs/logical/q_res/chips/chips.prt';

PART_NAME
 R515 'Q_RES_0402LF-10K,1%,1/16W,CHIPA':;

SECTION_NUMBER 1
 '@S9S_MB_2U_LIB.S9S_MB_2U(SCH_1):PAGE127_I7@PURE_QUANTA.Q_RES(CHIPS)':
 C_PATH='@s9s_mb_2u_lib.s9s_mb_2u(sch_1):page127_i7@pure_quanta.q_res(chips)',
 P_PATH='@s9s_mb_2u_lib.s9s_mb_2u(sch_1):page127_i7@pure_quanta.q_res(chips)',
 PATH='I7',
 DRAWING='@S9S_MB_2U_LIB.S9S_MB_2U(SCH_1):PAGE127',
 PHYS_PAGE='127',
 XY='(-1625,2975)',
 ROT='0',
 VER='2',
 PACK_TYPE='0402LF',
 CDS_LIB='pure_quanta',
 CDS_PART_NAME='Q_RES_0402LF-10K,1%,1/16W,CHIPA',
 WATTAGE='1/16W',
 TOLERANCE='1%',
 MATERIAL='CHIP',
 VALUE='10K',
 PRIM_FILE='./archive_libs/logical/q_res/chips/chips.prt';

PART_NAME
 R519 'Q_RES_0603LF-1,1%,1/10W,CHIP,CA':;

SECTION_NUMBER 1
 '@S9S_MB_2U_LIB.S9S_MB_2U(SCH_1):PAGE199_I7@PURE_QUANTA.Q_RES(CHIPS)':
 C_PATH='@s9s_mb_2u_lib.s9s_mb_2u(sch_1):page199_i7@pure_quanta.q_res(chips)',
 P_PATH='@s9s_mb_2u_lib.s9s_mb_2u(sch_1):page210_i7@pure_quanta.q_res(chips)',
 PATH='I7',
 DRAWING='@S9S_MB_2U_LIB.S9S_MB_2U(SCH_1):PAGE199',
 PHYS_PAGE='210',
 XY='(-9775,7675)',
 ROT='0',
 VER='1',
 PACK_TYPE='0603LF',
 CDS_LIB='pure_quanta',
 CDS_PART_NAME='Q_RES_0603LF-1,1%,1/10W,CHIP,CA',
 WATTAGE='1/10W',
 TOLERANCE='1%',
 MATERIAL='CHIP',
 VALUE='1',
 PRIM_FILE='./archive_libs/logical/q_res/chips/chips.prt';

PART_NAME
 R536 'Q_RES_0402LF-10K,1%,1/16W,EMPTA':;

SECTION_NUMBER 1
 '@S9S_MB_2U_LIB.S9S_MB_2U(SCH_1):PAGE219_I3@PURE_QUANTA.Q_RES(CHIPS)':
 C_PATH='@s9s_mb_2u_lib.s9s_mb_2u(sch_1):page219_i3@pure_quanta.q_res(chips)',
 P_PATH='@s9s_mb_2u_lib.s9s_mb_2u(sch_1):page231_i3@pure_quanta.q_res(chips)',
 PATH='I3',
 DRAWING='@S9S_MB_2U_LIB.S9S_MB_2U(SCH_1):PAGE219',
 PHYS_PAGE='231',
 XY='(-1250,675)',
 ROT='0',
 VER='2',
 PACK_TYPE='0402LF',
 CDS_LIB='pure_quanta',
 CDS_PART_NAME='Q_RES_0402LF-10K,1%,1/16W,EMPTA',
 WATTAGE='1/16W',
 TOLERANCE='1%',
 MATERIAL='EMPTY',
 VALUE='10K',
 PRIM_FILE='./archive_libs/logical/q_res/chips/chips.prt';

PART_NAME
 R537 'Q_RES_0402LF-1K,1%,1/16W,CHIP,A':;

SECTION_NUMBER 1
 '@S9S_MB_2U_LIB.S9S_MB_2U(SCH_1):PAGE219_I2@PURE_QUANTA.Q_RES(CHIPS)':
 C_PATH='@s9s_mb_2u_lib.s9s_mb_2u(sch_1):page219_i2@pure_quanta.q_res(chips)',
 P_PATH='@s9s_mb_2u_lib.s9s_mb_2u(sch_1):page231_i2@pure_quanta.q_res(chips)',
 PATH='I2',
 DRAWING='@S9S_MB_2U_LIB.S9S_MB_2U(SCH_1):PAGE219',
 PHYS_PAGE='231',
 XY='(-1250,25)',
 ROT='0',
 VER='2',
 PACK_TYPE='0402LF',
 CDS_LIB='pure_quanta',
 CDS_PART_NAME='Q_RES_0402LF-1K,1%,1/16W,CHIP,A',
 WATTAGE='1/16W',
 TOLERANCE='1%',
 MATERIAL='CHIP',
 VALUE='1K',
 PRIM_FILE='./archive_libs/logical/q_res/chips/chips.prt';

PART_NAME
 R538 'Q_RES_0402LF-10K,1%,1/16W,EMPTA':;

SECTION_NUMBER 1
 '@S9S_MB_2U_LIB.S9S_MB_2U(SCH_1):PAGE219_I9@PURE_QUANTA.Q_RES(CHIPS)':
 C_PATH='@s9s_mb_2u_lib.s9s_mb_2u(sch_1):page219_i9@pure_quanta.q_res(chips)',
 P_PATH='@s9s_mb_2u_lib.s9s_mb_2u(sch_1):page231_i9@pure_quanta.q_res(chips)',
 PATH='I9',
 DRAWING='@S9S_MB_2U_LIB.S9S_MB_2U(SCH_1):PAGE219',
 PHYS_PAGE='231',
 XY='(-975,675)',
 ROT='0',
 VER='2',
 PACK_TYPE='0402LF',
 CDS_LIB='pure_quanta',
 CDS_PART_NAME='Q_RES_0402LF-10K,1%,1/16W,EMPTA',
 WATTAGE='1/16W',
 TOLERANCE='1%',
 MATERIAL='EMPTY',
 VALUE='10K',
 PRIM_FILE='./archive_libs/logical/q_res/chips/chips.prt';

PART_NAME
 R539 'Q_RES_0402LF-1K,1%,1/16W,CHIP,A':;

SECTION_NUMBER 1
 '@S9S_MB_2U_LIB.S9S_MB_2U(SCH_1):PAGE219_I6@PURE_QUANTA.Q_RES(CHIPS)':
 C_PATH='@s9s_mb_2u_lib.s9s_mb_2u(sch_1):page219_i6@pure_quanta.q_res(chips)',
 P_PATH='@s9s_mb_2u_lib.s9s_mb_2u(sch_1):page231_i6@pure_quanta.q_res(chips)',
 PATH='I6',
 DRAWING='@S9S_MB_2U_LIB.S9S_MB_2U(SCH_1):PAGE219',
 PHYS_PAGE='231',
 XY='(-975,25)',
 ROT='0',
 VER='2',
 PACK_TYPE='0402LF',
 CDS_LIB='pure_quanta',
 CDS_PART_NAME='Q_RES_0402LF-1K,1%,1/16W,CHIP,A',
 WATTAGE='1/16W',
 TOLERANCE='1%',
 MATERIAL='CHIP',
 VALUE='1K',
 PRIM_FILE='./archive_libs/logical/q_res/chips/chips.prt';

PART_NAME
 R540 'Q_RES_0402LF-10K,1%,1/16W,EMPTA':;

SECTION_NUMBER 1
 '@S9S_MB_2U_LIB.S9S_MB_2U(SCH_1):PAGE219_I10@PURE_QUANTA.Q_RES(CHIPS)':
 C_PATH='@s9s_mb_2u_lib.s9s_mb_2u(sch_1):page219_i10@pure_quanta.q_res(chips)',
 P_PATH='@s9s_mb_2u_lib.s9s_mb_2u(sch_1):page231_i10@pure_quanta.q_res(chips)',
 PATH='I10',
 DRAWING='@S9S_MB_2U_LIB.S9S_MB_2U(SCH_1):PAGE219',
 PHYS_PAGE='231',
 XY='(-700,675)',
 ROT='0',
 VER='2',
 PACK_TYPE='0402LF',
 CDS_LIB='pure_quanta',
 CDS_PART_NAME='Q_RES_0402LF-10K,1%,1/16W,EMPTA',
 WATTAGE='1/16W',
 TOLERANCE='1%',
 MATERIAL='EMPTY',
 VALUE='10K',
 PRIM_FILE='./archive_libs/logical/q_res/chips/chips.prt';

PART_NAME
 R548 'Q_RES_0402LF-49.9,1%,1/16W,CHIA':;

SECTION_NUMBER 1
 '@S9S_MB_2U_LIB.S9S_MB_2U(SCH_1):PAGE14_I94@PURE_QUANTA.Q_RES(CHIPS)':
 C_PATH='@s9s_mb_2u_lib.s9s_mb_2u(sch_1):page14_i94@pure_quanta.q_res(chips)',
 P_PATH='@s9s_mb_2u_lib.s9s_mb_2u(sch_1):page14_i94@pure_quanta.q_res(chips)',
 PATH='I94',
 DRAWING='@S9S_MB_2U_LIB.S9S_MB_2U(SCH_1):PAGE14',
 PHYS_PAGE='14',
 XY='(2975,175)',
 ROT='0',
 VER='1',
 PACK_TYPE='0402LF',
 CDS_LIB='pure_quanta',
 CDS_PART_NAME='Q_RES_0402LF-49.9,1%,1/16W,CHIA',
 WATTAGE='1/16W',
 TOLERANCE='1%',
 MATERIAL='CHIP',
 VALUE='49.9',
 PRIM_FILE='./archive_libs/logical/q_res/chips/chips.prt';

PART_NAME
 R553 'Q_RES_0402LF-0,5%,1/16W,CHIP,CA':;

SECTION_NUMBER 1
 '@S9S_MB_2U_LIB.S9S_MB_2U(SCH_1):PAGE198_I58@PURE_QUANTA.Q_RES(CHIPS)':
 C_PATH='@s9s_mb_2u_lib.s9s_mb_2u(sch_1):page198_i58@pure_quanta.q_res(chips)',
 P_PATH='@s9s_mb_2u_lib.s9s_mb_2u(sch_1):page209_i58@pure_quanta.q_res(chips)',
 PATH='I58',
 DRAWING='@S9S_MB_2U_LIB.S9S_MB_2U(SCH_1):PAGE198',
 PHYS_PAGE='209',
 XY='(-1675,1025)',
 ROT='0',
 VER='1',
 PACK_TYPE='0402LF',
 CDS_LIB='pure_quanta',
 CDS_PART_NAME='Q_RES_0402LF-0,5%,1/16W,CHIP,CA',
 WATTAGE='1/16W',
 TOLERANCE='5%',
 MATERIAL='CHIP',
 VALUE='0',
 PRIM_FILE='./archive_libs/logical/q_res/chips/chips.prt';

PART_NAME
 R554 'Q_RES_0402LF-0,5%,1/16W,CHIP,CA':;

SECTION_NUMBER 1
 '@S9S_MB_2U_LIB.S9S_MB_2U(SCH_1):PAGE198_I57@PURE_QUANTA.Q_RES(CHIPS)':
 C_PATH='@s9s_mb_2u_lib.s9s_mb_2u(sch_1):page198_i57@pure_quanta.q_res(chips)',
 P_PATH='@s9s_mb_2u_lib.s9s_mb_2u(sch_1):page209_i57@pure_quanta.q_res(chips)',
 PATH='I57',
 DRAWING='@S9S_MB_2U_LIB.S9S_MB_2U(SCH_1):PAGE198',
 PHYS_PAGE='209',
 XY='(-1675,850)',
 ROT='0',
 VER='1',
 PACK_TYPE='0402LF',
 CDS_LIB='pure_quanta',
 CDS_PART_NAME='Q_RES_0402LF-0,5%,1/16W,CHIP,CA',
 WATTAGE='1/16W',
 TOLERANCE='5%',
 MATERIAL='CHIP',
 VALUE='0',
 PRIM_FILE='./archive_libs/logical/q_res/chips/chips.prt';

PART_NAME
 R555 'Q_RES_0402LF-100,1%,1/16W,CHIPA':;

SECTION_NUMBER 1
 '@S9S_MB_2U_LIB.S9S_MB_2U(SCH_1):PAGE14_I98@PURE_QUANTA.Q_RES(CHIPS)':
 C_PATH='@s9s_mb_2u_lib.s9s_mb_2u(sch_1):page14_i98@pure_quanta.q_res(chips)',
 P_PATH='@s9s_mb_2u_lib.s9s_mb_2u(sch_1):page14_i98@pure_quanta.q_res(chips)',
 PATH='I98',
 DRAWING='@S9S_MB_2U_LIB.S9S_MB_2U(SCH_1):PAGE14',
 PHYS_PAGE='14',
 XY='(2975,-25)',
 ROT='0',
 VER='1',
 PACK_TYPE='0402LF',
 CDS_LIB='pure_quanta',
 CDS_PART_NAME='Q_RES_0402LF-100,1%,1/16W,CHIPA',
 WATTAGE='1/16W',
 TOLERANCE='1%',
 MATERIAL='CHIP',
 VALUE='100',
 PRIM_FILE='./archive_libs/logical/q_res/chips/chips.prt';

PART_NAME
 R556 'Q_RES_0402LF-49.9,1%,1/16W,CHIA':;

SECTION_NUMBER 1
 '@S9S_MB_2U_LIB.S9S_MB_2U(SCH_1):PAGE14_I100@PURE_QUANTA.Q_RES(CHIPS)':
 C_PATH='@s9s_mb_2u_lib.s9s_mb_2u(sch_1):page14_i100@pure_quanta.q_res(chips)',
 P_PATH='@s9s_mb_2u_lib.s9s_mb_2u(sch_1):page14_i100@pure_quanta.q_res(chips)',
 PATH='I100',
 DRAWING='@S9S_MB_2U_LIB.S9S_MB_2U(SCH_1):PAGE14',
 PHYS_PAGE='14',
 XY='(2975,-225)',
 ROT='0',
 VER='1',
 PACK_TYPE='0402LF',
 CDS_LIB='pure_quanta',
 CDS_PART_NAME='Q_RES_0402LF-49.9,1%,1/16W,CHIA',
 WATTAGE='1/16W',
 TOLERANCE='1%',
 MATERIAL='CHIP',
 VALUE='49.9',
 PRIM_FILE='./archive_libs/logical/q_res/chips/chips.prt';

PART_NAME
 R557 'Q_RES_0402LF-100,1%,1/16W,CHIPA':;

SECTION_NUMBER 1
 '@S9S_MB_2U_LIB.S9S_MB_2U(SCH_1):PAGE45_I74@PURE_QUANTA.Q_RES(CHIPS)':
 C_PATH='@s9s_mb_2u_lib.s9s_mb_2u(sch_1):page45_i74@pure_quanta.q_res(chips)',
 P_PATH='@s9s_mb_2u_lib.s9s_mb_2u(sch_1):page45_i74@pure_quanta.q_res(chips)',
 PATH='I74',
 DRAWING='@S9S_MB_2U_LIB.S9S_MB_2U(SCH_1):PAGE45',
 PHYS_PAGE='45',
 XY='(-3075,-4525)',
 ROT='0',
 VER='1',
 PACK_TYPE='0402LF',
 CDS_LIB='pure_quanta',
 CDS_PART_NAME='Q_RES_0402LF-100,1%,1/16W,CHIPA',
 WATTAGE='1/16W',
 TOLERANCE='1%',
 MATERIAL='CHIP',
 VALUE='100',
 PRIM_FILE='./archive_libs/logical/q_res/chips/chips.prt';

PART_NAME
 R558 'Q_RES_0402LF-49.9,1%,1/16W,CHIA':;

SECTION_NUMBER 1
 '@S9S_MB_2U_LIB.S9S_MB_2U(SCH_1):PAGE45_I73@PURE_QUANTA.Q_RES(CHIPS)':
 C_PATH='@s9s_mb_2u_lib.s9s_mb_2u(sch_1):page45_i73@pure_quanta.q_res(chips)',
 P_PATH='@s9s_mb_2u_lib.s9s_mb_2u(sch_1):page45_i73@pure_quanta.q_res(chips)',
 PATH='I73',
 DRAWING='@S9S_MB_2U_LIB.S9S_MB_2U(SCH_1):PAGE45',
 PHYS_PAGE='45',
 XY='(-3075,-4725)',
 ROT='0',
 VER='1',
 PACK_TYPE='0402LF',
 CDS_LIB='pure_quanta',
 CDS_PART_NAME='Q_RES_0402LF-49.9,1%,1/16W,CHIA',
 WATTAGE='1/16W',
 TOLERANCE='1%',
 MATERIAL='CHIP',
 VALUE='49.9',
 PRIM_FILE='./archive_libs/logical/q_res/chips/chips.prt';

PART_NAME
 R559 'Q_RES_0402LF-100,1%,1/16W,CHIPA':;

SECTION_NUMBER 1
 '@S9S_MB_2U_LIB.S9S_MB_2U(SCH_1):PAGE45_I69@PURE_QUANTA.Q_RES(CHIPS)':
 C_PATH='@s9s_mb_2u_lib.s9s_mb_2u(sch_1):page45_i69@pure_quanta.q_res(chips)',
 P_PATH='@s9s_mb_2u_lib.s9s_mb_2u(sch_1):page45_i69@pure_quanta.q_res(chips)',
 PATH='I69',
 DRAWING='@S9S_MB_2U_LIB.S9S_MB_2U(SCH_1):PAGE45',
 PHYS_PAGE='45',
 XY='(-3075,-4925)',
 ROT='0',
 VER='1',
 PACK_TYPE='0402LF',
 CDS_LIB='pure_quanta',
 CDS_PART_NAME='Q_RES_0402LF-100,1%,1/16W,CHIPA',
 WATTAGE='1/16W',
 TOLERANCE='1%',
 MATERIAL='CHIP',
 VALUE='100',
 PRIM_FILE='./archive_libs/logical/q_res/chips/chips.prt';

PART_NAME
 R560 'Q_RES_0402LF-49.9,1%,1/16W,CHIA':;

SECTION_NUMBER 1
 '@S9S_MB_2U_LIB.S9S_MB_2U(SCH_1):PAGE45_I70@PURE_QUANTA.Q_RES(CHIPS)':
 C_PATH='@s9s_mb_2u_lib.s9s_mb_2u(sch_1):page45_i70@pure_quanta.q_res(chips)',
 P_PATH='@s9s_mb_2u_lib.s9s_mb_2u(sch_1):page45_i70@pure_quanta.q_res(chips)',
 PATH='I70',
 DRAWING='@S9S_MB_2U_LIB.S9S_MB_2U(SCH_1):PAGE45',
 PHYS_PAGE='45',
 XY='(-3075,-5125)',
 ROT='0',
 VER='1',
 PACK_TYPE='0402LF',
 CDS_LIB='pure_quanta',
 CDS_PART_NAME='Q_RES_0402LF-49.9,1%,1/16W,CHIA',
 WATTAGE='1/16W',
 TOLERANCE='1%',
 MATERIAL='CHIP',
 VALUE='49.9',
 PRIM_FILE='./archive_libs/logical/q_res/chips/chips.prt';

PART_NAME
 R563 'Q_RES_0402LF-22,1%,1/16W,CHIP,A':;

SECTION_NUMBER 1
 '@S9S_MB_2U_LIB.S9S_MB_2U(SCH_1):PAGE198_I48@PURE_QUANTA.Q_RES(CHIPS)':
 C_PATH='@s9s_mb_2u_lib.s9s_mb_2u(sch_1):page198_i48@pure_quanta.q_res(chips)',
 P_PATH='@s9s_mb_2u_lib.s9s_mb_2u(sch_1):page209_i48@pure_quanta.q_res(chips)',
 PATH='I48',
 DRAWING='@S9S_MB_2U_LIB.S9S_MB_2U(SCH_1):PAGE198',
 PHYS_PAGE='209',
 XY='(-6025,1000)',
 ROT='0',
 VER='1',
 PACK_TYPE='0402LF',
 CDS_LIB='pure_quanta',
 CDS_PART_NAME='Q_RES_0402LF-22,1%,1/16W,CHIP,A',
 WATTAGE='1/16W',
 TOLERANCE='1%',
 MATERIAL='CHIP',
 VALUE='22',
 PRIM_FILE='./archive_libs/logical/q_res/chips/chips.prt';

PART_NAME
 R564 'Q_RES_0402LF-22,1%,1/16W,CHIP,A':;

SECTION_NUMBER 1
 '@S9S_MB_2U_LIB.S9S_MB_2U(SCH_1):PAGE198_I47@PURE_QUANTA.Q_RES(CHIPS)':
 C_PATH='@s9s_mb_2u_lib.s9s_mb_2u(sch_1):page198_i47@pure_quanta.q_res(chips)',
 P_PATH='@s9s_mb_2u_lib.s9s_mb_2u(sch_1):page209_i47@pure_quanta.q_res(chips)',
 PATH='I47',
 DRAWING='@S9S_MB_2U_LIB.S9S_MB_2U(SCH_1):PAGE198',
 PHYS_PAGE='209',
 XY='(-6025,850)',
 ROT='0',
 VER='1',
 PACK_TYPE='0402LF',
 CDS_LIB='pure_quanta',
 CDS_PART_NAME='Q_RES_0402LF-22,1%,1/16W,CHIP,A',
 WATTAGE='1/16W',
 TOLERANCE='1%',
 MATERIAL='CHIP',
 VALUE='22',
 PRIM_FILE='./archive_libs/logical/q_res/chips/chips.prt';

PART_NAME
 R565 'Q_RES_0402LF-22,1%,1/16W,CHIP,A':;

SECTION_NUMBER 1
 '@S9S_MB_2U_LIB.S9S_MB_2U(SCH_1):PAGE198_I46@PURE_QUANTA.Q_RES(CHIPS)':
 C_PATH='@s9s_mb_2u_lib.s9s_mb_2u(sch_1):page198_i46@pure_quanta.q_res(chips)',
 P_PATH='@s9s_mb_2u_lib.s9s_mb_2u(sch_1):page209_i46@pure_quanta.q_res(chips)',
 PATH='I46',
 DRAWING='@S9S_MB_2U_LIB.S9S_MB_2U(SCH_1):PAGE198',
 PHYS_PAGE='209',
 XY='(-6025,600)',
 ROT='0',
 VER='1',
 PACK_TYPE='0402LF',
 CDS_LIB='pure_quanta',
 CDS_PART_NAME='Q_RES_0402LF-22,1%,1/16W,CHIP,A',
 WATTAGE='1/16W',
 TOLERANCE='1%',
 MATERIAL='CHIP',
 VALUE='22',
 PRIM_FILE='./archive_libs/logical/q_res/chips/chips.prt';

PART_NAME
 R566 'Q_RES_0402LF-22,1%,1/16W,CHIP,A':;

SECTION_NUMBER 1
 '@S9S_MB_2U_LIB.S9S_MB_2U(SCH_1):PAGE198_I45@PURE_QUANTA.Q_RES(CHIPS)':
 C_PATH='@s9s_mb_2u_lib.s9s_mb_2u(sch_1):page198_i45@pure_quanta.q_res(chips)',
 P_PATH='@s9s_mb_2u_lib.s9s_mb_2u(sch_1):page209_i45@pure_quanta.q_res(chips)',
 PATH='I45',
 DRAWING='@S9S_MB_2U_LIB.S9S_MB_2U(SCH_1):PAGE198',
 PHYS_PAGE='209',
 XY='(-6025,450)',
 ROT='0',
 VER='1',
 PACK_TYPE='0402LF',
 CDS_LIB='pure_quanta',
 CDS_PART_NAME='Q_RES_0402LF-22,1%,1/16W,CHIP,A',
 WATTAGE='1/16W',
 TOLERANCE='1%',
 MATERIAL='CHIP',
 VALUE='22',
 PRIM_FILE='./archive_libs/logical/q_res/chips/chips.prt';

PART_NAME
 R567 'Q_RES_0402LF-4.7K,1%,1/16W,EMPA':;

SECTION_NUMBER 1
 '@S9S_MB_2U_LIB.S9S_MB_2U(SCH_1):PAGE195_I179@PURE_QUANTA.Q_RES(CHIPS)':
 C_PATH='@s9s_mb_2u_lib.s9s_mb_2u(sch_1):page195_i179@pure_quanta.q_res(chips)',
 P_PATH='@s9s_mb_2u_lib.s9s_mb_2u(sch_1):page206_i179@pure_quanta.q_res(chips)',
 PATH='I179',
 DRAWING='@S9S_MB_2U_LIB.S9S_MB_2U(SCH_1):PAGE195',
 PHYS_PAGE='206',
 XY='(-9225,2050)',
 ROT='0',
 VER='2',
 PACK_TYPE='0402LF',
 CDS_LIB='pure_quanta',
 CDS_PART_NAME='Q_RES_0402LF-4.7K,1%,1/16W,EMPA',
 WATTAGE='1/16W',
 TOLERANCE='1%',
 MATERIAL='EMPTY',
 VALUE='4.7K',
 PRIM_FILE='./archive_libs/logical/q_res/chips/chips.prt';

PART_NAME
 R568 'Q_RES_0402LF-4.7K,1%,1/16W,CHIA':;

SECTION_NUMBER 1
 '@S9S_MB_2U_LIB.S9S_MB_2U(SCH_1):PAGE195_I178@PURE_QUANTA.Q_RES(CHIPS)':
 C_PATH='@s9s_mb_2u_lib.s9s_mb_2u(sch_1):page195_i178@pure_quanta.q_res(chips)',
 P_PATH='@s9s_mb_2u_lib.s9s_mb_2u(sch_1):page206_i178@pure_quanta.q_res(chips)',
 PATH='I178',
 DRAWING='@S9S_MB_2U_LIB.S9S_MB_2U(SCH_1):PAGE195',
 PHYS_PAGE='206',
 XY='(-9225,1475)',
 ROT='0',
 VER='2',
 PACK_TYPE='0402LF',
 CDS_LIB='pure_quanta',
 CDS_PART_NAME='Q_RES_0402LF-4.7K,1%,1/16W,CHIA',
 WATTAGE='1/16W',
 TOLERANCE='1%',
 MATERIAL='CHIP',
 VALUE='4.7K',
 PRIM_FILE='./archive_libs/logical/q_res/chips/chips.prt';

PART_NAME
 R569 'Q_RES_0402LF-4.7K,1%,1/16W,EMPA':;

SECTION_NUMBER 1
 '@S9S_MB_2U_LIB.S9S_MB_2U(SCH_1):PAGE195_I185@PURE_QUANTA.Q_RES(CHIPS)':
 C_PATH='@s9s_mb_2u_lib.s9s_mb_2u(sch_1):page195_i185@pure_quanta.q_res(chips)',
 P_PATH='@s9s_mb_2u_lib.s9s_mb_2u(sch_1):page206_i185@pure_quanta.q_res(chips)',
 PATH='I185',
 DRAWING='@S9S_MB_2U_LIB.S9S_MB_2U(SCH_1):PAGE195',
 PHYS_PAGE='206',
 XY='(-8825,2050)',
 ROT='0',
 VER='2',
 PACK_TYPE='0402LF',
 CDS_LIB='pure_quanta',
 CDS_PART_NAME='Q_RES_0402LF-4.7K,1%,1/16W,EMPA',
 WATTAGE='1/16W',
 TOLERANCE='1%',
 MATERIAL='EMPTY',
 VALUE='4.7K',
 PRIM_FILE='./archive_libs/logical/q_res/chips/chips.prt';

PART_NAME
 R570 'Q_RES_0402LF-4.7K,1%,1/16W,CHIA':;

SECTION_NUMBER 1
 '@S9S_MB_2U_LIB.S9S_MB_2U(SCH_1):PAGE195_I187@PURE_QUANTA.Q_RES(CHIPS)':
 C_PATH='@s9s_mb_2u_lib.s9s_mb_2u(sch_1):page195_i187@pure_quanta.q_res(chips)',
 P_PATH='@s9s_mb_2u_lib.s9s_mb_2u(sch_1):page206_i187@pure_quanta.q_res(chips)',
 PATH='I187',
 DRAWING='@S9S_MB_2U_LIB.S9S_MB_2U(SCH_1):PAGE195',
 PHYS_PAGE='206',
 XY='(-8825,1475)',
 ROT='0',
 VER='2',
 PACK_TYPE='0402LF',
 CDS_LIB='pure_quanta',
 CDS_PART_NAME='Q_RES_0402LF-4.7K,1%,1/16W,CHIA',
 WATTAGE='1/16W',
 TOLERANCE='1%',
 MATERIAL='CHIP',
 VALUE='4.7K',
 PRIM_FILE='./archive_libs/logical/q_res/chips/chips.prt';

PART_NAME
 R571 'Q_RES_0603LF-2.2,1%,1/10W,CHIPA':;

SECTION_NUMBER 1
 '@S9S_MB_2U_LIB.S9S_MB_2U(SCH_1):PAGE195_I163@PURE_QUANTA.Q_RES(CHIPS)':
 C_PATH='@s9s_mb_2u_lib.s9s_mb_2u(sch_1):page195_i163@pure_quanta.q_res(chips)',
 P_PATH='@s9s_mb_2u_lib.s9s_mb_2u(sch_1):page206_i163@pure_quanta.q_res(chips)',
 PATH='I163',
 DRAWING='@S9S_MB_2U_LIB.S9S_MB_2U(SCH_1):PAGE195',
 PHYS_PAGE='206',
 XY='(-7875,4200)',
 ROT='0',
 VER='1',
 PACK_TYPE='0603LF',
 CDS_LIB='pure_quanta',
 CDS_PART_NAME='Q_RES_0603LF-2.2,1%,1/10W,CHIPA',
 WATTAGE='1/10W',
 TOLERANCE='1%',
 MATERIAL='CHIP',
 VALUE='2.2',
 PRIM_FILE='./archive_libs/logical/q_res/chips/chips.prt';

PART_NAME
 R572 'Q_RES_0603LF-2.2,1%,1/10W,CHIPA':;

SECTION_NUMBER 1
 '@S9S_MB_2U_LIB.S9S_MB_2U(SCH_1):PAGE195_I162@PURE_QUANTA.Q_RES(CHIPS)':
 C_PATH='@s9s_mb_2u_lib.s9s_mb_2u(sch_1):page195_i162@pure_quanta.q_res(chips)',
 P_PATH='@s9s_mb_2u_lib.s9s_mb_2u(sch_1):page206_i162@pure_quanta.q_res(chips)',
 PATH='I162',
 DRAWING='@S9S_MB_2U_LIB.S9S_MB_2U(SCH_1):PAGE195',
 PHYS_PAGE='206',
 XY='(-7875,3325)',
 ROT='0',
 VER='1',
 PACK_TYPE='0603LF',
 CDS_LIB='pure_quanta',
 CDS_PART_NAME='Q_RES_0603LF-2.2,1%,1/10W,CHIPA',
 WATTAGE='1/10W',
 TOLERANCE='1%',
 MATERIAL='CHIP',
 VALUE='2.2',
 PRIM_FILE='./archive_libs/logical/q_res/chips/chips.prt';

PART_NAME
 R573 'Q_RES_0402LF-4.7K,1%,1/16W,EMPA':;

SECTION_NUMBER 1
 '@S9S_MB_2U_LIB.S9S_MB_2U(SCH_1):PAGE195_I194@PURE_QUANTA.Q_RES(CHIPS)':
 C_PATH='@s9s_mb_2u_lib.s9s_mb_2u(sch_1):page195_i194@pure_quanta.q_res(chips)',
 P_PATH='@s9s_mb_2u_lib.s9s_mb_2u(sch_1):page206_i194@pure_quanta.q_res(chips)',
 PATH='I194',
 DRAWING='@S9S_MB_2U_LIB.S9S_MB_2U(SCH_1):PAGE195',
 PHYS_PAGE='206',
 XY='(-9225,625)',
 ROT='0',
 VER='2',
 PACK_TYPE='0402LF',
 CDS_LIB='pure_quanta',
 CDS_PART_NAME='Q_RES_0402LF-4.7K,1%,1/16W,EMPA',
 WATTAGE='1/16W',
 TOLERANCE='1%',
 MATERIAL='EMPTY',
 VALUE='4.7K',
 PRIM_FILE='./archive_libs/logical/q_res/chips/chips.prt';

PART_NAME
 R574 'Q_RES_0402LF-4.7K,1%,1/16W,CHIA':;

SECTION_NUMBER 1
 '@S9S_MB_2U_LIB.S9S_MB_2U(SCH_1):PAGE195_I197@PURE_QUANTA.Q_RES(CHIPS)':
 C_PATH='@s9s_mb_2u_lib.s9s_mb_2u(sch_1):page195_i197@pure_quanta.q_res(chips)',
 P_PATH='@s9s_mb_2u_lib.s9s_mb_2u(sch_1):page206_i197@pure_quanta.q_res(chips)',
 PATH='I197',
 DRAWING='@S9S_MB_2U_LIB.S9S_MB_2U(SCH_1):PAGE195',
 PHYS_PAGE='206',
 XY='(-9225,50)',
 ROT='0',
 VER='2',
 PACK_TYPE='0402LF',
 CDS_LIB='pure_quanta',
 CDS_PART_NAME='Q_RES_0402LF-4.7K,1%,1/16W,CHIA',
 WATTAGE='1/16W',
 TOLERANCE='1%',
 MATERIAL='CHIP',
 VALUE='4.7K',
 PRIM_FILE='./archive_libs/logical/q_res/chips/chips.prt';

PART_NAME
 R575 'Q_RES_0402LF-49.9,1%,1/16W,CHIA':;

SECTION_NUMBER 1
 '@S9S_MB_2U_LIB.S9S_MB_2U(SCH_1):PAGE195_I199@PURE_QUANTA.Q_RES(CHIPS)':
 C_PATH='@s9s_mb_2u_lib.s9s_mb_2u(sch_1):page195_i199@pure_quanta.q_res(chips)',
 P_PATH='@s9s_mb_2u_lib.s9s_mb_2u(sch_1):page206_i199@pure_quanta.q_res(chips)',
 PATH='I199',
 DRAWING='@S9S_MB_2U_LIB.S9S_MB_2U(SCH_1):PAGE195',
 PHYS_PAGE='206',
 XY='(-5300,2550)',
 ROT='0',
 VER='1',
 PACK_TYPE='0402LF',
 CDS_LIB='pure_quanta',
 CDS_PART_NAME='Q_RES_0402LF-49.9,1%,1/16W,CHIA',
 WATTAGE='1/16W',
 TOLERANCE='1%',
 MATERIAL='CHIP',
 VALUE='49.9',
 PRIM_FILE='./archive_libs/logical/q_res/chips/chips.prt';

PART_NAME
 R576 'Q_RES_0402LF-49.9,1%,1/16W,CHIA':;

SECTION_NUMBER 1
 '@S9S_MB_2U_LIB.S9S_MB_2U(SCH_1):PAGE195_I156@PURE_QUANTA.Q_RES(CHIPS)':
 C_PATH='@s9s_mb_2u_lib.s9s_mb_2u(sch_1):page195_i156@pure_quanta.q_res(chips)',
 P_PATH='@s9s_mb_2u_lib.s9s_mb_2u(sch_1):page206_i156@pure_quanta.q_res(chips)',
 PATH='I156',
 DRAWING='@S9S_MB_2U_LIB.S9S_MB_2U(SCH_1):PAGE195',
 PHYS_PAGE='206',
 XY='(-5300,2250)',
 ROT='0',
 VER='1',
 PACK_TYPE='0402LF',
 CDS_LIB='pure_quanta',
 CDS_PART_NAME='Q_RES_0402LF-49.9,1%,1/16W,CHIA',
 WATTAGE='1/16W',
 TOLERANCE='1%',
 MATERIAL='CHIP',
 VALUE='49.9',
 PRIM_FILE='./archive_libs/logical/q_res/chips/chips.prt';

PART_NAME
 R577 'Q_RES_0402LF-33.2,1%,1/16W,CHIA':;

SECTION_NUMBER 1
 '@S9S_MB_2U_LIB.S9S_MB_2U(SCH_1):PAGE228_I303@PURE_QUANTA.Q_RES(CHIPS)':
 C_PATH='@s9s_mb_2u_lib.s9s_mb_2u(sch_1):page228_i303@pure_quanta.q_res(chips)',
 P_PATH='@s9s_mb_2u_lib.s9s_mb_2u(sch_1):page241_i303@pure_quanta.q_res(chips)',
 PATH='I303',
 DRAWING='@S9S_MB_2U_LIB.S9S_MB_2U(SCH_1):PAGE228',
 PHYS_PAGE='241',
 XY='(-350,6400)',
 ROT='0',
 VER='1',
 PACK_TYPE='0402LF',
 CDS_LIB='pure_quanta',
 CDS_PART_NAME='Q_RES_0402LF-33.2,1%,1/16W,CHIA',
 WATTAGE='1/16W',
 TOLERANCE='1%',
 MATERIAL='CHIP',
 VALUE='33.2',
 PRIM_FILE='./archive_libs/logical/q_res/chips/chips.prt';

PART_NAME
 R578 'Q_RES_0402LF-33.2,1%,1/16W,CHIA':;

SECTION_NUMBER 1
 '@S9S_MB_2U_LIB.S9S_MB_2U(SCH_1):PAGE228_I304@PURE_QUANTA.Q_RES(CHIPS)':
 C_PATH='@s9s_mb_2u_lib.s9s_mb_2u(sch_1):page228_i304@pure_quanta.q_res(chips)',
 P_PATH='@s9s_mb_2u_lib.s9s_mb_2u(sch_1):page241_i304@pure_quanta.q_res(chips)',
 PATH='I304',
 DRAWING='@S9S_MB_2U_LIB.S9S_MB_2U(SCH_1):PAGE228',
 PHYS_PAGE='241',
 XY='(-350,6350)',
 ROT='0',
 VER='1',
 PACK_TYPE='0402LF',
 CDS_LIB='pure_quanta',
 CDS_PART_NAME='Q_RES_0402LF-33.2,1%,1/16W,CHIA',
 WATTAGE='1/16W',
 TOLERANCE='1%',
 MATERIAL='CHIP',
 VALUE='33.2',
 PRIM_FILE='./archive_libs/logical/q_res/chips/chips.prt';

PART_NAME
 R579 'Q_RES_0402LF-33.2,1%,1/16W,CHIA':;

SECTION_NUMBER 1
 '@S9S_MB_2U_LIB.S9S_MB_2U(SCH_1):PAGE228_I38@PURE_QUANTA.Q_RES(CHIPS)':
 C_PATH='@s9s_mb_2u_lib.s9s_mb_2u(sch_1):page228_i38@pure_quanta.q_res(chips)',
 P_PATH='@s9s_mb_2u_lib.s9s_mb_2u(sch_1):page241_i38@pure_quanta.q_res(chips)',
 PATH='I38',
 DRAWING='@S9S_MB_2U_LIB.S9S_MB_2U(SCH_1):PAGE228',
 PHYS_PAGE='241',
 XY='(-200,5800)',
 ROT='0',
 VER='1',
 PACK_TYPE='0402LF',
 CDS_LIB='pure_quanta',
 CDS_PART_NAME='Q_RES_0402LF-33.2,1%,1/16W,CHIA',
 WATTAGE='1/16W',
 TOLERANCE='1%',
 MATERIAL='CHIP',
 VALUE='33.2',
 PRIM_FILE='./archive_libs/logical/q_res/chips/chips.prt';

PART_NAME
 R580 'Q_RES_0402LF-33.2,1%,1/16W,CHIA':;

SECTION_NUMBER 1
 '@S9S_MB_2U_LIB.S9S_MB_2U(SCH_1):PAGE228_I39@PURE_QUANTA.Q_RES(CHIPS)':
 C_PATH='@s9s_mb_2u_lib.s9s_mb_2u(sch_1):page228_i39@pure_quanta.q_res(chips)',
 P_PATH='@s9s_mb_2u_lib.s9s_mb_2u(sch_1):page241_i39@pure_quanta.q_res(chips)',
 PATH='I39',
 DRAWING='@S9S_MB_2U_LIB.S9S_MB_2U(SCH_1):PAGE228',
 PHYS_PAGE='241',
 XY='(-200,5750)',
 ROT='0',
 VER='1',
 PACK_TYPE='0402LF',
 CDS_LIB='pure_quanta',
 CDS_PART_NAME='Q_RES_0402LF-33.2,1%,1/16W,CHIA',
 WATTAGE='1/16W',
 TOLERANCE='1%',
 MATERIAL='CHIP',
 VALUE='33.2',
 PRIM_FILE='./archive_libs/logical/q_res/chips/chips.prt';

PART_NAME
 R581 'Q_RES_0402LF-33.2,1%,1/16W,CHIA':;

SECTION_NUMBER 1
 '@S9S_MB_2U_LIB.S9S_MB_2U(SCH_1):PAGE228_I44@PURE_QUANTA.Q_RES(CHIPS)':
 C_PATH='@s9s_mb_2u_lib.s9s_mb_2u(sch_1):page228_i44@pure_quanta.q_res(chips)',
 P_PATH='@s9s_mb_2u_lib.s9s_mb_2u(sch_1):page241_i44@pure_quanta.q_res(chips)',
 PATH='I44',
 DRAWING='@S9S_MB_2U_LIB.S9S_MB_2U(SCH_1):PAGE228',
 PHYS_PAGE='241',
 XY='(-325,4550)',
 ROT='0',
 VER='1',
 PACK_TYPE='0402LF',
 CDS_LIB='pure_quanta',
 CDS_PART_NAME='Q_RES_0402LF-33.2,1%,1/16W,CHIA',
 WATTAGE='1/16W',
 TOLERANCE='1%',
 MATERIAL='CHIP',
 VALUE='33.2',
 PRIM_FILE='./archive_libs/logical/q_res/chips/chips.prt';

PART_NAME
 R582 'Q_RES_0402LF-33.2,1%,1/16W,CHIA':;

SECTION_NUMBER 1
 '@S9S_MB_2U_LIB.S9S_MB_2U(SCH_1):PAGE228_I45@PURE_QUANTA.Q_RES(CHIPS)':
 C_PATH='@s9s_mb_2u_lib.s9s_mb_2u(sch_1):page228_i45@pure_quanta.q_res(chips)',
 P_PATH='@s9s_mb_2u_lib.s9s_mb_2u(sch_1):page241_i45@pure_quanta.q_res(chips)',
 PATH='I45',
 DRAWING='@S9S_MB_2U_LIB.S9S_MB_2U(SCH_1):PAGE228',
 PHYS_PAGE='241',
 XY='(-325,4500)',
 ROT='0',
 VER='1',
 PACK_TYPE='0402LF',
 CDS_LIB='pure_quanta',
 CDS_PART_NAME='Q_RES_0402LF-33.2,1%,1/16W,CHIA',
 WATTAGE='1/16W',
 TOLERANCE='1%',
 MATERIAL='CHIP',
 VALUE='33.2',
 PRIM_FILE='./archive_libs/logical/q_res/chips/chips.prt';

PART_NAME
 R587 'Q_RES_0402LF-1K,1%,1/16W,CHIP,A':;

SECTION_NUMBER 1
 '@S9S_MB_2U_LIB.S9S_MB_2U(SCH_1):PAGE219_I8@PURE_QUANTA.Q_RES(CHIPS)':
 C_PATH='@s9s_mb_2u_lib.s9s_mb_2u(sch_1):page219_i8@pure_quanta.q_res(chips)',
 P_PATH='@s9s_mb_2u_lib.s9s_mb_2u(sch_1):page231_i8@pure_quanta.q_res(chips)',
 PATH='I8',
 DRAWING='@S9S_MB_2U_LIB.S9S_MB_2U(SCH_1):PAGE219',
 PHYS_PAGE='231',
 XY='(-700,25)',
 ROT='0',
 VER='2',
 PACK_TYPE='0402LF',
 CDS_LIB='pure_quanta',
 CDS_PART_NAME='Q_RES_0402LF-1K,1%,1/16W,CHIP,A',
 WATTAGE='1/16W',
 TOLERANCE='1%',
 MATERIAL='CHIP',
 VALUE='1K',
 PRIM_FILE='./archive_libs/logical/q_res/chips/chips.prt';

PART_NAME
 R588 'Q_RES_0402LF-33.2,1%,1/16W,CHIA':;

SECTION_NUMBER 1
 '@S9S_MB_2U_LIB.S9S_MB_2U(SCH_1):PAGE219_I65@PURE_QUANTA.Q_RES(CHIPS)':
 C_PATH='@s9s_mb_2u_lib.s9s_mb_2u(sch_1):page219_i65@pure_quanta.q_res(chips)',
 P_PATH='@s9s_mb_2u_lib.s9s_mb_2u(sch_1):page231_i65@pure_quanta.q_res(chips)',
 PATH='I65',
 DRAWING='@S9S_MB_2U_LIB.S9S_MB_2U(SCH_1):PAGE219',
 PHYS_PAGE='231',
 XY='(3475,2975)',
 ROT='2',
 VER='1',
 PACK_TYPE='0402LF',
 CDS_LIB='pure_quanta',
 CDS_PART_NAME='Q_RES_0402LF-33.2,1%,1/16W,CHIA',
 WATTAGE='1/16W',
 TOLERANCE='1%',
 MATERIAL='CHIP',
 VALUE='33.2',
 PRIM_FILE='./archive_libs/logical/q_res/chips/chips.prt';

PART_NAME
 R589 'Q_RES_0402LF-33.2,1%,1/16W,CHIA':;

SECTION_NUMBER 1
 '@S9S_MB_2U_LIB.S9S_MB_2U(SCH_1):PAGE219_I66@PURE_QUANTA.Q_RES(CHIPS)':
 C_PATH='@s9s_mb_2u_lib.s9s_mb_2u(sch_1):page219_i66@pure_quanta.q_res(chips)',
 P_PATH='@s9s_mb_2u_lib.s9s_mb_2u(sch_1):page231_i66@pure_quanta.q_res(chips)',
 PATH='I66',
 DRAWING='@S9S_MB_2U_LIB.S9S_MB_2U(SCH_1):PAGE219',
 PHYS_PAGE='231',
 XY='(3475,3025)',
 ROT='2',
 VER='1',
 PACK_TYPE='0402LF',
 CDS_LIB='pure_quanta',
 CDS_PART_NAME='Q_RES_0402LF-33.2,1%,1/16W,CHIA',
 WATTAGE='1/16W',
 TOLERANCE='1%',
 MATERIAL='CHIP',
 VALUE='33.2',
 PRIM_FILE='./archive_libs/logical/q_res/chips/chips.prt';

PART_NAME
 R592 'Q_RES_0402LF-2.2K,5%,1/16W,EMPA':;

SECTION_NUMBER 1
 '@S9S_MB_2U_LIB.S9S_MB_2U(SCH_1):PAGE228_I173@PURE_QUANTA.Q_RES(CHIPS)':
 C_PATH='@s9s_mb_2u_lib.s9s_mb_2u(sch_1):page228_i173@pure_quanta.q_res(chips)',
 P_PATH='@s9s_mb_2u_lib.s9s_mb_2u(sch_1):page241_i173@pure_quanta.q_res(chips)',
 PATH='I173',
 DRAWING='@S9S_MB_2U_LIB.S9S_MB_2U(SCH_1):PAGE228',
 PHYS_PAGE='241',
 XY='(5000,4975)',
 ROT='0',
 VER='1',
 PACK_TYPE='0402LF',
 CDS_LIB='pure_quanta',
 CDS_PART_NAME='Q_RES_0402LF-2.2K,5%,1/16W,EMPA',
 WATTAGE='1/16W',
 TOLERANCE='5%',
 MATERIAL='EMPTY',
 VALUE='2.2K',
 PRIM_FILE='./archive_libs/logical/q_res/chips/chips.prt';

PART_NAME
 R593 'Q_RES_0402LF-0,5%,1/16W,CHIP,CA':;

SECTION_NUMBER 1
 '@S9S_MB_2U_LIB.S9S_MB_2U(SCH_1):PAGE228_I311@PURE_QUANTA.Q_RES(CHIPS)':
 C_PATH='@s9s_mb_2u_lib.s9s_mb_2u(sch_1):page228_i311@pure_quanta.q_res(chips)',
 P_PATH='@s9s_mb_2u_lib.s9s_mb_2u(sch_1):page241_i311@pure_quanta.q_res(chips)',
 PATH='I311',
 DRAWING='@S9S_MB_2U_LIB.S9S_MB_2U(SCH_1):PAGE228',
 PHYS_PAGE='241',
 XY='(3875,2050)',
 ROT='0',
 VER='1',
 PACK_TYPE='0402LF',
 LOCATION='R593',
 CDS_LIB='pure_quanta',
 CDS_PART_NAME='Q_RES_0402LF-0,5%,1/16W,CHIP,CA',
 WATTAGE='1/16W',
 TOLERANCE='5%',
 MATERIAL='CHIP',
 VALUE='0',
 PRIM_FILE='./archive_libs/logical/q_res/chips/chips.prt';

PART_NAME
 R594 'Q_RES_0402LF-0,5%,1/16W,CHIP,CA':;

SECTION_NUMBER 1
 '@S9S_MB_2U_LIB.S9S_MB_2U(SCH_1):PAGE228_I312@PURE_QUANTA.Q_RES(CHIPS)':
 C_PATH='@s9s_mb_2u_lib.s9s_mb_2u(sch_1):page228_i312@pure_quanta.q_res(chips)',
 P_PATH='@s9s_mb_2u_lib.s9s_mb_2u(sch_1):page241_i312@pure_quanta.q_res(chips)',
 PATH='I312',
 DRAWING='@S9S_MB_2U_LIB.S9S_MB_2U(SCH_1):PAGE228',
 PHYS_PAGE='241',
 XY='(3875,2000)',
 ROT='0',
 VER='1',
 PACK_TYPE='0402LF',
 LOCATION='R594',
 CDS_LIB='pure_quanta',
 CDS_PART_NAME='Q_RES_0402LF-0,5%,1/16W,CHIP,CA',
 WATTAGE='1/16W',
 TOLERANCE='5%',
 MATERIAL='CHIP',
 VALUE='0',
 PRIM_FILE='./archive_libs/logical/q_res/chips/chips.prt';

PART_NAME
 R595 'Q_RES_0402LF-0,5%,1/16W,CHIP,CA':;

SECTION_NUMBER 1
 '@S9S_MB_2U_LIB.S9S_MB_2U(SCH_1):PAGE228_I314@PURE_QUANTA.Q_RES(CHIPS)':
 C_PATH='@s9s_mb_2u_lib.s9s_mb_2u(sch_1):page228_i314@pure_quanta.q_res(chips)',
 P_PATH='@s9s_mb_2u_lib.s9s_mb_2u(sch_1):page241_i314@pure_quanta.q_res(chips)',
 PATH='I314',
 DRAWING='@S9S_MB_2U_LIB.S9S_MB_2U(SCH_1):PAGE228',
 PHYS_PAGE='241',
 XY='(3875,1750)',
 ROT='0',
 VER='1',
 PACK_TYPE='0402LF',
 LOCATION='R595',
 CDS_LIB='pure_quanta',
 CDS_PART_NAME='Q_RES_0402LF-0,5%,1/16W,CHIP,CA',
 WATTAGE='1/16W',
 TOLERANCE='5%',
 MATERIAL='CHIP',
 VALUE='0',
 PRIM_FILE='./archive_libs/logical/q_res/chips/chips.prt';

PART_NAME
 R596 'Q_RES_0402LF-0,5%,1/16W,CHIP,CA':;

SECTION_NUMBER 1
 '@S9S_MB_2U_LIB.S9S_MB_2U(SCH_1):PAGE228_I313@PURE_QUANTA.Q_RES(CHIPS)':
 C_PATH='@s9s_mb_2u_lib.s9s_mb_2u(sch_1):page228_i313@pure_quanta.q_res(chips)',
 P_PATH='@s9s_mb_2u_lib.s9s_mb_2u(sch_1):page241_i313@pure_quanta.q_res(chips)',
 PATH='I313',
 DRAWING='@S9S_MB_2U_LIB.S9S_MB_2U(SCH_1):PAGE228',
 PHYS_PAGE='241',
 XY='(3875,1700)',
 ROT='0',
 VER='1',
 PACK_TYPE='0402LF',
 LOCATION='R596',
 CDS_LIB='pure_quanta',
 CDS_PART_NAME='Q_RES_0402LF-0,5%,1/16W,CHIP,CA',
 WATTAGE='1/16W',
 TOLERANCE='5%',
 MATERIAL='CHIP',
 VALUE='0',
 PRIM_FILE='./archive_libs/logical/q_res/chips/chips.prt';

PART_NAME
 R597 'Q_RES_0402LF-0,5%,1/16W,CHIP,CA':;

SECTION_NUMBER 1
 '@S9S_MB_2U_LIB.S9S_MB_2U(SCH_1):PAGE228_I316@PURE_QUANTA.Q_RES(CHIPS)':
 C_PATH='@s9s_mb_2u_lib.s9s_mb_2u(sch_1):page228_i316@pure_quanta.q_res(chips)',
 P_PATH='@s9s_mb_2u_lib.s9s_mb_2u(sch_1):page241_i316@pure_quanta.q_res(chips)',
 PATH='I316',
 DRAWING='@S9S_MB_2U_LIB.S9S_MB_2U(SCH_1):PAGE228',
 PHYS_PAGE='241',
 XY='(3875,1425)',
 ROT='0',
 VER='1',
 PACK_TYPE='0402LF',
 LOCATION='R597',
 CDS_LIB='pure_quanta',
 CDS_PART_NAME='Q_RES_0402LF-0,5%,1/16W,CHIP,CA',
 WATTAGE='1/16W',
 TOLERANCE='5%',
 MATERIAL='CHIP',
 VALUE='0',
 PRIM_FILE='./archive_libs/logical/q_res/chips/chips.prt';

PART_NAME
 R598 'Q_RES_0402LF-0,5%,1/16W,CHIP,CA':;

SECTION_NUMBER 1
 '@S9S_MB_2U_LIB.S9S_MB_2U(SCH_1):PAGE228_I315@PURE_QUANTA.Q_RES(CHIPS)':
 C_PATH='@s9s_mb_2u_lib.s9s_mb_2u(sch_1):page228_i315@pure_quanta.q_res(chips)',
 P_PATH='@s9s_mb_2u_lib.s9s_mb_2u(sch_1):page241_i315@pure_quanta.q_res(chips)',
 PATH='I315',
 DRAWING='@S9S_MB_2U_LIB.S9S_MB_2U(SCH_1):PAGE228',
 PHYS_PAGE='241',
 XY='(3875,1375)',
 ROT='0',
 VER='1',
 PACK_TYPE='0402LF',
 LOCATION='R598',
 CDS_LIB='pure_quanta',
 CDS_PART_NAME='Q_RES_0402LF-0,5%,1/16W,CHIP,CA',
 WATTAGE='1/16W',
 TOLERANCE='5%',
 MATERIAL='CHIP',
 VALUE='0',
 PRIM_FILE='./archive_libs/logical/q_res/chips/chips.prt';

PART_NAME
 R599 'Q_RES_0402LF-0,5%,1/16W,CHIP,CA':;

SECTION_NUMBER 1
 '@S9S_MB_2U_LIB.S9S_MB_2U(SCH_1):PAGE228_I317@PURE_QUANTA.Q_RES(CHIPS)':
 C_PATH='@s9s_mb_2u_lib.s9s_mb_2u(sch_1):page228_i317@pure_quanta.q_res(chips)',
 P_PATH='@s9s_mb_2u_lib.s9s_mb_2u(sch_1):page241_i317@pure_quanta.q_res(chips)',
 PATH='I317',
 DRAWING='@S9S_MB_2U_LIB.S9S_MB_2U(SCH_1):PAGE228',
 PHYS_PAGE='241',
 XY='(3875,1125)',
 ROT='0',
 VER='1',
 PACK_TYPE='0402LF',
 LOCATION='R599',
 CDS_LIB='pure_quanta',
 CDS_PART_NAME='Q_RES_0402LF-0,5%,1/16W,CHIP,CA',
 WATTAGE='1/16W',
 TOLERANCE='5%',
 MATERIAL='CHIP',
 VALUE='0',
 PRIM_FILE='./archive_libs/logical/q_res/chips/chips.prt';

PART_NAME
 R600 'Q_RES_0402LF-0,5%,1/16W,CHIP,CA':;

SECTION_NUMBER 1
 '@S9S_MB_2U_LIB.S9S_MB_2U(SCH_1):PAGE228_I318@PURE_QUANTA.Q_RES(CHIPS)':
 C_PATH='@s9s_mb_2u_lib.s9s_mb_2u(sch_1):page228_i318@pure_quanta.q_res(chips)',
 P_PATH='@s9s_mb_2u_lib.s9s_mb_2u(sch_1):page241_i318@pure_quanta.q_res(chips)',
 PATH='I318',
 DRAWING='@S9S_MB_2U_LIB.S9S_MB_2U(SCH_1):PAGE228',
 PHYS_PAGE='241',
 XY='(3875,1075)',
 ROT='0',
 VER='1',
 PACK_TYPE='0402LF',
 LOCATION='R600',
 CDS_LIB='pure_quanta',
 CDS_PART_NAME='Q_RES_0402LF-0,5%,1/16W,CHIP,CA',
 WATTAGE='1/16W',
 TOLERANCE='5%',
 MATERIAL='CHIP',
 VALUE='0',
 PRIM_FILE='./archive_libs/logical/q_res/chips/chips.prt';

PART_NAME
 R601 'Q_RES_0402LF-2.2K,5%,1/16W,EMPA':;

SECTION_NUMBER 1
 '@S9S_MB_2U_LIB.S9S_MB_2U(SCH_1):PAGE228_I172@PURE_QUANTA.Q_RES(CHIPS)':
 C_PATH='@s9s_mb_2u_lib.s9s_mb_2u(sch_1):page228_i172@pure_quanta.q_res(chips)',
 P_PATH='@s9s_mb_2u_lib.s9s_mb_2u(sch_1):page241_i172@pure_quanta.q_res(chips)',
 PATH='I172',
 DRAWING='@S9S_MB_2U_LIB.S9S_MB_2U(SCH_1):PAGE228',
 PHYS_PAGE='241',
 XY='(5000,4925)',
 ROT='0',
 VER='1',
 PACK_TYPE='0402LF',
 CDS_LIB='pure_quanta',
 CDS_PART_NAME='Q_RES_0402LF-2.2K,5%,1/16W,EMPA',
 WATTAGE='1/16W',
 TOLERANCE='5%',
 MATERIAL='EMPTY',
 VALUE='2.2K',
 PRIM_FILE='./archive_libs/logical/q_res/chips/chips.prt';

PART_NAME
 R607 'Q_RES_0402LF-1K,1%,1/16W,EMPTYA':;

SECTION_NUMBER 1
 '@S9S_MB_2U_LIB.S9S_MB_2U(SCH_1):PAGE187_I21@PURE_QUANTA.Q_RES(CHIPS)':
 C_PATH='@s9s_mb_2u_lib.s9s_mb_2u(sch_1):page187_i21@pure_quanta.q_res(chips)',
 P_PATH='@s9s_mb_2u_lib.s9s_mb_2u(sch_1):page199_i21@pure_quanta.q_res(chips)',
 PATH='I21',
 DRAWING='@S9S_MB_2U_LIB.S9S_MB_2U(SCH_1):PAGE187',
 PHYS_PAGE='199',
 XY='(-8425,2950)',
 ROT='0',
 VER='2',
 PACK_TYPE='0402LF',
 CDS_LIB='pure_quanta',
 CDS_PART_NAME='Q_RES_0402LF-1K,1%,1/16W,EMPTYA',
 WATTAGE='1/16W',
 TOLERANCE='1%',
 MATERIAL='EMPTY',
 VALUE='1K',
 PRIM_FILE='./archive_libs/logical/q_res/chips/chips.prt';

PART_NAME
 R608 'Q_RES_0402LF-10K,1%,1/16W,CHIPA':;

SECTION_NUMBER 1
 '@S9S_MB_2U_LIB.S9S_MB_2U(SCH_1):PAGE187_I36@PURE_QUANTA.Q_RES(CHIPS)':
 C_PATH='@s9s_mb_2u_lib.s9s_mb_2u(sch_1):page187_i36@pure_quanta.q_res(chips)',
 P_PATH='@s9s_mb_2u_lib.s9s_mb_2u(sch_1):page199_i36@pure_quanta.q_res(chips)',
 PATH='I36',
 DRAWING='@S9S_MB_2U_LIB.S9S_MB_2U(SCH_1):PAGE187',
 PHYS_PAGE='199',
 XY='(-8425,2425)',
 ROT='0',
 VER='2',
 PACK_TYPE='0402LF',
 CDS_LIB='pure_quanta',
 CDS_PART_NAME='Q_RES_0402LF-10K,1%,1/16W,CHIPA',
 WATTAGE='1/16W',
 TOLERANCE='1%',
 MATERIAL='CHIP',
 VALUE='10K',
 PRIM_FILE='./archive_libs/logical/q_res/chips/chips.prt';

PART_NAME
 R609 'Q_RES_0402LF-1K,1%,1/16W,EMPTYA':;

SECTION_NUMBER 1
 '@S9S_MB_2U_LIB.S9S_MB_2U(SCH_1):PAGE187_I39@PURE_QUANTA.Q_RES(CHIPS)':
 C_PATH='@s9s_mb_2u_lib.s9s_mb_2u(sch_1):page187_i39@pure_quanta.q_res(chips)',
 P_PATH='@s9s_mb_2u_lib.s9s_mb_2u(sch_1):page199_i39@pure_quanta.q_res(chips)',
 PATH='I39',
 DRAWING='@S9S_MB_2U_LIB.S9S_MB_2U(SCH_1):PAGE187',
 PHYS_PAGE='199',
 XY='(-8425,950)',
 ROT='0',
 VER='2',
 PACK_TYPE='0402LF',
 CDS_LIB='pure_quanta',
 CDS_PART_NAME='Q_RES_0402LF-1K,1%,1/16W,EMPTYA',
 WATTAGE='1/16W',
 TOLERANCE='1%',
 MATERIAL='EMPTY',
 VALUE='1K',
 PRIM_FILE='./archive_libs/logical/q_res/chips/chips.prt';

PART_NAME
 R610 'Q_RES_0402LF-10K,1%,1/16W,CHIPA':;

SECTION_NUMBER 1
 '@S9S_MB_2U_LIB.S9S_MB_2U(SCH_1):PAGE187_I40@PURE_QUANTA.Q_RES(CHIPS)':
 C_PATH='@s9s_mb_2u_lib.s9s_mb_2u(sch_1):page187_i40@pure_quanta.q_res(chips)',
 P_PATH='@s9s_mb_2u_lib.s9s_mb_2u(sch_1):page199_i40@pure_quanta.q_res(chips)',
 PATH='I40',
 DRAWING='@S9S_MB_2U_LIB.S9S_MB_2U(SCH_1):PAGE187',
 PHYS_PAGE='199',
 XY='(-8425,425)',
 ROT='0',
 VER='2',
 PACK_TYPE='0402LF',
 CDS_LIB='pure_quanta',
 CDS_PART_NAME='Q_RES_0402LF-10K,1%,1/16W,CHIPA',
 WATTAGE='1/16W',
 TOLERANCE='1%',
 MATERIAL='CHIP',
 VALUE='10K',
 PRIM_FILE='./archive_libs/logical/q_res/chips/chips.prt';

PART_NAME
 R611 'Q_RES_0402LF-1K,1%,1/16W,CHIP,A':;

SECTION_NUMBER 1
 '@S9S_MB_2U_LIB.S9S_MB_2U(SCH_1):PAGE187_I43@PURE_QUANTA.Q_RES(CHIPS)':
 C_PATH='@s9s_mb_2u_lib.s9s_mb_2u(sch_1):page187_i43@pure_quanta.q_res(chips)',
 P_PATH='@s9s_mb_2u_lib.s9s_mb_2u(sch_1):page199_i43@pure_quanta.q_res(chips)',
 PATH='I43',
 DRAWING='@S9S_MB_2U_LIB.S9S_MB_2U(SCH_1):PAGE187',
 PHYS_PAGE='199',
 XY='(-8425,-1100)',
 ROT='0',
 VER='2',
 PACK_TYPE='0402LF',
 CDS_LIB='pure_quanta',
 CDS_PART_NAME='Q_RES_0402LF-1K,1%,1/16W,CHIP,A',
 WATTAGE='1/16W',
 TOLERANCE='1%',
 MATERIAL='CHIP',
 VALUE='1K',
 PRIM_FILE='./archive_libs/logical/q_res/chips/chips.prt';

PART_NAME
 R612 'Q_RES_0402LF-10K,1%,1/16W,EMPTA':;

SECTION_NUMBER 1
 '@S9S_MB_2U_LIB.S9S_MB_2U(SCH_1):PAGE187_I44@PURE_QUANTA.Q_RES(CHIPS)':
 C_PATH='@s9s_mb_2u_lib.s9s_mb_2u(sch_1):page187_i44@pure_quanta.q_res(chips)',
 P_PATH='@s9s_mb_2u_lib.s9s_mb_2u(sch_1):page199_i44@pure_quanta.q_res(chips)',
 PATH='I44',
 DRAWING='@S9S_MB_2U_LIB.S9S_MB_2U(SCH_1):PAGE187',
 PHYS_PAGE='199',
 XY='(-8425,-1625)',
 ROT='0',
 VER='2',
 PACK_TYPE='0402LF',
 CDS_LIB='pure_quanta',
 CDS_PART_NAME='Q_RES_0402LF-10K,1%,1/16W,EMPTA',
 WATTAGE='1/16W',
 TOLERANCE='1%',
 MATERIAL='EMPTY',
 VALUE='10K',
 PRIM_FILE='./archive_libs/logical/q_res/chips/chips.prt';

PART_NAME
 R613 'Q_RES_0402LF-10K,1%,1/16W,CHIPA':;

SECTION_NUMBER 1
 '@S9S_MB_2U_LIB.S9S_MB_2U(SCH_1):PAGE187_I18@PURE_QUANTA.Q_RES(CHIPS)':
 C_PATH='@s9s_mb_2u_lib.s9s_mb_2u(sch_1):page187_i18@pure_quanta.q_res(chips)',
 P_PATH='@s9s_mb_2u_lib.s9s_mb_2u(sch_1):page199_i18@pure_quanta.q_res(chips)',
 PATH='I18',
 DRAWING='@S9S_MB_2U_LIB.S9S_MB_2U(SCH_1):PAGE187',
 PHYS_PAGE='199',
 XY='(-5300,2950)',
 ROT='0',
 VER='2',
 PACK_TYPE='0402LF',
 CDS_LIB='pure_quanta',
 CDS_PART_NAME='Q_RES_0402LF-10K,1%,1/16W,CHIPA',
 WATTAGE='1/16W',
 TOLERANCE='1%',
 MATERIAL='CHIP',
 VALUE='10K',
 PRIM_FILE='./archive_libs/logical/q_res/chips/chips.prt';

PART_NAME
 R614 'Q_RES_0402LF-1K,1%,1/16W,EMPTYA':;

SECTION_NUMBER 1
 '@S9S_MB_2U_LIB.S9S_MB_2U(SCH_1):PAGE187_I23@PURE_QUANTA.Q_RES(CHIPS)':
 C_PATH='@s9s_mb_2u_lib.s9s_mb_2u(sch_1):page187_i23@pure_quanta.q_res(chips)',
 P_PATH='@s9s_mb_2u_lib.s9s_mb_2u(sch_1):page199_i23@pure_quanta.q_res(chips)',
 PATH='I23',
 DRAWING='@S9S_MB_2U_LIB.S9S_MB_2U(SCH_1):PAGE187',
 PHYS_PAGE='199',
 XY='(-5300,2425)',
 ROT='0',
 VER='2',
 PACK_TYPE='0402LF',
 CDS_LIB='pure_quanta',
 CDS_PART_NAME='Q_RES_0402LF-1K,1%,1/16W,EMPTYA',
 WATTAGE='1/16W',
 TOLERANCE='1%',
 MATERIAL='EMPTY',
 VALUE='1K',
 PRIM_FILE='./archive_libs/logical/q_res/chips/chips.prt';

PART_NAME
 R615 'Q_RES_0402LF-1K,1%,1/16W,CHIP,A':;

SECTION_NUMBER 1
 '@S9S_MB_2U_LIB.S9S_MB_2U(SCH_1):PAGE187_I51@PURE_QUANTA.Q_RES(CHIPS)':
 C_PATH='@s9s_mb_2u_lib.s9s_mb_2u(sch_1):page187_i51@pure_quanta.q_res(chips)',
 P_PATH='@s9s_mb_2u_lib.s9s_mb_2u(sch_1):page199_i51@pure_quanta.q_res(chips)',
 PATH='I51',
 DRAWING='@S9S_MB_2U_LIB.S9S_MB_2U(SCH_1):PAGE187',
 PHYS_PAGE='199',
 XY='(-5300,950)',
 ROT='0',
 VER='2',
 PACK_TYPE='0402LF',
 CDS_LIB='pure_quanta',
 CDS_PART_NAME='Q_RES_0402LF-1K,1%,1/16W,CHIP,A',
 WATTAGE='1/16W',
 TOLERANCE='1%',
 MATERIAL='CHIP',
 VALUE='1K',
 PRIM_FILE='./archive_libs/logical/q_res/chips/chips.prt';

PART_NAME
 R617 'Q_RES_0402LF-1K,1%,1/16W,EMPTYA':;

SECTION_NUMBER 1
 '@S9S_MB_2U_LIB.S9S_MB_2U(SCH_1):PAGE187_I54@PURE_QUANTA.Q_RES(CHIPS)':
 C_PATH='@s9s_mb_2u_lib.s9s_mb_2u(sch_1):page187_i54@pure_quanta.q_res(chips)',
 P_PATH='@s9s_mb_2u_lib.s9s_mb_2u(sch_1):page199_i54@pure_quanta.q_res(chips)',
 PATH='I54',
 DRAWING='@S9S_MB_2U_LIB.S9S_MB_2U(SCH_1):PAGE187',
 PHYS_PAGE='199',
 XY='(-5300,-1150)',
 ROT='0',
 VER='2',
 PACK_TYPE='0402LF',
 CDS_LIB='pure_quanta',
 CDS_PART_NAME='Q_RES_0402LF-1K,1%,1/16W,EMPTYA',
 WATTAGE='1/16W',
 TOLERANCE='1%',
 MATERIAL='EMPTY',
 VALUE='1K',
 PRIM_FILE='./archive_libs/logical/q_res/chips/chips.prt';

PART_NAME
 R618 'Q_RES_0402LF-10K,1%,1/16W,CHIPA':;

SECTION_NUMBER 1
 '@S9S_MB_2U_LIB.S9S_MB_2U(SCH_1):PAGE187_I53@PURE_QUANTA.Q_RES(CHIPS)':
 C_PATH='@s9s_mb_2u_lib.s9s_mb_2u(sch_1):page187_i53@pure_quanta.q_res(chips)',
 P_PATH='@s9s_mb_2u_lib.s9s_mb_2u(sch_1):page199_i53@pure_quanta.q_res(chips)',
 PATH='I53',
 DRAWING='@S9S_MB_2U_LIB.S9S_MB_2U(SCH_1):PAGE187',
 PHYS_PAGE='199',
 XY='(-5300,-1625)',
 ROT='0',
 VER='2',
 PACK_TYPE='0402LF',
 CDS_LIB='pure_quanta',
 CDS_PART_NAME='Q_RES_0402LF-10K,1%,1/16W,CHIPA',
 WATTAGE='1/16W',
 TOLERANCE='1%',
 MATERIAL='CHIP',
 VALUE='10K',
 PRIM_FILE='./archive_libs/logical/q_res/chips/chips.prt';

PART_NAME
 R619 'Q_RES_0402LF-10K,1%,1/16W,CHIPA':;

SECTION_NUMBER 1
 '@S9S_MB_2U_LIB.S9S_MB_2U(SCH_1):PAGE187_I48@PURE_QUANTA.Q_RES(CHIPS)':
 C_PATH='@s9s_mb_2u_lib.s9s_mb_2u(sch_1):page187_i48@pure_quanta.q_res(chips)',
 P_PATH='@s9s_mb_2u_lib.s9s_mb_2u(sch_1):page199_i48@pure_quanta.q_res(chips)',
 PATH='I48',
 DRAWING='@S9S_MB_2U_LIB.S9S_MB_2U(SCH_1):PAGE187',
 PHYS_PAGE='199',
 XY='(-2125,2950)',
 ROT='0',
 VER='2',
 PACK_TYPE='0402LF',
 CDS_LIB='pure_quanta',
 CDS_PART_NAME='Q_RES_0402LF-10K,1%,1/16W,CHIPA',
 WATTAGE='1/16W',
 TOLERANCE='1%',
 MATERIAL='CHIP',
 VALUE='10K',
 PRIM_FILE='./archive_libs/logical/q_res/chips/chips.prt';

PART_NAME
 R621 'Q_RES_0402LF-1K,1%,1/16W,EMPTYA':;

SECTION_NUMBER 1
 '@S9S_MB_2U_LIB.S9S_MB_2U(SCH_1):PAGE187_I55@PURE_QUANTA.Q_RES(CHIPS)':
 C_PATH='@s9s_mb_2u_lib.s9s_mb_2u(sch_1):page187_i55@pure_quanta.q_res(chips)',
 P_PATH='@s9s_mb_2u_lib.s9s_mb_2u(sch_1):page199_i55@pure_quanta.q_res(chips)',
 PATH='I55',
 DRAWING='@S9S_MB_2U_LIB.S9S_MB_2U(SCH_1):PAGE187',
 PHYS_PAGE='199',
 XY='(-2125,900)',
 ROT='0',
 VER='2',
 PACK_TYPE='0402LF',
 CDS_LIB='pure_quanta',
 CDS_PART_NAME='Q_RES_0402LF-1K,1%,1/16W,EMPTYA',
 WATTAGE='1/16W',
 TOLERANCE='1%',
 MATERIAL='EMPTY',
 VALUE='1K',
 PRIM_FILE='./archive_libs/logical/q_res/chips/chips.prt';

PART_NAME
 R622 'Q_RES_0402LF-1K,1%,1/16W,CHIP,A':;

SECTION_NUMBER 1
 '@S9S_MB_2U_LIB.S9S_MB_2U(SCH_1):PAGE187_I56@PURE_QUANTA.Q_RES(CHIPS)':
 C_PATH='@s9s_mb_2u_lib.s9s_mb_2u(sch_1):page187_i56@pure_quanta.q_res(chips)',
 P_PATH='@s9s_mb_2u_lib.s9s_mb_2u(sch_1):page199_i56@pure_quanta.q_res(chips)',
 PATH='I56',
 DRAWING='@S9S_MB_2U_LIB.S9S_MB_2U(SCH_1):PAGE187',
 PHYS_PAGE='199',
 XY='(-2125,425)',
 ROT='0',
 VER='2',
 PACK_TYPE='0402LF',
 CDS_LIB='pure_quanta',
 CDS_PART_NAME='Q_RES_0402LF-1K,1%,1/16W,CHIP,A',
 WATTAGE='1/16W',
 TOLERANCE='1%',
 MATERIAL='CHIP',
 VALUE='1K',
 PRIM_FILE='./archive_libs/logical/q_res/chips/chips.prt';

PART_NAME
 R623 'Q_RES_0402LF-1K,1%,1/16W,EMPTYA':;

SECTION_NUMBER 1
 '@S9S_MB_2U_LIB.S9S_MB_2U(SCH_1):PAGE187_I13@PURE_QUANTA.Q_RES(CHIPS)':
 C_PATH='@s9s_mb_2u_lib.s9s_mb_2u(sch_1):page187_i13@pure_quanta.q_res(chips)',
 P_PATH='@s9s_mb_2u_lib.s9s_mb_2u(sch_1):page199_i13@pure_quanta.q_res(chips)',
 PATH='I13',
 DRAWING='@S9S_MB_2U_LIB.S9S_MB_2U(SCH_1):PAGE187',
 PHYS_PAGE='199',
 XY='(-2125,-1125)',
 ROT='0',
 VER='2',
 PACK_TYPE='0402LF',
 CDS_LIB='pure_quanta',
 CDS_PART_NAME='Q_RES_0402LF-1K,1%,1/16W,EMPTYA',
 WATTAGE='1/16W',
 TOLERANCE='1%',
 MATERIAL='EMPTY',
 VALUE='1K',
 PRIM_FILE='./archive_libs/logical/q_res/chips/chips.prt';

PART_NAME
 R624 'Q_RES_0402LF-10K,1%,1/16W,CHIPA':;

SECTION_NUMBER 1
 '@S9S_MB_2U_LIB.S9S_MB_2U(SCH_1):PAGE187_I14@PURE_QUANTA.Q_RES(CHIPS)':
 C_PATH='@s9s_mb_2u_lib.s9s_mb_2u(sch_1):page187_i14@pure_quanta.q_res(chips)',
 P_PATH='@s9s_mb_2u_lib.s9s_mb_2u(sch_1):page199_i14@pure_quanta.q_res(chips)',
 PATH='I14',
 DRAWING='@S9S_MB_2U_LIB.S9S_MB_2U(SCH_1):PAGE187',
 PHYS_PAGE='199',
 XY='(-2125,-1650)',
 ROT='0',
 VER='2',
 PACK_TYPE='0402LF',
 CDS_LIB='pure_quanta',
 CDS_PART_NAME='Q_RES_0402LF-10K,1%,1/16W,CHIPA',
 WATTAGE='1/16W',
 TOLERANCE='1%',
 MATERIAL='CHIP',
 VALUE='10K',
 PRIM_FILE='./archive_libs/logical/q_res/chips/chips.prt';

PART_NAME
 R625 'Q_RES_0402LF-1K,1%,1/16W,EMPTYA':;

SECTION_NUMBER 1
 '@S9S_MB_2U_LIB.S9S_MB_2U(SCH_1):PAGE127_I24@PURE_QUANTA.Q_RES(CHIPS)':
 C_PATH='@s9s_mb_2u_lib.s9s_mb_2u(sch_1):page127_i24@pure_quanta.q_res(chips)',
 P_PATH='@s9s_mb_2u_lib.s9s_mb_2u(sch_1):page127_i24@pure_quanta.q_res(chips)',
 PATH='I24',
 DRAWING='@S9S_MB_2U_LIB.S9S_MB_2U(SCH_1):PAGE127',
 PHYS_PAGE='127',
 XY='(1075,3625)',
 ROT='0',
 VER='2',
 PACK_TYPE='0402LF',
 CDS_LIB='pure_quanta',
 CDS_PART_NAME='Q_RES_0402LF-1K,1%,1/16W,EMPTYA',
 WATTAGE='1/16W',
 TOLERANCE='1%',
 MATERIAL='EMPTY',
 VALUE='1K',
 PRIM_FILE='./archive_libs/logical/q_res/chips/chips.prt';

PART_NAME
 R626 'Q_RES_0402LF-10K,1%,1/16W,CHIPA':;

SECTION_NUMBER 1
 '@S9S_MB_2U_LIB.S9S_MB_2U(SCH_1):PAGE127_I26@PURE_QUANTA.Q_RES(CHIPS)':
 C_PATH='@s9s_mb_2u_lib.s9s_mb_2u(sch_1):page127_i26@pure_quanta.q_res(chips)',
 P_PATH='@s9s_mb_2u_lib.s9s_mb_2u(sch_1):page127_i26@pure_quanta.q_res(chips)',
 PATH='I26',
 DRAWING='@S9S_MB_2U_LIB.S9S_MB_2U(SCH_1):PAGE127',
 PHYS_PAGE='127',
 XY='(1075,2975)',
 ROT='0',
 VER='2',
 PACK_TYPE='0402LF',
 CDS_LIB='pure_quanta',
 CDS_PART_NAME='Q_RES_0402LF-10K,1%,1/16W,CHIPA',
 WATTAGE='1/16W',
 TOLERANCE='1%',
 MATERIAL='CHIP',
 VALUE='10K',
 PRIM_FILE='./archive_libs/logical/q_res/chips/chips.prt';

PART_NAME
 R627 'Q_RES_0402LF-1K,1%,1/16W,EMPTYA':;

SECTION_NUMBER 1
 '@S9S_MB_2U_LIB.S9S_MB_2U(SCH_1):PAGE127_I14@PURE_QUANTA.Q_RES(CHIPS)':
 C_PATH='@s9s_mb_2u_lib.s9s_mb_2u(sch_1):page127_i14@pure_quanta.q_res(chips)',
 P_PATH='@s9s_mb_2u_lib.s9s_mb_2u(sch_1):page127_i14@pure_quanta.q_res(chips)',
 PATH='I14',
 DRAWING='@S9S_MB_2U_LIB.S9S_MB_2U(SCH_1):PAGE127',
 PHYS_PAGE='127',
 XY='(1350,3625)',
 ROT='0',
 VER='2',
 PACK_TYPE='0402LF',
 CDS_LIB='pure_quanta',
 CDS_PART_NAME='Q_RES_0402LF-1K,1%,1/16W,EMPTYA',
 WATTAGE='1/16W',
 TOLERANCE='1%',
 MATERIAL='EMPTY',
 VALUE='1K',
 PRIM_FILE='./archive_libs/logical/q_res/chips/chips.prt';

PART_NAME
 R628 'Q_RES_0402LF-10K,1%,1/16W,CHIPA':;

SECTION_NUMBER 1
 '@S9S_MB_2U_LIB.S9S_MB_2U(SCH_1):PAGE127_I17@PURE_QUANTA.Q_RES(CHIPS)':
 C_PATH='@s9s_mb_2u_lib.s9s_mb_2u(sch_1):page127_i17@pure_quanta.q_res(chips)',
 P_PATH='@s9s_mb_2u_lib.s9s_mb_2u(sch_1):page127_i17@pure_quanta.q_res(chips)',
 PATH='I17',
 DRAWING='@S9S_MB_2U_LIB.S9S_MB_2U(SCH_1):PAGE127',
 PHYS_PAGE='127',
 XY='(1350,2975)',
 ROT='0',
 VER='2',
 PACK_TYPE='0402LF',
 CDS_LIB='pure_quanta',
 CDS_PART_NAME='Q_RES_0402LF-10K,1%,1/16W,CHIPA',
 WATTAGE='1/16W',
 TOLERANCE='1%',
 MATERIAL='CHIP',
 VALUE='10K',
 PRIM_FILE='./archive_libs/logical/q_res/chips/chips.prt';

PART_NAME
 R629 'Q_RES_0402LF-1K,1%,1/16W,CHIP,A':;

SECTION_NUMBER 1
 '@S9S_MB_2U_LIB.S9S_MB_2U(SCH_1):PAGE127_I13@PURE_QUANTA.Q_RES(CHIPS)':
 C_PATH='@s9s_mb_2u_lib.s9s_mb_2u(sch_1):page127_i13@pure_quanta.q_res(chips)',
 P_PATH='@s9s_mb_2u_lib.s9s_mb_2u(sch_1):page127_i13@pure_quanta.q_res(chips)',
 PATH='I13',
 DRAWING='@S9S_MB_2U_LIB.S9S_MB_2U(SCH_1):PAGE127',
 PHYS_PAGE='127',
 XY='(1625,3625)',
 ROT='0',
 VER='2',
 PACK_TYPE='0402LF',
 CDS_LIB='pure_quanta',
 CDS_PART_NAME='Q_RES_0402LF-1K,1%,1/16W,CHIP,A',
 WATTAGE='1/16W',
 TOLERANCE='1%',
 MATERIAL='CHIP',
 VALUE='1K',
 PRIM_FILE='./archive_libs/logical/q_res/chips/chips.prt';

PART_NAME
 R630 'Q_RES_0402LF-10K,1%,1/16W,EMPTA':;

SECTION_NUMBER 1
 '@S9S_MB_2U_LIB.S9S_MB_2U(SCH_1):PAGE127_I15@PURE_QUANTA.Q_RES(CHIPS)':
 C_PATH='@s9s_mb_2u_lib.s9s_mb_2u(sch_1):page127_i15@pure_quanta.q_res(chips)',
 P_PATH='@s9s_mb_2u_lib.s9s_mb_2u(sch_1):page127_i15@pure_quanta.q_res(chips)',
 PATH='I15',
 DRAWING='@S9S_MB_2U_LIB.S9S_MB_2U(SCH_1):PAGE127',
 PHYS_PAGE='127',
 XY='(1625,2975)',
 ROT='0',
 VER='2',
 PACK_TYPE='0402LF',
 CDS_LIB='pure_quanta',
 CDS_PART_NAME='Q_RES_0402LF-10K,1%,1/16W,EMPTA',
 WATTAGE='1/16W',
 TOLERANCE='1%',
 MATERIAL='EMPTY',
 VALUE='10K',
 PRIM_FILE='./archive_libs/logical/q_res/chips/chips.prt';

PART_NAME
 R635 'Q_RES_0402LF-10K,1%,1/16W,CHIPA':;

SECTION_NUMBER 1
 '@S9S_MB_2U_LIB.S9S_MB_2U(SCH_1):PAGE175_I234@PURE_QUANTA.Q_RES(CHIPS)':
 C_PATH='@s9s_mb_2u_lib.s9s_mb_2u(sch_1):page175_i234@pure_quanta.q_res(chips)',
 P_PATH='@s9s_mb_2u_lib.s9s_mb_2u(sch_1):page183_i234@pure_quanta.q_res(chips)',
 PATH='I234',
 DRAWING='@S9S_MB_2U_LIB.S9S_MB_2U(SCH_1):PAGE175',
 PHYS_PAGE='183',
 XY='(3475,-275)',
 ROT='0',
 VER='1',
 PACK_TYPE='0402LF',
 CDS_LIB='pure_quanta',
 CDS_PART_NAME='Q_RES_0402LF-10K,1%,1/16W,CHIPA',
 WATTAGE='1/16W',
 TOLERANCE='1%',
 MATERIAL='CHIP',
 VALUE='10K',
 PRIM_FILE='./archive_libs/logical/q_res/chips/chips.prt';

PART_NAME
 R650 'Q_RES_0402LF-1K,1%,1/16W,CHIP,A':;

SECTION_NUMBER 1
 '@S9S_MB_2U_LIB.S9S_MB_2U(SCH_1):PAGE127_I32@PURE_QUANTA.Q_RES(CHIPS)':
 C_PATH='@s9s_mb_2u_lib.s9s_mb_2u(sch_1):page127_i32@pure_quanta.q_res(chips)',
 P_PATH='@s9s_mb_2u_lib.s9s_mb_2u(sch_1):page127_i32@pure_quanta.q_res(chips)',
 PATH='I32',
 DRAWING='@S9S_MB_2U_LIB.S9S_MB_2U(SCH_1):PAGE127',
 PHYS_PAGE='127',
 XY='(-2175,2000)',
 ROT='0',
 VER='2',
 PACK_TYPE='0402LF',
 CDS_LIB='pure_quanta',
 CDS_PART_NAME='Q_RES_0402LF-1K,1%,1/16W,CHIP,A',
 WATTAGE='1/16W',
 TOLERANCE='1%',
 MATERIAL='CHIP',
 VALUE='1K',
 PRIM_FILE='./archive_libs/logical/q_res/chips/chips.prt';

PART_NAME
 R651 'Q_RES_0402LF-2.2K,5%,1/16W,CHIA':;

SECTION_NUMBER 1
 '@S9S_MB_2U_LIB.S9S_MB_2U(SCH_1):PAGE219_I22@PURE_QUANTA.Q_RES(CHIPS)':
 C_PATH='@s9s_mb_2u_lib.s9s_mb_2u(sch_1):page219_i22@pure_quanta.q_res(chips)',
 P_PATH='@s9s_mb_2u_lib.s9s_mb_2u(sch_1):page231_i22@pure_quanta.q_res(chips)',
 PATH='I22',
 DRAWING='@S9S_MB_2U_LIB.S9S_MB_2U(SCH_1):PAGE219',
 PHYS_PAGE='231',
 XY='(3875,-900)',
 ROT='0',
 VER='1',
 PACK_TYPE='0402LF',
 CDS_LIB='pure_quanta',
 CDS_PART_NAME='Q_RES_0402LF-2.2K,5%,1/16W,CHIA',
 WATTAGE='1/16W',
 TOLERANCE='5%',
 MATERIAL='CHIP',
 VALUE='2.2K',
 PRIM_FILE='./archive_libs/logical/q_res/chips/chips.prt';

PART_NAME
 R652 'Q_RES_0402LF-2.2K,5%,1/16W,CHIA':;

SECTION_NUMBER 1
 '@S9S_MB_2U_LIB.S9S_MB_2U(SCH_1):PAGE219_I23@PURE_QUANTA.Q_RES(CHIPS)':
 C_PATH='@s9s_mb_2u_lib.s9s_mb_2u(sch_1):page219_i23@pure_quanta.q_res(chips)',
 P_PATH='@s9s_mb_2u_lib.s9s_mb_2u(sch_1):page231_i23@pure_quanta.q_res(chips)',
 PATH='I23',
 DRAWING='@S9S_MB_2U_LIB.S9S_MB_2U(SCH_1):PAGE219',
 PHYS_PAGE='231',
 XY='(3875,-950)',
 ROT='0',
 VER='1',
 PACK_TYPE='0402LF',
 CDS_LIB='pure_quanta',
 CDS_PART_NAME='Q_RES_0402LF-2.2K,5%,1/16W,CHIA',
 WATTAGE='1/16W',
 TOLERANCE='5%',
 MATERIAL='CHIP',
 VALUE='2.2K',
 PRIM_FILE='./archive_libs/logical/q_res/chips/chips.prt';

PART_NAME
 R661 'Q_RES_0402LF-1K,1%,1/16W,CHIP,A':;

SECTION_NUMBER 1
 '@S9S_MB_2U_LIB.S9S_MB_2U(SCH_1):PAGE218_I4@PURE_QUANTA.Q_RES(CHIPS)':
 C_PATH='@s9s_mb_2u_lib.s9s_mb_2u(sch_1):page218_i4@pure_quanta.q_res(chips)',
 P_PATH='@s9s_mb_2u_lib.s9s_mb_2u(sch_1):page230_i4@pure_quanta.q_res(chips)',
 PATH='I4',
 DRAWING='@S9S_MB_2U_LIB.S9S_MB_2U(SCH_1):PAGE218',
 PHYS_PAGE='230',
 XY='(-1050,1225)',
 ROT='0',
 VER='2',
 PACK_TYPE='0402LF',
 CDS_LIB='pure_quanta',
 CDS_PART_NAME='Q_RES_0402LF-1K,1%,1/16W,CHIP,A',
 WATTAGE='1/16W',
 TOLERANCE='1%',
 MATERIAL='CHIP',
 VALUE='1K',
 PRIM_FILE='./archive_libs/logical/q_res/chips/chips.prt';

PART_NAME
 R662 'Q_RES_0402LF-499,1%,1/16W,CHIPA':;

SECTION_NUMBER 1
 '@S9S_MB_2U_LIB.S9S_MB_2U(SCH_1):PAGE218_I17@PURE_QUANTA.Q_RES(CHIPS)':
 C_PATH='@s9s_mb_2u_lib.s9s_mb_2u(sch_1):page218_i17@pure_quanta.q_res(chips)',
 P_PATH='@s9s_mb_2u_lib.s9s_mb_2u(sch_1):page230_i17@pure_quanta.q_res(chips)',
 PATH='I17',
 DRAWING='@S9S_MB_2U_LIB.S9S_MB_2U(SCH_1):PAGE218',
 PHYS_PAGE='230',
 XY='(-25,4300)',
 ROT='0',
 VER='2',
 PACK_TYPE='0402LF',
 CDS_LIB='pure_quanta',
 CDS_PART_NAME='Q_RES_0402LF-499,1%,1/16W,CHIPA',
 WATTAGE='1/16W',
 TOLERANCE='1%',
 MATERIAL='CHIP',
 VALUE='499',
 PRIM_FILE='./archive_libs/logical/q_res/chips/chips.prt';

PART_NAME
 R663 'Q_RES_0402LF-499,1%,1/16W,CHIPA':;

SECTION_NUMBER 1
 '@S9S_MB_2U_LIB.S9S_MB_2U(SCH_1):PAGE218_I18@PURE_QUANTA.Q_RES(CHIPS)':
 C_PATH='@s9s_mb_2u_lib.s9s_mb_2u(sch_1):page218_i18@pure_quanta.q_res(chips)',
 P_PATH='@s9s_mb_2u_lib.s9s_mb_2u(sch_1):page230_i18@pure_quanta.q_res(chips)',
 PATH='I18',
 DRAWING='@S9S_MB_2U_LIB.S9S_MB_2U(SCH_1):PAGE218',
 PHYS_PAGE='230',
 XY='(225,4300)',
 ROT='0',
 VER='2',
 PACK_TYPE='0402LF',
 CDS_LIB='pure_quanta',
 CDS_PART_NAME='Q_RES_0402LF-499,1%,1/16W,CHIPA',
 WATTAGE='1/16W',
 TOLERANCE='1%',
 MATERIAL='CHIP',
 VALUE='499',
 PRIM_FILE='./archive_libs/logical/q_res/chips/chips.prt';

PART_NAME
 R664 'Q_RES_0402LF-499,1%,1/16W,CHIPA':;

SECTION_NUMBER 1
 '@S9S_MB_2U_LIB.S9S_MB_2U(SCH_1):PAGE218_I28@PURE_QUANTA.Q_RES(CHIPS)':
 C_PATH='@s9s_mb_2u_lib.s9s_mb_2u(sch_1):page218_i28@pure_quanta.q_res(chips)',
 P_PATH='@s9s_mb_2u_lib.s9s_mb_2u(sch_1):page230_i28@pure_quanta.q_res(chips)',
 PATH='I28',
 DRAWING='@S9S_MB_2U_LIB.S9S_MB_2U(SCH_1):PAGE218',
 PHYS_PAGE='230',
 XY='(475,4300)',
 ROT='0',
 VER='2',
 PACK_TYPE='0402LF',
 CDS_LIB='pure_quanta',
 CDS_PART_NAME='Q_RES_0402LF-499,1%,1/16W,CHIPA',
 WATTAGE='1/16W',
 TOLERANCE='1%',
 MATERIAL='CHIP',
 VALUE='499',
 PRIM_FILE='./archive_libs/logical/q_res/chips/chips.prt';

PART_NAME
 R665 'Q_RES_0402LF-0,5%,1/16W,EMPTY,A':;

SECTION_NUMBER 1
 '@S9S_MB_2U_LIB.S9S_MB_2U(SCH_1):PAGE218_I23@PURE_QUANTA.Q_RES(CHIPS)':
 C_PATH='@s9s_mb_2u_lib.s9s_mb_2u(sch_1):page218_i23@pure_quanta.q_res(chips)',
 P_PATH='@s9s_mb_2u_lib.s9s_mb_2u(sch_1):page230_i23@pure_quanta.q_res(chips)',
 PATH='I23',
 DRAWING='@S9S_MB_2U_LIB.S9S_MB_2U(SCH_1):PAGE218',
 PHYS_PAGE='230',
 XY='(625,1150)',
 ROT='0',
 VER='1',
 PACK_TYPE='0402LF',
 CDS_LIB='pure_quanta',
 CDS_PART_NAME='Q_RES_0402LF-0,5%,1/16W,EMPTY,A',
 WATTAGE='1/16W',
 TOLERANCE='5%',
 MATERIAL='EMPTY',
 VALUE='0',
 PRIM_FILE='./archive_libs/logical/q_res/chips/chips.prt';

PART_NAME
 R666 'Q_RES_0402LF-0,5%,1/16W,EMPTY,A':;

SECTION_NUMBER 1
 '@S9S_MB_2U_LIB.S9S_MB_2U(SCH_1):PAGE218_I22@PURE_QUANTA.Q_RES(CHIPS)':
 C_PATH='@s9s_mb_2u_lib.s9s_mb_2u(sch_1):page218_i22@pure_quanta.q_res(chips)',
 P_PATH='@s9s_mb_2u_lib.s9s_mb_2u(sch_1):page230_i22@pure_quanta.q_res(chips)',
 PATH='I22',
 DRAWING='@S9S_MB_2U_LIB.S9S_MB_2U(SCH_1):PAGE218',
 PHYS_PAGE='230',
 XY='(625,1025)',
 ROT='0',
 VER='1',
 PACK_TYPE='0402LF',
 CDS_LIB='pure_quanta',
 CDS_PART_NAME='Q_RES_0402LF-0,5%,1/16W,EMPTY,A',
 WATTAGE='1/16W',
 TOLERANCE='5%',
 MATERIAL='EMPTY',
 VALUE='0',
 PRIM_FILE='./archive_libs/logical/q_res/chips/chips.prt';

PART_NAME
 R667 'Q_RES_0402LF-0,5%,1/16W,EMPTY,A':;

SECTION_NUMBER 1
 '@S9S_MB_2U_LIB.S9S_MB_2U(SCH_1):PAGE218_I21@PURE_QUANTA.Q_RES(CHIPS)':
 C_PATH='@s9s_mb_2u_lib.s9s_mb_2u(sch_1):page218_i21@pure_quanta.q_res(chips)',
 P_PATH='@s9s_mb_2u_lib.s9s_mb_2u(sch_1):page230_i21@pure_quanta.q_res(chips)',
 PATH='I21',
 DRAWING='@S9S_MB_2U_LIB.S9S_MB_2U(SCH_1):PAGE218',
 PHYS_PAGE='230',
 XY='(625,900)',
 ROT='0',
 VER='1',
 PACK_TYPE='0402LF',
 CDS_LIB='pure_quanta',
 CDS_PART_NAME='Q_RES_0402LF-0,5%,1/16W,EMPTY,A',
 WATTAGE='1/16W',
 TOLERANCE='5%',
 MATERIAL='EMPTY',
 VALUE='0',
 PRIM_FILE='./archive_libs/logical/q_res/chips/chips.prt';

PART_NAME
 R668 'Q_RES_0402LF-0,5%,1/16W,EMPTY,A':;

SECTION_NUMBER 1
 '@S9S_MB_2U_LIB.S9S_MB_2U(SCH_1):PAGE218_I20@PURE_QUANTA.Q_RES(CHIPS)':
 C_PATH='@s9s_mb_2u_lib.s9s_mb_2u(sch_1):page218_i20@pure_quanta.q_res(chips)',
 P_PATH='@s9s_mb_2u_lib.s9s_mb_2u(sch_1):page230_i20@pure_quanta.q_res(chips)',
 PATH='I20',
 DRAWING='@S9S_MB_2U_LIB.S9S_MB_2U(SCH_1):PAGE218',
 PHYS_PAGE='230',
 XY='(625,775)',
 ROT='0',
 VER='1',
 PACK_TYPE='0402LF',
 CDS_LIB='pure_quanta',
 CDS_PART_NAME='Q_RES_0402LF-0,5%,1/16W,EMPTY,A',
 WATTAGE='1/16W',
 TOLERANCE='5%',
 MATERIAL='EMPTY',
 VALUE='0',
 PRIM_FILE='./archive_libs/logical/q_res/chips/chips.prt';

PART_NAME
 R669 'Q_RES_0402LF-499,1%,1/16W,CHIPA':;

SECTION_NUMBER 1
 '@S9S_MB_2U_LIB.S9S_MB_2U(SCH_1):PAGE218_I29@PURE_QUANTA.Q_RES(CHIPS)':
 C_PATH='@s9s_mb_2u_lib.s9s_mb_2u(sch_1):page218_i29@pure_quanta.q_res(chips)',
 P_PATH='@s9s_mb_2u_lib.s9s_mb_2u(sch_1):page230_i29@pure_quanta.q_res(chips)',
 PATH='I29',
 DRAWING='@S9S_MB_2U_LIB.S9S_MB_2U(SCH_1):PAGE218',
 PHYS_PAGE='230',
 XY='(725,4300)',
 ROT='0',
 VER='2',
 PACK_TYPE='0402LF',
 CDS_LIB='pure_quanta',
 CDS_PART_NAME='Q_RES_0402LF-499,1%,1/16W,CHIPA',
 WATTAGE='1/16W',
 TOLERANCE='1%',
 MATERIAL='CHIP',
 VALUE='499',
 PRIM_FILE='./archive_libs/logical/q_res/chips/chips.prt';

PART_NAME
 R670 'Q_RES_0402LF-0,5%,1/16W,CHIP,CA':;

SECTION_NUMBER 1
 '@S9S_MB_2U_LIB.S9S_MB_2U(SCH_1):PAGE218_I32@PURE_QUANTA.Q_RES(CHIPS)':
 C_PATH='@s9s_mb_2u_lib.s9s_mb_2u(sch_1):page218_i32@pure_quanta.q_res(chips)',
 P_PATH='@s9s_mb_2u_lib.s9s_mb_2u(sch_1):page230_i32@pure_quanta.q_res(chips)',
 PATH='I32',
 DRAWING='@S9S_MB_2U_LIB.S9S_MB_2U(SCH_1):PAGE218',
 PHYS_PAGE='230',
 XY='(1125,3975)',
 ROT='0',
 VER='1',
 PACK_TYPE='0402LF',
 LOCATION='R670',
 CDS_LIB='pure_quanta',
 CDS_PART_NAME='Q_RES_0402LF-0,5%,1/16W,CHIP,CA',
 WATTAGE='1/16W',
 TOLERANCE='5%',
 MATERIAL='CHIP',
 VALUE='0',
 PRIM_FILE='./archive_libs/logical/q_res/chips/chips.prt';

PART_NAME
 R671 'Q_RES_0402LF-33.2,1%,1/16W,CHIA':;

SECTION_NUMBER 1
 '@S9S_MB_2U_LIB.S9S_MB_2U(SCH_1):PAGE218_I33@PURE_QUANTA.Q_RES(CHIPS)':
 C_PATH='@s9s_mb_2u_lib.s9s_mb_2u(sch_1):page218_i33@pure_quanta.q_res(chips)',
 P_PATH='@s9s_mb_2u_lib.s9s_mb_2u(sch_1):page230_i33@pure_quanta.q_res(chips)',
 PATH='I33',
 DRAWING='@S9S_MB_2U_LIB.S9S_MB_2U(SCH_1):PAGE218',
 PHYS_PAGE='230',
 XY='(1125,3925)',
 ROT='0',
 VER='1',
 PACK_TYPE='0402LF',
 CDS_LIB='pure_quanta',
 CDS_PART_NAME='Q_RES_0402LF-33.2,1%,1/16W,CHIA',
 WATTAGE='1/16W',
 TOLERANCE='1%',
 MATERIAL='CHIP',
 VALUE='33.2',
 PRIM_FILE='./archive_libs/logical/q_res/chips/chips.prt';

PART_NAME
 R672 'Q_RES_0402LF-0,5%,1/16W,CHIP,CA':;

SECTION_NUMBER 1
 '@S9S_MB_2U_LIB.S9S_MB_2U(SCH_1):PAGE218_I30@PURE_QUANTA.Q_RES(CHIPS)':
 C_PATH='@s9s_mb_2u_lib.s9s_mb_2u(sch_1):page218_i30@pure_quanta.q_res(chips)',
 P_PATH='@s9s_mb_2u_lib.s9s_mb_2u(sch_1):page230_i30@pure_quanta.q_res(chips)',
 PATH='I30',
 DRAWING='@S9S_MB_2U_LIB.S9S_MB_2U(SCH_1):PAGE218',
 PHYS_PAGE='230',
 XY='(1125,3675)',
 ROT='0',
 VER='1',
 PACK_TYPE='0402LF',
 LOCATION='R672',
 CDS_LIB='pure_quanta',
 CDS_PART_NAME='Q_RES_0402LF-0,5%,1/16W,CHIP,CA',
 WATTAGE='1/16W',
 TOLERANCE='5%',
 MATERIAL='CHIP',
 VALUE='0',
 PRIM_FILE='./archive_libs/logical/q_res/chips/chips.prt';

PART_NAME
 R673 'Q_RES_0402LF-33.2,1%,1/16W,CHIA':;

SECTION_NUMBER 1
 '@S9S_MB_2U_LIB.S9S_MB_2U(SCH_1):PAGE218_I31@PURE_QUANTA.Q_RES(CHIPS)':
 C_PATH='@s9s_mb_2u_lib.s9s_mb_2u(sch_1):page218_i31@pure_quanta.q_res(chips)',
 P_PATH='@s9s_mb_2u_lib.s9s_mb_2u(sch_1):page230_i31@pure_quanta.q_res(chips)',
 PATH='I31',
 DRAWING='@S9S_MB_2U_LIB.S9S_MB_2U(SCH_1):PAGE218',
 PHYS_PAGE='230',
 XY='(1125,3625)',
 ROT='0',
 VER='1',
 PACK_TYPE='0402LF',
 CDS_LIB='pure_quanta',
 CDS_PART_NAME='Q_RES_0402LF-33.2,1%,1/16W,CHIA',
 WATTAGE='1/16W',
 TOLERANCE='1%',
 MATERIAL='CHIP',
 VALUE='33.2',
 PRIM_FILE='./archive_libs/logical/q_res/chips/chips.prt';

PART_NAME
 R674 'Q_RES_0402LF-0,5%,1/16W,CHIP,CA':;

SECTION_NUMBER 1
 '@S9S_MB_2U_LIB.S9S_MB_2U(SCH_1):PAGE218_I37@PURE_QUANTA.Q_RES(CHIPS)':
 C_PATH='@s9s_mb_2u_lib.s9s_mb_2u(sch_1):page218_i37@pure_quanta.q_res(chips)',
 P_PATH='@s9s_mb_2u_lib.s9s_mb_2u(sch_1):page230_i37@pure_quanta.q_res(chips)',
 PATH='I37',
 DRAWING='@S9S_MB_2U_LIB.S9S_MB_2U(SCH_1):PAGE218',
 PHYS_PAGE='230',
 XY='(2750,2025)',
 ROT='0',
 VER='1',
 PACK_TYPE='0402LF',
 CDS_LIB='pure_quanta',
 CDS_PART_NAME='Q_RES_0402LF-0,5%,1/16W,CHIP,CA',
 WATTAGE='1/16W',
 TOLERANCE='5%',
 MATERIAL='CHIP',
 VALUE='0',
 PRIM_FILE='./archive_libs/logical/q_res/chips/chips.prt';

PART_NAME
 R675 'Q_RES_0402LF-33.2,1%,1/16W,CHIA':;

SECTION_NUMBER 1
 '@S9S_MB_2U_LIB.S9S_MB_2U(SCH_1):PAGE218_I36@PURE_QUANTA.Q_RES(CHIPS)':
 C_PATH='@s9s_mb_2u_lib.s9s_mb_2u(sch_1):page218_i36@pure_quanta.q_res(chips)',
 P_PATH='@s9s_mb_2u_lib.s9s_mb_2u(sch_1):page230_i36@pure_quanta.q_res(chips)',
 PATH='I36',
 DRAWING='@S9S_MB_2U_LIB.S9S_MB_2U(SCH_1):PAGE218',
 PHYS_PAGE='230',
 XY='(2750,1875)',
 ROT='0',
 VER='1',
 PACK_TYPE='0402LF',
 CDS_LIB='pure_quanta',
 CDS_PART_NAME='Q_RES_0402LF-33.2,1%,1/16W,CHIA',
 WATTAGE='1/16W',
 TOLERANCE='1%',
 MATERIAL='CHIP',
 VALUE='33.2',
 PRIM_FILE='./archive_libs/logical/q_res/chips/chips.prt';

PART_NAME
 R676 'Q_RES_0402LF-0,5%,1/16W,CHIP,CA':;

SECTION_NUMBER 1
 '@S9S_MB_2U_LIB.S9S_MB_2U(SCH_1):PAGE218_I35@PURE_QUANTA.Q_RES(CHIPS)':
 C_PATH='@s9s_mb_2u_lib.s9s_mb_2u(sch_1):page218_i35@pure_quanta.q_res(chips)',
 P_PATH='@s9s_mb_2u_lib.s9s_mb_2u(sch_1):page230_i35@pure_quanta.q_res(chips)',
 PATH='I35',
 DRAWING='@S9S_MB_2U_LIB.S9S_MB_2U(SCH_1):PAGE218',
 PHYS_PAGE='230',
 XY='(2750,1725)',
 ROT='0',
 VER='1',
 PACK_TYPE='0402LF',
 CDS_LIB='pure_quanta',
 CDS_PART_NAME='Q_RES_0402LF-0,5%,1/16W,CHIP,CA',
 WATTAGE='1/16W',
 TOLERANCE='5%',
 MATERIAL='CHIP',
 VALUE='0',
 PRIM_FILE='./archive_libs/logical/q_res/chips/chips.prt';

PART_NAME
 R677 'Q_RES_0402LF-33.2,1%,1/16W,CHIA':;

SECTION_NUMBER 1
 '@S9S_MB_2U_LIB.S9S_MB_2U(SCH_1):PAGE218_I34@PURE_QUANTA.Q_RES(CHIPS)':
 C_PATH='@s9s_mb_2u_lib.s9s_mb_2u(sch_1):page218_i34@pure_quanta.q_res(chips)',
 P_PATH='@s9s_mb_2u_lib.s9s_mb_2u(sch_1):page230_i34@pure_quanta.q_res(chips)',
 PATH='I34',
 DRAWING='@S9S_MB_2U_LIB.S9S_MB_2U(SCH_1):PAGE218',
 PHYS_PAGE='230',
 XY='(2750,1575)',
 ROT='0',
 VER='1',
 PACK_TYPE='0402LF',
 CDS_LIB='pure_quanta',
 CDS_PART_NAME='Q_RES_0402LF-33.2,1%,1/16W,CHIA',
 WATTAGE='1/16W',
 TOLERANCE='1%',
 MATERIAL='CHIP',
 VALUE='33.2',
 PRIM_FILE='./archive_libs/logical/q_res/chips/chips.prt';

PART_NAME
 R678 'Q_RES_0402LF-1K,1%,1/16W,CHIP,A':;

SECTION_NUMBER 1
 '@S9S_MB_2U_LIB.S9S_MB_2U(SCH_1):PAGE217_I13@PURE_QUANTA.Q_RES(CHIPS)':
 C_PATH='@s9s_mb_2u_lib.s9s_mb_2u(sch_1):page217_i13@pure_quanta.q_res(chips)',
 P_PATH='@s9s_mb_2u_lib.s9s_mb_2u(sch_1):page229_i13@pure_quanta.q_res(chips)',
 PATH='I13',
 DRAWING='@S9S_MB_2U_LIB.S9S_MB_2U(SCH_1):PAGE217',
 PHYS_PAGE='229',
 XY='(-3050,1125)',
 ROT='0',
 VER='2',
 PACK_TYPE='0402LF',
 CDS_LIB='pure_quanta',
 CDS_PART_NAME='Q_RES_0402LF-1K,1%,1/16W,CHIP,A',
 WATTAGE='1/16W',
 TOLERANCE='1%',
 MATERIAL='CHIP',
 VALUE='1K',
 PRIM_FILE='./archive_libs/logical/q_res/chips/chips.prt';

PART_NAME
 R679 'Q_RES_0402LF-499,1%,1/16W,CHIPA':;

SECTION_NUMBER 1
 '@S9S_MB_2U_LIB.S9S_MB_2U(SCH_1):PAGE217_I29@PURE_QUANTA.Q_RES(CHIPS)':
 C_PATH='@s9s_mb_2u_lib.s9s_mb_2u(sch_1):page217_i29@pure_quanta.q_res(chips)',
 P_PATH='@s9s_mb_2u_lib.s9s_mb_2u(sch_1):page229_i29@pure_quanta.q_res(chips)',
 PATH='I29',
 DRAWING='@S9S_MB_2U_LIB.S9S_MB_2U(SCH_1):PAGE217',
 PHYS_PAGE='229',
 XY='(-1975,4600)',
 ROT='0',
 VER='2',
 PACK_TYPE='0402LF',
 CDS_LIB='pure_quanta',
 CDS_PART_NAME='Q_RES_0402LF-499,1%,1/16W,CHIPA',
 WATTAGE='1/16W',
 TOLERANCE='1%',
 MATERIAL='CHIP',
 VALUE='499',
 PRIM_FILE='./archive_libs/logical/q_res/chips/chips.prt';

PART_NAME
 R680 'Q_RES_0402LF-499,1%,1/16W,CHIPA':;

SECTION_NUMBER 1
 '@S9S_MB_2U_LIB.S9S_MB_2U(SCH_1):PAGE217_I30@PURE_QUANTA.Q_RES(CHIPS)':
 C_PATH='@s9s_mb_2u_lib.s9s_mb_2u(sch_1):page217_i30@pure_quanta.q_res(chips)',
 P_PATH='@s9s_mb_2u_lib.s9s_mb_2u(sch_1):page229_i30@pure_quanta.q_res(chips)',
 PATH='I30',
 DRAWING='@S9S_MB_2U_LIB.S9S_MB_2U(SCH_1):PAGE217',
 PHYS_PAGE='229',
 XY='(-1725,4600)',
 ROT='0',
 VER='2',
 PACK_TYPE='0402LF',
 CDS_LIB='pure_quanta',
 CDS_PART_NAME='Q_RES_0402LF-499,1%,1/16W,CHIPA',
 WATTAGE='1/16W',
 TOLERANCE='1%',
 MATERIAL='CHIP',
 VALUE='499',
 PRIM_FILE='./archive_libs/logical/q_res/chips/chips.prt';

PART_NAME
 R681 'Q_RES_0402LF-499,1%,1/16W,CHIPA':;

SECTION_NUMBER 1
 '@S9S_MB_2U_LIB.S9S_MB_2U(SCH_1):PAGE217_I32@PURE_QUANTA.Q_RES(CHIPS)':
 C_PATH='@s9s_mb_2u_lib.s9s_mb_2u(sch_1):page217_i32@pure_quanta.q_res(chips)',
 P_PATH='@s9s_mb_2u_lib.s9s_mb_2u(sch_1):page229_i32@pure_quanta.q_res(chips)',
 PATH='I32',
 DRAWING='@S9S_MB_2U_LIB.S9S_MB_2U(SCH_1):PAGE217',
 PHYS_PAGE='229',
 XY='(-1475,4600)',
 ROT='0',
 VER='2',
 PACK_TYPE='0402LF',
 CDS_LIB='pure_quanta',
 CDS_PART_NAME='Q_RES_0402LF-499,1%,1/16W,CHIPA',
 WATTAGE='1/16W',
 TOLERANCE='1%',
 MATERIAL='CHIP',
 VALUE='499',
 PRIM_FILE='./archive_libs/logical/q_res/chips/chips.prt';

PART_NAME
 R682 'Q_RES_0402LF-0,5%,1/16W,EMPTY,A':;

SECTION_NUMBER 1
 '@S9S_MB_2U_LIB.S9S_MB_2U(SCH_1):PAGE217_I20@PURE_QUANTA.Q_RES(CHIPS)':
 C_PATH='@s9s_mb_2u_lib.s9s_mb_2u(sch_1):page217_i20@pure_quanta.q_res(chips)',
 P_PATH='@s9s_mb_2u_lib.s9s_mb_2u(sch_1):page229_i20@pure_quanta.q_res(chips)',
 PATH='I20',
 DRAWING='@S9S_MB_2U_LIB.S9S_MB_2U(SCH_1):PAGE217',
 PHYS_PAGE='229',
 XY='(-1375,1050)',
 ROT='0',
 VER='1',
 PACK_TYPE='0402LF',
 CDS_LIB='pure_quanta',
 CDS_PART_NAME='Q_RES_0402LF-0,5%,1/16W,EMPTY,A',
 WATTAGE='1/16W',
 TOLERANCE='5%',
 MATERIAL='EMPTY',
 VALUE='0',
 PRIM_FILE='./archive_libs/logical/q_res/chips/chips.prt';

PART_NAME
 R683 'Q_RES_0402LF-0,5%,1/16W,EMPTY,A':;

SECTION_NUMBER 1
 '@S9S_MB_2U_LIB.S9S_MB_2U(SCH_1):PAGE217_I18@PURE_QUANTA.Q_RES(CHIPS)':
 C_PATH='@s9s_mb_2u_lib.s9s_mb_2u(sch_1):page217_i18@pure_quanta.q_res(chips)',
 P_PATH='@s9s_mb_2u_lib.s9s_mb_2u(sch_1):page229_i18@pure_quanta.q_res(chips)',
 PATH='I18',
 DRAWING='@S9S_MB_2U_LIB.S9S_MB_2U(SCH_1):PAGE217',
 PHYS_PAGE='229',
 XY='(-1375,925)',
 ROT='0',
 VER='1',
 PACK_TYPE='0402LF',
 CDS_LIB='pure_quanta',
 CDS_PART_NAME='Q_RES_0402LF-0,5%,1/16W,EMPTY,A',
 WATTAGE='1/16W',
 TOLERANCE='5%',
 MATERIAL='EMPTY',
 VALUE='0',
 PRIM_FILE='./archive_libs/logical/q_res/chips/chips.prt';

PART_NAME
 R684 'Q_RES_0402LF-0,5%,1/16W,EMPTY,A':;

SECTION_NUMBER 1
 '@S9S_MB_2U_LIB.S9S_MB_2U(SCH_1):PAGE217_I17@PURE_QUANTA.Q_RES(CHIPS)':
 C_PATH='@s9s_mb_2u_lib.s9s_mb_2u(sch_1):page217_i17@pure_quanta.q_res(chips)',
 P_PATH='@s9s_mb_2u_lib.s9s_mb_2u(sch_1):page229_i17@pure_quanta.q_res(chips)',
 PATH='I17',
 DRAWING='@S9S_MB_2U_LIB.S9S_MB_2U(SCH_1):PAGE217',
 PHYS_PAGE='229',
 XY='(-1375,800)',
 ROT='0',
 VER='1',
 PACK_TYPE='0402LF',
 CDS_LIB='pure_quanta',
 CDS_PART_NAME='Q_RES_0402LF-0,5%,1/16W,EMPTY,A',
 WATTAGE='1/16W',
 TOLERANCE='5%',
 MATERIAL='EMPTY',
 VALUE='0',
 PRIM_FILE='./archive_libs/logical/q_res/chips/chips.prt';

PART_NAME
 R685 'Q_RES_0402LF-0,5%,1/16W,EMPTY,A':;

SECTION_NUMBER 1
 '@S9S_MB_2U_LIB.S9S_MB_2U(SCH_1):PAGE217_I16@PURE_QUANTA.Q_RES(CHIPS)':
 C_PATH='@s9s_mb_2u_lib.s9s_mb_2u(sch_1):page217_i16@pure_quanta.q_res(chips)',
 P_PATH='@s9s_mb_2u_lib.s9s_mb_2u(sch_1):page229_i16@pure_quanta.q_res(chips)',
 PATH='I16',
 DRAWING='@S9S_MB_2U_LIB.S9S_MB_2U(SCH_1):PAGE217',
 PHYS_PAGE='229',
 XY='(-1375,675)',
 ROT='0',
 VER='1',
 PACK_TYPE='0402LF',
 CDS_LIB='pure_quanta',
 CDS_PART_NAME='Q_RES_0402LF-0,5%,1/16W,EMPTY,A',
 WATTAGE='1/16W',
 TOLERANCE='5%',
 MATERIAL='EMPTY',
 VALUE='0',
 PRIM_FILE='./archive_libs/logical/q_res/chips/chips.prt';

PART_NAME
 R686 'Q_RES_0402LF-499,1%,1/16W,CHIPA':;

SECTION_NUMBER 1
 '@S9S_MB_2U_LIB.S9S_MB_2U(SCH_1):PAGE217_I33@PURE_QUANTA.Q_RES(CHIPS)':
 C_PATH='@s9s_mb_2u_lib.s9s_mb_2u(sch_1):page217_i33@pure_quanta.q_res(chips)',
 P_PATH='@s9s_mb_2u_lib.s9s_mb_2u(sch_1):page229_i33@pure_quanta.q_res(chips)',
 PATH='I33',
 DRAWING='@S9S_MB_2U_LIB.S9S_MB_2U(SCH_1):PAGE217',
 PHYS_PAGE='229',
 XY='(-1225,4600)',
 ROT='0',
 VER='2',
 PACK_TYPE='0402LF',
 CDS_LIB='pure_quanta',
 CDS_PART_NAME='Q_RES_0402LF-499,1%,1/16W,CHIPA',
 WATTAGE='1/16W',
 TOLERANCE='1%',
 MATERIAL='CHIP',
 VALUE='499',
 PRIM_FILE='./archive_libs/logical/q_res/chips/chips.prt';

PART_NAME
 R687 'Q_RES_0402LF-0,5%,1/16W,CHIP,CA':;

SECTION_NUMBER 1
 '@S9S_MB_2U_LIB.S9S_MB_2U(SCH_1):PAGE217_I34@PURE_QUANTA.Q_RES(CHIPS)':
 C_PATH='@s9s_mb_2u_lib.s9s_mb_2u(sch_1):page217_i34@pure_quanta.q_res(chips)',
 P_PATH='@s9s_mb_2u_lib.s9s_mb_2u(sch_1):page229_i34@pure_quanta.q_res(chips)',
 PATH='I34',
 DRAWING='@S9S_MB_2U_LIB.S9S_MB_2U(SCH_1):PAGE217',
 PHYS_PAGE='229',
 XY='(-875,4275)',
 ROT='0',
 VER='1',
 PACK_TYPE='0402LF',
 LOCATION='R687',
 CDS_LIB='pure_quanta',
 CDS_PART_NAME='Q_RES_0402LF-0,5%,1/16W,CHIP,CA',
 WATTAGE='1/16W',
 TOLERANCE='5%',
 MATERIAL='CHIP',
 VALUE='0',
 PRIM_FILE='./archive_libs/logical/q_res/chips/chips.prt';

PART_NAME
 R688 'Q_RES_0402LF-33.2,1%,1/16W,CHIA':;

SECTION_NUMBER 1
 '@S9S_MB_2U_LIB.S9S_MB_2U(SCH_1):PAGE217_I35@PURE_QUANTA.Q_RES(CHIPS)':
 C_PATH='@s9s_mb_2u_lib.s9s_mb_2u(sch_1):page217_i35@pure_quanta.q_res(chips)',
 P_PATH='@s9s_mb_2u_lib.s9s_mb_2u(sch_1):page229_i35@pure_quanta.q_res(chips)',
 PATH='I35',
 DRAWING='@S9S_MB_2U_LIB.S9S_MB_2U(SCH_1):PAGE217',
 PHYS_PAGE='229',
 XY='(-875,4225)',
 ROT='0',
 VER='1',
 PACK_TYPE='0402LF',
 CDS_LIB='pure_quanta',
 CDS_PART_NAME='Q_RES_0402LF-33.2,1%,1/16W,CHIA',
 WATTAGE='1/16W',
 TOLERANCE='1%',
 MATERIAL='CHIP',
 VALUE='33.2',
 PRIM_FILE='./archive_libs/logical/q_res/chips/chips.prt';

PART_NAME
 R689 'Q_RES_0402LF-0,5%,1/16W,CHIP,CA':;

SECTION_NUMBER 1
 '@S9S_MB_2U_LIB.S9S_MB_2U(SCH_1):PAGE217_I25@PURE_QUANTA.Q_RES(CHIPS)':
 C_PATH='@s9s_mb_2u_lib.s9s_mb_2u(sch_1):page217_i25@pure_quanta.q_res(chips)',
 P_PATH='@s9s_mb_2u_lib.s9s_mb_2u(sch_1):page229_i25@pure_quanta.q_res(chips)',
 PATH='I25',
 DRAWING='@S9S_MB_2U_LIB.S9S_MB_2U(SCH_1):PAGE217',
 PHYS_PAGE='229',
 XY='(-875,3975)',
 ROT='0',
 VER='1',
 PACK_TYPE='0402LF',
 LOCATION='R689',
 CDS_LIB='pure_quanta',
 CDS_PART_NAME='Q_RES_0402LF-0,5%,1/16W,CHIP,CA',
 WATTAGE='1/16W',
 TOLERANCE='5%',
 MATERIAL='CHIP',
 VALUE='0',
 PRIM_FILE='./archive_libs/logical/q_res/chips/chips.prt';

PART_NAME
 R690 'Q_RES_0402LF-33.2,1%,1/16W,CHIA':;

SECTION_NUMBER 1
 '@S9S_MB_2U_LIB.S9S_MB_2U(SCH_1):PAGE217_I26@PURE_QUANTA.Q_RES(CHIPS)':
 C_PATH='@s9s_mb_2u_lib.s9s_mb_2u(sch_1):page217_i26@pure_quanta.q_res(chips)',
 P_PATH='@s9s_mb_2u_lib.s9s_mb_2u(sch_1):page229_i26@pure_quanta.q_res(chips)',
 PATH='I26',
 DRAWING='@S9S_MB_2U_LIB.S9S_MB_2U(SCH_1):PAGE217',
 PHYS_PAGE='229',
 XY='(-875,3925)',
 ROT='0',
 VER='1',
 PACK_TYPE='0402LF',
 CDS_LIB='pure_quanta',
 CDS_PART_NAME='Q_RES_0402LF-33.2,1%,1/16W,CHIA',
 WATTAGE='1/16W',
 TOLERANCE='1%',
 MATERIAL='CHIP',
 VALUE='33.2',
 PRIM_FILE='./archive_libs/logical/q_res/chips/chips.prt';

PART_NAME
 R691 'Q_RES_0402LF-0,5%,1/16W,CHIP,CA':;

SECTION_NUMBER 1
 '@S9S_MB_2U_LIB.S9S_MB_2U(SCH_1):PAGE217_I39@PURE_QUANTA.Q_RES(CHIPS)':
 C_PATH='@s9s_mb_2u_lib.s9s_mb_2u(sch_1):page217_i39@pure_quanta.q_res(chips)',
 P_PATH='@s9s_mb_2u_lib.s9s_mb_2u(sch_1):page229_i39@pure_quanta.q_res(chips)',
 PATH='I39',
 DRAWING='@S9S_MB_2U_LIB.S9S_MB_2U(SCH_1):PAGE217',
 PHYS_PAGE='229',
 XY='(750,1925)',
 ROT='0',
 VER='1',
 PACK_TYPE='0402LF',
 CDS_LIB='pure_quanta',
 CDS_PART_NAME='Q_RES_0402LF-0,5%,1/16W,CHIP,CA',
 WATTAGE='1/16W',
 TOLERANCE='5%',
 MATERIAL='CHIP',
 VALUE='0',
 PRIM_FILE='./archive_libs/logical/q_res/chips/chips.prt';

PART_NAME
 R692 'Q_RES_0402LF-33.2,1%,1/16W,CHIA':;

SECTION_NUMBER 1
 '@S9S_MB_2U_LIB.S9S_MB_2U(SCH_1):PAGE217_I40@PURE_QUANTA.Q_RES(CHIPS)':
 C_PATH='@s9s_mb_2u_lib.s9s_mb_2u(sch_1):page217_i40@pure_quanta.q_res(chips)',
 P_PATH='@s9s_mb_2u_lib.s9s_mb_2u(sch_1):page229_i40@pure_quanta.q_res(chips)',
 PATH='I40',
 DRAWING='@S9S_MB_2U_LIB.S9S_MB_2U(SCH_1):PAGE217',
 PHYS_PAGE='229',
 XY='(750,1775)',
 ROT='0',
 VER='1',
 PACK_TYPE='0402LF',
 CDS_LIB='pure_quanta',
 CDS_PART_NAME='Q_RES_0402LF-33.2,1%,1/16W,CHIA',
 WATTAGE='1/16W',
 TOLERANCE='1%',
 MATERIAL='CHIP',
 VALUE='33.2',
 PRIM_FILE='./archive_libs/logical/q_res/chips/chips.prt';

PART_NAME
 R693 'Q_RES_0402LF-0,5%,1/16W,CHIP,CA':;

SECTION_NUMBER 1
 '@S9S_MB_2U_LIB.S9S_MB_2U(SCH_1):PAGE217_I38@PURE_QUANTA.Q_RES(CHIPS)':
 C_PATH='@s9s_mb_2u_lib.s9s_mb_2u(sch_1):page217_i38@pure_quanta.q_res(chips)',
 P_PATH='@s9s_mb_2u_lib.s9s_mb_2u(sch_1):page229_i38@pure_quanta.q_res(chips)',
 PATH='I38',
 DRAWING='@S9S_MB_2U_LIB.S9S_MB_2U(SCH_1):PAGE217',
 PHYS_PAGE='229',
 XY='(750,1625)',
 ROT='0',
 VER='1',
 PACK_TYPE='0402LF',
 CDS_LIB='pure_quanta',
 CDS_PART_NAME='Q_RES_0402LF-0,5%,1/16W,CHIP,CA',
 WATTAGE='1/16W',
 TOLERANCE='5%',
 MATERIAL='CHIP',
 VALUE='0',
 PRIM_FILE='./archive_libs/logical/q_res/chips/chips.prt';

PART_NAME
 R694 'Q_RES_0402LF-33.2,1%,1/16W,CHIA':;

SECTION_NUMBER 1
 '@S9S_MB_2U_LIB.S9S_MB_2U(SCH_1):PAGE217_I37@PURE_QUANTA.Q_RES(CHIPS)':
 C_PATH='@s9s_mb_2u_lib.s9s_mb_2u(sch_1):page217_i37@pure_quanta.q_res(chips)',
 P_PATH='@s9s_mb_2u_lib.s9s_mb_2u(sch_1):page229_i37@pure_quanta.q_res(chips)',
 PATH='I37',
 DRAWING='@S9S_MB_2U_LIB.S9S_MB_2U(SCH_1):PAGE217',
 PHYS_PAGE='229',
 XY='(750,1475)',
 ROT='0',
 VER='1',
 PACK_TYPE='0402LF',
 CDS_LIB='pure_quanta',
 CDS_PART_NAME='Q_RES_0402LF-33.2,1%,1/16W,CHIA',
 WATTAGE='1/16W',
 TOLERANCE='1%',
 MATERIAL='CHIP',
 VALUE='33.2',
 PRIM_FILE='./archive_libs/logical/q_res/chips/chips.prt';

PART_NAME
 R696 'Q_RES_0402LF-4.75K,1%,1/16W,CHA':;

SECTION_NUMBER 1
 '@S9S_MB_2U_LIB.S9S_MB_2U(SCH_1):PAGE174_I63@PURE_QUANTA.Q_RES(CHIPS)':
 C_PATH='@s9s_mb_2u_lib.s9s_mb_2u(sch_1):page174_i63@pure_quanta.q_res(chips)',
 P_PATH='@s9s_mb_2u_lib.s9s_mb_2u(sch_1):page182_i63@pure_quanta.q_res(chips)',
 PATH='I63',
 DRAWING='@S9S_MB_2U_LIB.S9S_MB_2U(SCH_1):PAGE174',
 PHYS_PAGE='182',
 XY='(-250,3375)',
 ROT='2',
 VER='2',
 PACK_TYPE='0402LF',
 CDS_LIB='pure_quanta',
 CDS_PART_NAME='Q_RES_0402LF-4.75K,1%,1/16W,CHA',
 WATTAGE='1/16W',
 TOLERANCE='1%',
 MATERIAL='CHIP',
 VALUE='4.75K',
 PRIM_FILE='./archive_libs/logical/q_res/chips/chips.prt';

PART_NAME
 R697 'Q_RES_0402LF-33.2,1%,1/16W,CHIA':;

SECTION_NUMBER 1
 '@S9S_MB_2U_LIB.S9S_MB_2U(SCH_1):PAGE174_I66@PURE_QUANTA.Q_RES(CHIPS)':
 C_PATH='@s9s_mb_2u_lib.s9s_mb_2u(sch_1):page174_i66@pure_quanta.q_res(chips)',
 P_PATH='@s9s_mb_2u_lib.s9s_mb_2u(sch_1):page182_i66@pure_quanta.q_res(chips)',
 PATH='I66',
 DRAWING='@S9S_MB_2U_LIB.S9S_MB_2U(SCH_1):PAGE174',
 PHYS_PAGE='182',
 XY='(-150,375)',
 ROT='0',
 VER='1',
 PACK_TYPE='0402LF',
 CDS_LIB='pure_quanta',
 CDS_PART_NAME='Q_RES_0402LF-33.2,1%,1/16W,CHIA',
 WATTAGE='1/16W',
 TOLERANCE='1%',
 MATERIAL='CHIP',
 VALUE='33.2',
 PRIM_FILE='./archive_libs/logical/q_res/chips/chips.prt';

PART_NAME
 R698 'Q_RES_0402LF-49.9,1%,1/16W,CHIA':;

SECTION_NUMBER 1
 '@S9S_MB_2U_LIB.S9S_MB_2U(SCH_1):PAGE193_I32@PURE_QUANTA.Q_RES(CHIPS)':
 C_PATH='@s9s_mb_2u_lib.s9s_mb_2u(sch_1):page193_i32@pure_quanta.q_res(chips)',
 P_PATH='@s9s_mb_2u_lib.s9s_mb_2u(sch_1):page205_i32@pure_quanta.q_res(chips)',
 PATH='I32',
 DRAWING='@S9S_MB_2U_LIB.S9S_MB_2U(SCH_1):PAGE193',
 PHYS_PAGE='205',
 XY='(-5725,-2275)',
 ROT='0',
 VER='1',
 PACK_TYPE='0402LF',
 CDS_LIB='pure_quanta',
 CDS_PART_NAME='Q_RES_0402LF-49.9,1%,1/16W,CHIA',
 WATTAGE='1/16W',
 TOLERANCE='1%',
 MATERIAL='CHIP',
 VALUE='49.9',
 PRIM_FILE='./archive_libs/logical/q_res/chips/chips.prt';

PART_NAME
 R699 'Q_RES_0402LF-33.2,1%,1/16W,CHIA':;

SECTION_NUMBER 1
 '@S9S_MB_2U_LIB.S9S_MB_2U(SCH_1):PAGE175_I102@PURE_QUANTA.Q_RES(CHIPS)':
 C_PATH='@s9s_mb_2u_lib.s9s_mb_2u(sch_1):page175_i102@pure_quanta.q_res(chips)',
 P_PATH='@s9s_mb_2u_lib.s9s_mb_2u(sch_1):page183_i102@pure_quanta.q_res(chips)',
 PATH='I102',
 DRAWING='@S9S_MB_2U_LIB.S9S_MB_2U(SCH_1):PAGE175',
 PHYS_PAGE='183',
 XY='(2950,900)',
 ROT='0',
 VER='1',
 PACK_TYPE='0402LF',
 CDS_LIB='pure_quanta',
 CDS_PART_NAME='Q_RES_0402LF-33.2,1%,1/16W,CHIA',
 WATTAGE='1/16W',
 TOLERANCE='1%',
 MATERIAL='CHIP',
 VALUE='33.2',
 PRIM_FILE='./archive_libs/logical/q_res/chips/chips.prt';

PART_NAME
 R700 'Q_RES_0402LF-0,5%,1/16W,CHIP,CA':;

SECTION_NUMBER 1
 '@S9S_MB_2U_LIB.S9S_MB_2U(SCH_1):PAGE312_I169@PURE_QUANTA.Q_RES(CHIPS)':
 C_PATH='@s9s_mb_2u_lib.s9s_mb_2u(sch_1):page312_i169@pure_quanta.q_res(chips)',
 P_PATH='@s9s_mb_2u_lib.s9s_mb_2u(sch_1):page215_i169@pure_quanta.q_res(chips)',
 PATH='I169',
 DRAWING='@S9S_MB_2U_LIB.S9S_MB_2U(SCH_1):PAGE312',
 PHYS_PAGE='215',
 XY='(-575,-850)',
 ROT='0',
 VER='1',
 PACK_TYPE='0402LF',
 CDS_LIB='pure_quanta',
 CDS_PART_NAME='Q_RES_0402LF-0,5%,1/16W,CHIP,CA',
 WATTAGE='1/16W',
 TOLERANCE='5%',
 MATERIAL='CHIP',
 VALUE='0',
 PRIM_FILE='./archive_libs/logical/q_res/chips/chips.prt';

PART_NAME
 R701 'Q_RES_0402LF-10K,1%,1/16W,EMPTA':;

SECTION_NUMBER 1
 '@S9S_MB_2U_LIB.S9S_MB_2U(SCH_1):PAGE130_I63@PURE_QUANTA.Q_RES(CHIPS)':
 C_PATH='@s9s_mb_2u_lib.s9s_mb_2u(sch_1):page130_i63@pure_quanta.q_res(chips)',
 P_PATH='@s9s_mb_2u_lib.s9s_mb_2u(sch_1):page130_i63@pure_quanta.q_res(chips)',
 PATH='I63',
 DRAWING='@S9S_MB_2U_LIB.S9S_MB_2U(SCH_1):PAGE130',
 PHYS_PAGE='130',
 XY='(-7625,2400)',
 ROT='0',
 VER='2',
 PACK_TYPE='0402LF',
 CDS_LIB='pure_quanta',
 CDS_PART_NAME='Q_RES_0402LF-10K,1%,1/16W,EMPTA',
 WATTAGE='1/16W',
 TOLERANCE='1%',
 MATERIAL='EMPTY',
 VALUE='10K',
 PRIM_FILE='./archive_libs/logical/q_res/chips/chips.prt';

PART_NAME
 R702 'Q_RES_0402LF-10K,1%,1/16W,EMPTA':;

SECTION_NUMBER 1
 '@S9S_MB_2U_LIB.S9S_MB_2U(SCH_1):PAGE130_I76@PURE_QUANTA.Q_RES(CHIPS)':
 C_PATH='@s9s_mb_2u_lib.s9s_mb_2u(sch_1):page130_i76@pure_quanta.q_res(chips)',
 P_PATH='@s9s_mb_2u_lib.s9s_mb_2u(sch_1):page130_i76@pure_quanta.q_res(chips)',
 PATH='I76',
 DRAWING='@S9S_MB_2U_LIB.S9S_MB_2U(SCH_1):PAGE130',
 PHYS_PAGE='130',
 XY='(-7625,-650)',
 ROT='0',
 VER='2',
 PACK_TYPE='0402LF',
 CDS_LIB='pure_quanta',
 CDS_PART_NAME='Q_RES_0402LF-10K,1%,1/16W,EMPTA',
 WATTAGE='1/16W',
 TOLERANCE='1%',
 MATERIAL='EMPTY',
 VALUE='10K',
 PRIM_FILE='./archive_libs/logical/q_res/chips/chips.prt';

PART_NAME
 R703 'Q_RES_0402LF-10K,1%,1/16W,EMPTA':;

SECTION_NUMBER 1
 '@S9S_MB_2U_LIB.S9S_MB_2U(SCH_1):PAGE130_I79@PURE_QUANTA.Q_RES(CHIPS)':
 C_PATH='@s9s_mb_2u_lib.s9s_mb_2u(sch_1):page130_i79@pure_quanta.q_res(chips)',
 P_PATH='@s9s_mb_2u_lib.s9s_mb_2u(sch_1):page130_i79@pure_quanta.q_res(chips)',
 PATH='I79',
 DRAWING='@S9S_MB_2U_LIB.S9S_MB_2U(SCH_1):PAGE130',
 PHYS_PAGE='130',
 XY='(-7600,3900)',
 ROT='0',
 VER='2',
 PACK_TYPE='0402LF',
 CDS_LIB='pure_quanta',
 CDS_PART_NAME='Q_RES_0402LF-10K,1%,1/16W,EMPTA',
 WATTAGE='1/16W',
 TOLERANCE='1%',
 MATERIAL='EMPTY',
 VALUE='10K',
 PRIM_FILE='./archive_libs/logical/q_res/chips/chips.prt';

PART_NAME
 R704 'Q_RES_0402LF-10K,1%,1/16W,EMPTA':;

SECTION_NUMBER 1
 '@S9S_MB_2U_LIB.S9S_MB_2U(SCH_1):PAGE130_I75@PURE_QUANTA.Q_RES(CHIPS)':
 C_PATH='@s9s_mb_2u_lib.s9s_mb_2u(sch_1):page130_i75@pure_quanta.q_res(chips)',
 P_PATH='@s9s_mb_2u_lib.s9s_mb_2u(sch_1):page130_i75@pure_quanta.q_res(chips)',
 PATH='I75',
 DRAWING='@S9S_MB_2U_LIB.S9S_MB_2U(SCH_1):PAGE130',
 PHYS_PAGE='130',
 XY='(-7600,875)',
 ROT='0',
 VER='2',
 PACK_TYPE='0402LF',
 CDS_LIB='pure_quanta',
 CDS_PART_NAME='Q_RES_0402LF-10K,1%,1/16W,EMPTA',
 WATTAGE='1/16W',
 TOLERANCE='1%',
 MATERIAL='EMPTY',
 VALUE='10K',
 PRIM_FILE='./archive_libs/logical/q_res/chips/chips.prt';

PART_NAME
 R705 'Q_RES_0402LF-10K,1%,1/16W,EMPTA':;

SECTION_NUMBER 1
 '@S9S_MB_2U_LIB.S9S_MB_2U(SCH_1):PAGE129_I112@PURE_QUANTA.Q_RES(CHIPS)':
 C_PATH='@s9s_mb_2u_lib.s9s_mb_2u(sch_1):page129_i112@pure_quanta.q_res(chips)',
 P_PATH='@s9s_mb_2u_lib.s9s_mb_2u(sch_1):page129_i112@pure_quanta.q_res(chips)',
 PATH='I112',
 DRAWING='@S9S_MB_2U_LIB.S9S_MB_2U(SCH_1):PAGE129',
 PHYS_PAGE='129',
 XY='(-7350,600)',
 ROT='0',
 VER='2',
 PACK_TYPE='0402LF',
 CDS_LIB='pure_quanta',
 CDS_PART_NAME='Q_RES_0402LF-10K,1%,1/16W,EMPTA',
 WATTAGE='1/16W',
 TOLERANCE='1%',
 MATERIAL='EMPTY',
 VALUE='10K',
 PRIM_FILE='./archive_libs/logical/q_res/chips/chips.prt';

PART_NAME
 R706 'Q_RES_0402LF-10K,1%,1/16W,EMPTA':;

SECTION_NUMBER 1
 '@S9S_MB_2U_LIB.S9S_MB_2U(SCH_1):PAGE129_I103@PURE_QUANTA.Q_RES(CHIPS)':
 C_PATH='@s9s_mb_2u_lib.s9s_mb_2u(sch_1):page129_i103@pure_quanta.q_res(chips)',
 P_PATH='@s9s_mb_2u_lib.s9s_mb_2u(sch_1):page129_i103@pure_quanta.q_res(chips)',
 PATH='I103',
 DRAWING='@S9S_MB_2U_LIB.S9S_MB_2U(SCH_1):PAGE129',
 PHYS_PAGE='129',
 XY='(-7350,5150)',
 ROT='0',
 VER='2',
 PACK_TYPE='0402LF',
 CDS_LIB='pure_quanta',
 CDS_PART_NAME='Q_RES_0402LF-10K,1%,1/16W,EMPTA',
 WATTAGE='1/16W',
 TOLERANCE='1%',
 MATERIAL='EMPTY',
 VALUE='10K',
 PRIM_FILE='./archive_libs/logical/q_res/chips/chips.prt';

PART_NAME
 R707 'Q_RES_0402LF-10K,1%,1/16W,EMPTA':;

SECTION_NUMBER 1
 '@S9S_MB_2U_LIB.S9S_MB_2U(SCH_1):PAGE129_I106@PURE_QUANTA.Q_RES(CHIPS)':
 C_PATH='@s9s_mb_2u_lib.s9s_mb_2u(sch_1):page129_i106@pure_quanta.q_res(chips)',
 P_PATH='@s9s_mb_2u_lib.s9s_mb_2u(sch_1):page129_i106@pure_quanta.q_res(chips)',
 PATH='I106',
 DRAWING='@S9S_MB_2U_LIB.S9S_MB_2U(SCH_1):PAGE129',
 PHYS_PAGE='129',
 XY='(-7350,3625)',
 ROT='0',
 VER='2',
 PACK_TYPE='0402LF',
 CDS_LIB='pure_quanta',
 CDS_PART_NAME='Q_RES_0402LF-10K,1%,1/16W,EMPTA',
 WATTAGE='1/16W',
 TOLERANCE='1%',
 MATERIAL='EMPTY',
 VALUE='10K',
 PRIM_FILE='./archive_libs/logical/q_res/chips/chips.prt';

PART_NAME
 R708 'Q_RES_0402LF-10K,1%,1/16W,EMPTA':;

SECTION_NUMBER 1
 '@S9S_MB_2U_LIB.S9S_MB_2U(SCH_1):PAGE129_I109@PURE_QUANTA.Q_RES(CHIPS)':
 C_PATH='@s9s_mb_2u_lib.s9s_mb_2u(sch_1):page129_i109@pure_quanta.q_res(chips)',
 P_PATH='@s9s_mb_2u_lib.s9s_mb_2u(sch_1):page129_i109@pure_quanta.q_res(chips)',
 PATH='I109',
 DRAWING='@S9S_MB_2U_LIB.S9S_MB_2U(SCH_1):PAGE129',
 PHYS_PAGE='129',
 XY='(-7350,2125)',
 ROT='0',
 VER='2',
 PACK_TYPE='0402LF',
 CDS_LIB='pure_quanta',
 CDS_PART_NAME='Q_RES_0402LF-10K,1%,1/16W,EMPTA',
 WATTAGE='1/16W',
 TOLERANCE='1%',
 MATERIAL='EMPTY',
 VALUE='10K',
 PRIM_FILE='./archive_libs/logical/q_res/chips/chips.prt';

PART_NAME
 R710 'Q_RES_0402LF-1K,1%,1/16W,CHIP,A':;

SECTION_NUMBER 1
 '@S9S_MB_2U_LIB.S9S_MB_2U(SCH_1):PAGE231_I57@PURE_QUANTA.Q_RES(CHIPS)':
 C_PATH='@s9s_mb_2u_lib.s9s_mb_2u(sch_1):page231_i57@pure_quanta.q_res(chips)',
 P_PATH='@s9s_mb_2u_lib.s9s_mb_2u(sch_1):page243_i57@pure_quanta.q_res(chips)',
 PATH='I57',
 DRAWING='@S9S_MB_2U_LIB.S9S_MB_2U(SCH_1):PAGE231',
 PHYS_PAGE='243',
 XY='(-975,1950)',
 ROT='0',
 VER='2',
 PACK_TYPE='0402LF',
 CDS_LIB='pure_quanta',
 CDS_PART_NAME='Q_RES_0402LF-1K,1%,1/16W,CHIP,A',
 WATTAGE='1/16W',
 TOLERANCE='1%',
 MATERIAL='CHIP',
 VALUE='1K',
 PRIM_FILE='./archive_libs/logical/q_res/chips/chips.prt';

PART_NAME
 R713 'Q_RES_0402LF-10K,1%,1/16W,EMPTA':;

SECTION_NUMBER 1
 '@S9S_MB_2U_LIB.S9S_MB_2U(SCH_1):PAGE231_I47@PURE_QUANTA.Q_RES(CHIPS)':
 C_PATH='@s9s_mb_2u_lib.s9s_mb_2u(sch_1):page231_i47@pure_quanta.q_res(chips)',
 P_PATH='@s9s_mb_2u_lib.s9s_mb_2u(sch_1):page243_i47@pure_quanta.q_res(chips)',
 PATH='I47',
 DRAWING='@S9S_MB_2U_LIB.S9S_MB_2U(SCH_1):PAGE231',
 PHYS_PAGE='243',
 XY='(1850,2550)',
 ROT='0',
 VER='2',
 PACK_TYPE='0402LF',
 CDS_LIB='pure_quanta',
 CDS_PART_NAME='Q_RES_0402LF-10K,1%,1/16W,EMPTA',
 WATTAGE='1/16W',
 TOLERANCE='1%',
 MATERIAL='EMPTY',
 VALUE='10K',
 PRIM_FILE='./archive_libs/logical/q_res/chips/chips.prt';

PART_NAME
 R714 'Q_RES_0402LF-1K,1%,1/16W,CHIP,A':;

SECTION_NUMBER 1
 '@S9S_MB_2U_LIB.S9S_MB_2U(SCH_1):PAGE231_I52@PURE_QUANTA.Q_RES(CHIPS)':
 C_PATH='@s9s_mb_2u_lib.s9s_mb_2u(sch_1):page231_i52@pure_quanta.q_res(chips)',
 P_PATH='@s9s_mb_2u_lib.s9s_mb_2u(sch_1):page243_i52@pure_quanta.q_res(chips)',
 PATH='I52',
 DRAWING='@S9S_MB_2U_LIB.S9S_MB_2U(SCH_1):PAGE231',
 PHYS_PAGE='243',
 XY='(1850,2000)',
 ROT='0',
 VER='2',
 PACK_TYPE='0402LF',
 CDS_LIB='pure_quanta',
 CDS_PART_NAME='Q_RES_0402LF-1K,1%,1/16W,CHIP,A',
 WATTAGE='1/16W',
 TOLERANCE='1%',
 MATERIAL='CHIP',
 VALUE='1K',
 PRIM_FILE='./archive_libs/logical/q_res/chips/chips.prt';

PART_NAME
 R717 'Q_RES_0402LF-10K,1%,1/16W,EMPTA':;

SECTION_NUMBER 1
 '@S9S_MB_2U_LIB.S9S_MB_2U(SCH_1):PAGE231_I45@PURE_QUANTA.Q_RES(CHIPS)':
 C_PATH='@s9s_mb_2u_lib.s9s_mb_2u(sch_1):page231_i45@pure_quanta.q_res(chips)',
 P_PATH='@s9s_mb_2u_lib.s9s_mb_2u(sch_1):page243_i45@pure_quanta.q_res(chips)',
 PATH='I45',
 DRAWING='@S9S_MB_2U_LIB.S9S_MB_2U(SCH_1):PAGE231',
 PHYS_PAGE='243',
 XY='(2125,2550)',
 ROT='0',
 VER='2',
 PACK_TYPE='0402LF',
 CDS_LIB='pure_quanta',
 CDS_PART_NAME='Q_RES_0402LF-10K,1%,1/16W,EMPTA',
 WATTAGE='1/16W',
 TOLERANCE='1%',
 MATERIAL='EMPTY',
 VALUE='10K',
 PRIM_FILE='./archive_libs/logical/q_res/chips/chips.prt';

PART_NAME
 R718 'Q_RES_0402LF-1K,1%,1/16W,CHIP,A':;

SECTION_NUMBER 1
 '@S9S_MB_2U_LIB.S9S_MB_2U(SCH_1):PAGE231_I50@PURE_QUANTA.Q_RES(CHIPS)':
 C_PATH='@s9s_mb_2u_lib.s9s_mb_2u(sch_1):page231_i50@pure_quanta.q_res(chips)',
 P_PATH='@s9s_mb_2u_lib.s9s_mb_2u(sch_1):page243_i50@pure_quanta.q_res(chips)',
 PATH='I50',
 DRAWING='@S9S_MB_2U_LIB.S9S_MB_2U(SCH_1):PAGE231',
 PHYS_PAGE='243',
 XY='(2125,2000)',
 ROT='0',
 VER='2',
 PACK_TYPE='0402LF',
 CDS_LIB='pure_quanta',
 CDS_PART_NAME='Q_RES_0402LF-1K,1%,1/16W,CHIP,A',
 WATTAGE='1/16W',
 TOLERANCE='1%',
 MATERIAL='CHIP',
 VALUE='1K',
 PRIM_FILE='./archive_libs/logical/q_res/chips/chips.prt';

PART_NAME
 R721 'Q_RES_0402LF-10K,1%,1/16W,CHIPA':;

SECTION_NUMBER 1
 '@S9S_MB_2U_LIB.S9S_MB_2U(SCH_1):PAGE231_I62@PURE_QUANTA.Q_RES(CHIPS)':
 C_PATH='@s9s_mb_2u_lib.s9s_mb_2u(sch_1):page231_i62@pure_quanta.q_res(chips)',
 P_PATH='@s9s_mb_2u_lib.s9s_mb_2u(sch_1):page243_i62@pure_quanta.q_res(chips)',
 PATH='I62',
 DRAWING='@S9S_MB_2U_LIB.S9S_MB_2U(SCH_1):PAGE231',
 PHYS_PAGE='243',
 XY='(2400,2550)',
 ROT='0',
 VER='2',
 PACK_TYPE='0402LF',
 CDS_LIB='pure_quanta',
 CDS_PART_NAME='Q_RES_0402LF-10K,1%,1/16W,CHIPA',
 WATTAGE='1/16W',
 TOLERANCE='1%',
 MATERIAL='CHIP',
 VALUE='10K',
 PRIM_FILE='./archive_libs/logical/q_res/chips/chips.prt';

PART_NAME
 R722 'Q_RES_0402LF-1K,1%,1/16W,EMPTYA':;

SECTION_NUMBER 1
 '@S9S_MB_2U_LIB.S9S_MB_2U(SCH_1):PAGE231_I61@PURE_QUANTA.Q_RES(CHIPS)':
 C_PATH='@s9s_mb_2u_lib.s9s_mb_2u(sch_1):page231_i61@pure_quanta.q_res(chips)',
 P_PATH='@s9s_mb_2u_lib.s9s_mb_2u(sch_1):page243_i61@pure_quanta.q_res(chips)',
 PATH='I61',
 DRAWING='@S9S_MB_2U_LIB.S9S_MB_2U(SCH_1):PAGE231',
 PHYS_PAGE='243',
 XY='(2400,2000)',
 ROT='0',
 VER='2',
 PACK_TYPE='0402LF',
 CDS_LIB='pure_quanta',
 CDS_PART_NAME='Q_RES_0402LF-1K,1%,1/16W,EMPTYA',
 WATTAGE='1/16W',
 TOLERANCE='1%',
 MATERIAL='EMPTY',
 VALUE='1K',
 PRIM_FILE='./archive_libs/logical/q_res/chips/chips.prt';

PART_NAME
 R727 'Q_RES_0402LF-10K,1%,1/16W,CHIPA':;

SECTION_NUMBER 1
 '@S9S_MB_2U_LIB.S9S_MB_2U(SCH_1):PAGE175_I236@PURE_QUANTA.Q_RES(CHIPS)':
 C_PATH='@s9s_mb_2u_lib.s9s_mb_2u(sch_1):page175_i236@pure_quanta.q_res(chips)',
 P_PATH='@s9s_mb_2u_lib.s9s_mb_2u(sch_1):page183_i236@pure_quanta.q_res(chips)',
 PATH='I236',
 DRAWING='@S9S_MB_2U_LIB.S9S_MB_2U(SCH_1):PAGE175',
 PHYS_PAGE='183',
 XY='(3475,-325)',
 ROT='0',
 VER='1',
 PACK_TYPE='0402LF',
 CDS_LIB='pure_quanta',
 CDS_PART_NAME='Q_RES_0402LF-10K,1%,1/16W,CHIPA',
 WATTAGE='1/16W',
 TOLERANCE='1%',
 MATERIAL='CHIP',
 VALUE='10K',
 PRIM_FILE='./archive_libs/logical/q_res/chips/chips.prt';

PART_NAME
 R734 'Q_RES_0402LF-4.75K,1%,1/16W,CHA':;

SECTION_NUMBER 1
 '@S9S_MB_2U_LIB.S9S_MB_2U(SCH_1):PAGE197_I283@PURE_QUANTA.Q_RES(CHIPS)':
 C_PATH='@s9s_mb_2u_lib.s9s_mb_2u(sch_1):page197_i283@pure_quanta.q_res(chips)',
 P_PATH='@s9s_mb_2u_lib.s9s_mb_2u(sch_1):page208_i283@pure_quanta.q_res(chips)',
 PATH='I283',
 DRAWING='@S9S_MB_2U_LIB.S9S_MB_2U(SCH_1):PAGE197',
 PHYS_PAGE='208',
 XY='(-5625,9800)',
 ROT='0',
 VER='2',
 PACK_TYPE='0402LF',
 CDS_LIB='pure_quanta',
 CDS_PART_NAME='Q_RES_0402LF-4.75K,1%,1/16W,CHA',
 WATTAGE='1/16W',
 TOLERANCE='1%',
 MATERIAL='CHIP',
 VALUE='4.75K',
 PRIM_FILE='./archive_libs/logical/q_res/chips/chips.prt';

PART_NAME
 R735 'Q_RES_0402LF-10K,1%,1/16W,CHIPA':;

SECTION_NUMBER 1
 '@S9S_MB_2U_LIB.S9S_MB_2U(SCH_1):PAGE209_I13@PURE_QUANTA.Q_RES(CHIPS)':
 C_PATH='@s9s_mb_2u_lib.s9s_mb_2u(sch_1):page209_i13@pure_quanta.q_res(chips)',
 P_PATH='@s9s_mb_2u_lib.s9s_mb_2u(sch_1):page220_i13@pure_quanta.q_res(chips)',
 PATH='I13',
 DRAWING='@S9S_MB_2U_LIB.S9S_MB_2U(SCH_1):PAGE209',
 PHYS_PAGE='220',
 XY='(-3325,2525)',
 ROT='0',
 VER='2',
 PACK_TYPE='0402LF',
 CDS_LIB='pure_quanta',
 CDS_PART_NAME='Q_RES_0402LF-10K,1%,1/16W,CHIPA',
 WATTAGE='1/16W',
 TOLERANCE='1%',
 MATERIAL='CHIP',
 VALUE='10K',
 PRIM_FILE='./archive_libs/logical/q_res/chips/chips.prt';

PART_NAME
 R736 'Q_RES_0402LF-1K,1%,1/16W,EMPTYA':;

SECTION_NUMBER 1
 '@S9S_MB_2U_LIB.S9S_MB_2U(SCH_1):PAGE209_I11@PURE_QUANTA.Q_RES(CHIPS)':
 C_PATH='@s9s_mb_2u_lib.s9s_mb_2u(sch_1):page209_i11@pure_quanta.q_res(chips)',
 P_PATH='@s9s_mb_2u_lib.s9s_mb_2u(sch_1):page220_i11@pure_quanta.q_res(chips)',
 PATH='I11',
 DRAWING='@S9S_MB_2U_LIB.S9S_MB_2U(SCH_1):PAGE209',
 PHYS_PAGE='220',
 XY='(-3325,2050)',
 ROT='0',
 VER='2',
 PACK_TYPE='0402LF',
 CDS_LIB='pure_quanta',
 CDS_PART_NAME='Q_RES_0402LF-1K,1%,1/16W,EMPTYA',
 WATTAGE='1/16W',
 TOLERANCE='1%',
 MATERIAL='EMPTY',
 VALUE='1K',
 PRIM_FILE='./archive_libs/logical/q_res/chips/chips.prt';

PART_NAME
 R737 'Q_RES_0402LF-0,5%,1/16W,CHIP,CA':;

SECTION_NUMBER 1
 '@S9S_MB_2U_LIB.S9S_MB_2U(SCH_1):PAGE135_I106@PURE_QUANTA.Q_RES(CHIPS)':
 C_PATH='@s9s_mb_2u_lib.s9s_mb_2u(sch_1):page135_i106@pure_quanta.q_res(chips)',
 P_PATH='@s9s_mb_2u_lib.s9s_mb_2u(sch_1):page133_i106@pure_quanta.q_res(chips)',
 PATH='I106',
 DRAWING='@S9S_MB_2U_LIB.S9S_MB_2U(SCH_1):PAGE135',
 PHYS_PAGE='133',
 XY='(-750,250)',
 ROT='0',
 VER='1',
 PACK_TYPE='0402LF',
 CDS_LIB='pure_quanta',
 CDS_PART_NAME='Q_RES_0402LF-0,5%,1/16W,CHIP,CA',
 WATTAGE='1/16W',
 TOLERANCE='5%',
 MATERIAL='CHIP',
 VALUE='0',
 PRIM_FILE='./archive_libs/logical/q_res/chips/chips.prt';

PART_NAME
 R738 'Q_RES_0402LF-0,5%,1/16W,CHIP,CA':;

SECTION_NUMBER 1
 '@S9S_MB_2U_LIB.S9S_MB_2U(SCH_1):PAGE135_I110@PURE_QUANTA.Q_RES(CHIPS)':
 C_PATH='@s9s_mb_2u_lib.s9s_mb_2u(sch_1):page135_i110@pure_quanta.q_res(chips)',
 P_PATH='@s9s_mb_2u_lib.s9s_mb_2u(sch_1):page133_i110@pure_quanta.q_res(chips)',
 PATH='I110',
 DRAWING='@S9S_MB_2U_LIB.S9S_MB_2U(SCH_1):PAGE135',
 PHYS_PAGE='133',
 XY='(-750,150)',
 ROT='0',
 VER='1',
 PACK_TYPE='0402LF',
 CDS_LIB='pure_quanta',
 CDS_PART_NAME='Q_RES_0402LF-0,5%,1/16W,CHIP,CA',
 WATTAGE='1/16W',
 TOLERANCE='5%',
 MATERIAL='CHIP',
 VALUE='0',
 PRIM_FILE='./archive_libs/logical/q_res/chips/chips.prt';

PART_NAME
 R739 'Q_RES_0402LF-10K,1%,1/16W,CHIPA':;

SECTION_NUMBER 1
 '@S9S_MB_2U_LIB.S9S_MB_2U(SCH_1):PAGE135_I109@PURE_QUANTA.Q_RES(CHIPS)':
 C_PATH='@s9s_mb_2u_lib.s9s_mb_2u(sch_1):page135_i109@pure_quanta.q_res(chips)',
 P_PATH='@s9s_mb_2u_lib.s9s_mb_2u(sch_1):page133_i109@pure_quanta.q_res(chips)',
 PATH='I109',
 DRAWING='@S9S_MB_2U_LIB.S9S_MB_2U(SCH_1):PAGE135',
 PHYS_PAGE='133',
 XY='(-300,500)',
 ROT='0',
 VER='2',
 PACK_TYPE='0402LF',
 CDS_LIB='pure_quanta',
 CDS_PART_NAME='Q_RES_0402LF-10K,1%,1/16W,CHIPA',
 WATTAGE='1/16W',
 TOLERANCE='1%',
 MATERIAL='CHIP',
 VALUE='10K',
 PRIM_FILE='./archive_libs/logical/q_res/chips/chips.prt';

PART_NAME
 R740 'Q_RES_0402LF-10K,1%,1/16W,CHIPA':;

SECTION_NUMBER 1
 '@S9S_MB_2U_LIB.S9S_MB_2U(SCH_1):PAGE135_I107@PURE_QUANTA.Q_RES(CHIPS)':
 C_PATH='@s9s_mb_2u_lib.s9s_mb_2u(sch_1):page135_i107@pure_quanta.q_res(chips)',
 P_PATH='@s9s_mb_2u_lib.s9s_mb_2u(sch_1):page133_i107@pure_quanta.q_res(chips)',
 PATH='I107',
 DRAWING='@S9S_MB_2U_LIB.S9S_MB_2U(SCH_1):PAGE135',
 PHYS_PAGE='133',
 XY='(-50,500)',
 ROT='0',
 VER='2',
 PACK_TYPE='0402LF',
 CDS_LIB='pure_quanta',
 CDS_PART_NAME='Q_RES_0402LF-10K,1%,1/16W,CHIPA',
 WATTAGE='1/16W',
 TOLERANCE='1%',
 MATERIAL='CHIP',
 VALUE='10K',
 PRIM_FILE='./archive_libs/logical/q_res/chips/chips.prt';

PART_NAME
 R741 'Q_RES_0402LF-150,1%,1/16W,CHIPA':;

SECTION_NUMBER 1
 '@S9S_MB_2U_LIB.S9S_MB_2U(SCH_1):PAGE135_I66@PURE_QUANTA.Q_RES(CHIPS)':
 C_PATH='@s9s_mb_2u_lib.s9s_mb_2u(sch_1):page135_i66@pure_quanta.q_res(chips)',
 P_PATH='@s9s_mb_2u_lib.s9s_mb_2u(sch_1):page133_i66@pure_quanta.q_res(chips)',
 PATH='I66',
 DRAWING='@S9S_MB_2U_LIB.S9S_MB_2U(SCH_1):PAGE135',
 PHYS_PAGE='133',
 XY='(600,3800)',
 ROT='0',
 VER='2',
 PACK_TYPE='0402LF',
 CDS_LIB='pure_quanta',
 CDS_PART_NAME='Q_RES_0402LF-150,1%,1/16W,CHIPA',
 WATTAGE='1/16W',
 TOLERANCE='1%',
 MATERIAL='CHIP',
 VALUE='150',
 PRIM_FILE='./archive_libs/logical/q_res/chips/chips.prt';

PART_NAME
 R742 'Q_RES_0402LF-75,1%,1/16W,CHIP,A':;

SECTION_NUMBER 1
 '@S9S_MB_2U_LIB.S9S_MB_2U(SCH_1):PAGE135_I78@PURE_QUANTA.Q_RES(CHIPS)':
 C_PATH='@s9s_mb_2u_lib.s9s_mb_2u(sch_1):page135_i78@pure_quanta.q_res(chips)',
 P_PATH='@s9s_mb_2u_lib.s9s_mb_2u(sch_1):page133_i78@pure_quanta.q_res(chips)',
 PATH='I78',
 DRAWING='@S9S_MB_2U_LIB.S9S_MB_2U(SCH_1):PAGE135',
 PHYS_PAGE='133',
 XY='(600,2250)',
 ROT='0',
 VER='2',
 PACK_TYPE='0402LF',
 CDS_LIB='pure_quanta',
 CDS_PART_NAME='Q_RES_0402LF-75,1%,1/16W,CHIP,A',
 WATTAGE='1/16W',
 TOLERANCE='1%',
 MATERIAL='CHIP',
 VALUE='75',
 PRIM_FILE='./archive_libs/logical/q_res/chips/chips.prt';

PART_NAME
 R743 'Q_RES_0402LF-150,1%,1/16W,CHIPA':;

SECTION_NUMBER 1
 '@S9S_MB_2U_LIB.S9S_MB_2U(SCH_1):PAGE135_I65@PURE_QUANTA.Q_RES(CHIPS)':
 C_PATH='@s9s_mb_2u_lib.s9s_mb_2u(sch_1):page135_i65@pure_quanta.q_res(chips)',
 P_PATH='@s9s_mb_2u_lib.s9s_mb_2u(sch_1):page133_i65@pure_quanta.q_res(chips)',
 PATH='I65',
 DRAWING='@S9S_MB_2U_LIB.S9S_MB_2U(SCH_1):PAGE135',
 PHYS_PAGE='133',
 XY='(1250,3800)',
 ROT='0',
 VER='2',
 PACK_TYPE='0402LF',
 CDS_LIB='pure_quanta',
 CDS_PART_NAME='Q_RES_0402LF-150,1%,1/16W,CHIPA',
 WATTAGE='1/16W',
 TOLERANCE='1%',
 MATERIAL='CHIP',
 VALUE='150',
 PRIM_FILE='./archive_libs/logical/q_res/chips/chips.prt';

PART_NAME
 R744 'Q_RES_0402LF-75,1%,1/16W,CHIP,A':;

SECTION_NUMBER 1
 '@S9S_MB_2U_LIB.S9S_MB_2U(SCH_1):PAGE135_I77@PURE_QUANTA.Q_RES(CHIPS)':
 C_PATH='@s9s_mb_2u_lib.s9s_mb_2u(sch_1):page135_i77@pure_quanta.q_res(chips)',
 P_PATH='@s9s_mb_2u_lib.s9s_mb_2u(sch_1):page133_i77@pure_quanta.q_res(chips)',
 PATH='I77',
 DRAWING='@S9S_MB_2U_LIB.S9S_MB_2U(SCH_1):PAGE135',
 PHYS_PAGE='133',
 XY='(1250,2250)',
 ROT='0',
 VER='2',
 PACK_TYPE='0402LF',
 CDS_LIB='pure_quanta',
 CDS_PART_NAME='Q_RES_0402LF-75,1%,1/16W,CHIP,A',
 WATTAGE='1/16W',
 TOLERANCE='1%',
 MATERIAL='CHIP',
 VALUE='75',
 PRIM_FILE='./archive_libs/logical/q_res/chips/chips.prt';

PART_NAME
 R745 'Q_RES_0402LF-33.2,1%,1/16W,CHIA':;

SECTION_NUMBER 1
 '@S9S_MB_2U_LIB.S9S_MB_2U(SCH_1):PAGE135_I97@PURE_QUANTA.Q_RES(CHIPS)':
 C_PATH='@s9s_mb_2u_lib.s9s_mb_2u(sch_1):page135_i97@pure_quanta.q_res(chips)',
 P_PATH='@s9s_mb_2u_lib.s9s_mb_2u(sch_1):page133_i97@pure_quanta.q_res(chips)',
 PATH='I97',
 DRAWING='@S9S_MB_2U_LIB.S9S_MB_2U(SCH_1):PAGE135',
 PHYS_PAGE='133',
 XY='(2075,200)',
 ROT='0',
 VER='1',
 PACK_TYPE='0402LF',
 CDS_LIB='pure_quanta',
 CDS_PART_NAME='Q_RES_0402LF-33.2,1%,1/16W,CHIA',
 WATTAGE='1/16W',
 TOLERANCE='1%',
 MATERIAL='CHIP',
 VALUE='33.2',
 PRIM_FILE='./archive_libs/logical/q_res/chips/chips.prt';

PART_NAME
 R746 'Q_RES_0402LF-0,5%,1/16W,CHIP,CA':;

SECTION_NUMBER 1
 '@S9S_MB_2U_LIB.S9S_MB_2U(SCH_1):PAGE134_I90@PURE_QUANTA.Q_RES(CHIPS)':
 C_PATH='@s9s_mb_2u_lib.s9s_mb_2u(sch_1):page134_i90@pure_quanta.q_res(chips)',
 P_PATH='@s9s_mb_2u_lib.s9s_mb_2u(sch_1):page132_i90@pure_quanta.q_res(chips)',
 PATH='I90',
 DRAWING='@S9S_MB_2U_LIB.S9S_MB_2U(SCH_1):PAGE134',
 PHYS_PAGE='132',
 XY='(-1900,3025)',
 ROT='2',
 VER='2',
 PACK_TYPE='0402LF',
 CDS_LIB='pure_quanta',
 CDS_PART_NAME='Q_RES_0402LF-0,5%,1/16W,CHIP,CA',
 WATTAGE='1/16W',
 TOLERANCE='5%',
 MATERIAL='CHIP',
 VALUE='0',
 PRIM_FILE='./archive_libs/logical/q_res/chips/chips.prt';

PART_NAME
 R747 'Q_RES_0402LF-150,1%,1/16W,CHIPA':;

SECTION_NUMBER 1
 '@S9S_MB_2U_LIB.S9S_MB_2U(SCH_1):PAGE134_I176@PURE_QUANTA.Q_RES(CHIPS)':
 C_PATH='@s9s_mb_2u_lib.s9s_mb_2u(sch_1):page134_i176@pure_quanta.q_res(chips)',
 P_PATH='@s9s_mb_2u_lib.s9s_mb_2u(sch_1):page132_i176@pure_quanta.q_res(chips)',
 PATH='I176',
 DRAWING='@S9S_MB_2U_LIB.S9S_MB_2U(SCH_1):PAGE134',
 PHYS_PAGE='132',
 XY='(825,250)',
 ROT='0',
 VER='2',
 PACK_TYPE='0402LF',
 CDS_LIB='pure_quanta',
 CDS_PART_NAME='Q_RES_0402LF-150,1%,1/16W,CHIPA',
 WATTAGE='1/16W',
 TOLERANCE='1%',
 MATERIAL='CHIP',
 VALUE='150',
 PRIM_FILE='./archive_libs/logical/q_res/chips/chips.prt';

PART_NAME
 R748 'Q_RES_0402LF-75,1%,1/16W,CHIP,A':;

SECTION_NUMBER 1
 '@S9S_MB_2U_LIB.S9S_MB_2U(SCH_1):PAGE134_I180@PURE_QUANTA.Q_RES(CHIPS)':
 C_PATH='@s9s_mb_2u_lib.s9s_mb_2u(sch_1):page134_i180@pure_quanta.q_res(chips)',
 P_PATH='@s9s_mb_2u_lib.s9s_mb_2u(sch_1):page132_i180@pure_quanta.q_res(chips)',
 PATH='I180',
 DRAWING='@S9S_MB_2U_LIB.S9S_MB_2U(SCH_1):PAGE134',
 PHYS_PAGE='132',
 XY='(1175,250)',
 ROT='0',
 VER='2',
 PACK_TYPE='0402LF',
 CDS_LIB='pure_quanta',
 CDS_PART_NAME='Q_RES_0402LF-75,1%,1/16W,CHIP,A',
 WATTAGE='1/16W',
 TOLERANCE='1%',
 MATERIAL='CHIP',
 VALUE='75',
 PRIM_FILE='./archive_libs/logical/q_res/chips/chips.prt';

PART_NAME
 R749 'Q_RES_0402LF-75,1%,1/16W,CHIP,A':;

SECTION_NUMBER 1
 '@S9S_MB_2U_LIB.S9S_MB_2U(SCH_1):PAGE134_I179@PURE_QUANTA.Q_RES(CHIPS)':
 C_PATH='@s9s_mb_2u_lib.s9s_mb_2u(sch_1):page134_i179@pure_quanta.q_res(chips)',
 P_PATH='@s9s_mb_2u_lib.s9s_mb_2u(sch_1):page132_i179@pure_quanta.q_res(chips)',
 PATH='I179',
 DRAWING='@S9S_MB_2U_LIB.S9S_MB_2U(SCH_1):PAGE134',
 PHYS_PAGE='132',
 XY='(1525,250)',
 ROT='0',
 VER='2',
 PACK_TYPE='0402LF',
 CDS_LIB='pure_quanta',
 CDS_PART_NAME='Q_RES_0402LF-75,1%,1/16W,CHIP,A',
 WATTAGE='1/16W',
 TOLERANCE='1%',
 MATERIAL='CHIP',
 VALUE='75',
 PRIM_FILE='./archive_libs/logical/q_res/chips/chips.prt';

PART_NAME
 R750 'Q_RES_0402LF-150,1%,1/16W,CHIPA':;

SECTION_NUMBER 1
 '@S9S_MB_2U_LIB.S9S_MB_2U(SCH_1):PAGE134_I178@PURE_QUANTA.Q_RES(CHIPS)':
 C_PATH='@s9s_mb_2u_lib.s9s_mb_2u(sch_1):page134_i178@pure_quanta.q_res(chips)',
 P_PATH='@s9s_mb_2u_lib.s9s_mb_2u(sch_1):page132_i178@pure_quanta.q_res(chips)',
 PATH='I178',
 DRAWING='@S9S_MB_2U_LIB.S9S_MB_2U(SCH_1):PAGE134',
 PHYS_PAGE='132',
 XY='(1875,250)',
 ROT='0',
 VER='2',
 PACK_TYPE='0402LF',
 CDS_LIB='pure_quanta',
 CDS_PART_NAME='Q_RES_0402LF-150,1%,1/16W,CHIPA',
 WATTAGE='1/16W',
 TOLERANCE='1%',
 MATERIAL='CHIP',
 VALUE='150',
 PRIM_FILE='./archive_libs/logical/q_res/chips/chips.prt';

PART_NAME
 R751 'Q_RES_0402LF-150,1%,1/16W,CHIPA':;

SECTION_NUMBER 1
 '@S9S_MB_2U_LIB.S9S_MB_2U(SCH_1):PAGE134_I177@PURE_QUANTA.Q_RES(CHIPS)':
 C_PATH='@s9s_mb_2u_lib.s9s_mb_2u(sch_1):page134_i177@pure_quanta.q_res(chips)',
 P_PATH='@s9s_mb_2u_lib.s9s_mb_2u(sch_1):page132_i177@pure_quanta.q_res(chips)',
 PATH='I177',
 DRAWING='@S9S_MB_2U_LIB.S9S_MB_2U(SCH_1):PAGE134',
 PHYS_PAGE='132',
 XY='(2225,250)',
 ROT='0',
 VER='2',
 PACK_TYPE='0402LF',
 CDS_LIB='pure_quanta',
 CDS_PART_NAME='Q_RES_0402LF-150,1%,1/16W,CHIPA',
 WATTAGE='1/16W',
 TOLERANCE='1%',
 MATERIAL='CHIP',
 VALUE='150',
 PRIM_FILE='./archive_libs/logical/q_res/chips/chips.prt';

PART_NAME
 R752 'Q_RES_0402LF-10,1%,1/16W,CHIP,A':;

SECTION_NUMBER 1
 '@S9S_MB_2U_LIB.S9S_MB_2U(SCH_1):PAGE134_I127@PURE_QUANTA.Q_RES(CHIPS)':
 C_PATH='@s9s_mb_2u_lib.s9s_mb_2u(sch_1):page134_i127@pure_quanta.q_res(chips)',
 P_PATH='@s9s_mb_2u_lib.s9s_mb_2u(sch_1):page132_i127@pure_quanta.q_res(chips)',
 PATH='I127',
 DRAWING='@S9S_MB_2U_LIB.S9S_MB_2U(SCH_1):PAGE134',
 PHYS_PAGE='132',
 XY='(-575,0)',
 ROT='0',
 VER='1',
 PACK_TYPE='0402LF',
 CDS_LIB='pure_quanta',
 CDS_PART_NAME='Q_RES_0402LF-10,1%,1/16W,CHIP,A',
 WATTAGE='1/16W',
 TOLERANCE='1%',
 MATERIAL='CHIP',
 VALUE='10',
 PRIM_FILE='./archive_libs/logical/q_res/chips/chips.prt';

PART_NAME
 R753 'Q_RES_0402LF-10,1%,1/16W,CHIP,A':;

SECTION_NUMBER 1
 '@S9S_MB_2U_LIB.S9S_MB_2U(SCH_1):PAGE134_I128@PURE_QUANTA.Q_RES(CHIPS)':
 C_PATH='@s9s_mb_2u_lib.s9s_mb_2u(sch_1):page134_i128@pure_quanta.q_res(chips)',
 P_PATH='@s9s_mb_2u_lib.s9s_mb_2u(sch_1):page132_i128@pure_quanta.q_res(chips)',
 PATH='I128',
 DRAWING='@S9S_MB_2U_LIB.S9S_MB_2U(SCH_1):PAGE134',
 PHYS_PAGE='132',
 XY='(-575,-75)',
 ROT='0',
 VER='1',
 PACK_TYPE='0402LF',
 CDS_LIB='pure_quanta',
 CDS_PART_NAME='Q_RES_0402LF-10,1%,1/16W,CHIP,A',
 WATTAGE='1/16W',
 TOLERANCE='1%',
 MATERIAL='CHIP',
 VALUE='10',
 PRIM_FILE='./archive_libs/logical/q_res/chips/chips.prt';

PART_NAME
 R754 'Q_RES_0402LF-10,1%,1/16W,CHIP,A':;

SECTION_NUMBER 1
 '@S9S_MB_2U_LIB.S9S_MB_2U(SCH_1):PAGE134_I126@PURE_QUANTA.Q_RES(CHIPS)':
 C_PATH='@s9s_mb_2u_lib.s9s_mb_2u(sch_1):page134_i126@pure_quanta.q_res(chips)',
 P_PATH='@s9s_mb_2u_lib.s9s_mb_2u(sch_1):page132_i126@pure_quanta.q_res(chips)',
 PATH='I126',
 DRAWING='@S9S_MB_2U_LIB.S9S_MB_2U(SCH_1):PAGE134',
 PHYS_PAGE='132',
 XY='(-575,-150)',
 ROT='0',
 VER='1',
 PACK_TYPE='0402LF',
 CDS_LIB='pure_quanta',
 CDS_PART_NAME='Q_RES_0402LF-10,1%,1/16W,CHIP,A',
 WATTAGE='1/16W',
 TOLERANCE='1%',
 MATERIAL='CHIP',
 VALUE='10',
 PRIM_FILE='./archive_libs/logical/q_res/chips/chips.prt';

PART_NAME
 R755 'Q_RES_0402LF-10,1%,1/16W,CHIP,A':;

SECTION_NUMBER 1
 '@S9S_MB_2U_LIB.S9S_MB_2U(SCH_1):PAGE134_I147@PURE_QUANTA.Q_RES(CHIPS)':
 C_PATH='@s9s_mb_2u_lib.s9s_mb_2u(sch_1):page134_i147@pure_quanta.q_res(chips)',
 P_PATH='@s9s_mb_2u_lib.s9s_mb_2u(sch_1):page132_i147@pure_quanta.q_res(chips)',
 PATH='I147',
 DRAWING='@S9S_MB_2U_LIB.S9S_MB_2U(SCH_1):PAGE134',
 PHYS_PAGE='132',
 XY='(-575,-225)',
 ROT='0',
 VER='1',
 PACK_TYPE='0402LF',
 CDS_LIB='pure_quanta',
 CDS_PART_NAME='Q_RES_0402LF-10,1%,1/16W,CHIP,A',
 WATTAGE='1/16W',
 TOLERANCE='1%',
 MATERIAL='CHIP',
 VALUE='10',
 PRIM_FILE='./archive_libs/logical/q_res/chips/chips.prt';

PART_NAME
 R756 'Q_RES_0402LF-10,1%,1/16W,CHIP,A':;

SECTION_NUMBER 1
 '@S9S_MB_2U_LIB.S9S_MB_2U(SCH_1):PAGE134_I148@PURE_QUANTA.Q_RES(CHIPS)':
 C_PATH='@s9s_mb_2u_lib.s9s_mb_2u(sch_1):page134_i148@pure_quanta.q_res(chips)',
 P_PATH='@s9s_mb_2u_lib.s9s_mb_2u(sch_1):page132_i148@pure_quanta.q_res(chips)',
 PATH='I148',
 DRAWING='@S9S_MB_2U_LIB.S9S_MB_2U(SCH_1):PAGE134',
 PHYS_PAGE='132',
 XY='(-575,-300)',
 ROT='0',
 VER='1',
 PACK_TYPE='0402LF',
 CDS_LIB='pure_quanta',
 CDS_PART_NAME='Q_RES_0402LF-10,1%,1/16W,CHIP,A',
 WATTAGE='1/16W',
 TOLERANCE='1%',
 MATERIAL='CHIP',
 VALUE='10',
 PRIM_FILE='./archive_libs/logical/q_res/chips/chips.prt';

PART_NAME
 R757 'Q_RES_0402LF-120,1%,1/16W,CHIPA':;

SECTION_NUMBER 1
 '@S9S_MB_2U_LIB.S9S_MB_2U(SCH_1):PAGE134_I166@PURE_QUANTA.Q_RES(CHIPS)':
 C_PATH='@s9s_mb_2u_lib.s9s_mb_2u(sch_1):page134_i166@pure_quanta.q_res(chips)',
 P_PATH='@s9s_mb_2u_lib.s9s_mb_2u(sch_1):page132_i166@pure_quanta.q_res(chips)',
 PATH='I166',
 DRAWING='@S9S_MB_2U_LIB.S9S_MB_2U(SCH_1):PAGE134',
 PHYS_PAGE='132',
 XY='(1050,4075)',
 ROT='0',
 VER='2',
 PACK_TYPE='0402LF',
 CDS_LIB='pure_quanta',
 CDS_PART_NAME='Q_RES_0402LF-120,1%,1/16W,CHIPA',
 WATTAGE='1/16W',
 TOLERANCE='1%',
 MATERIAL='CHIP',
 VALUE='120',
 PRIM_FILE='./archive_libs/logical/q_res/chips/chips.prt';

PART_NAME
 R758 'Q_RES_0402LF-150,1%,1/16W,CHIPA':;

SECTION_NUMBER 1
 '@S9S_MB_2U_LIB.S9S_MB_2U(SCH_1):PAGE134_I168@PURE_QUANTA.Q_RES(CHIPS)':
 C_PATH='@s9s_mb_2u_lib.s9s_mb_2u(sch_1):page134_i168@pure_quanta.q_res(chips)',
 P_PATH='@s9s_mb_2u_lib.s9s_mb_2u(sch_1):page132_i168@pure_quanta.q_res(chips)',
 PATH='I168',
 DRAWING='@S9S_MB_2U_LIB.S9S_MB_2U(SCH_1):PAGE134',
 PHYS_PAGE='132',
 XY='(1125,2225)',
 ROT='0',
 VER='2',
 PACK_TYPE='0402LF',
 CDS_LIB='pure_quanta',
 CDS_PART_NAME='Q_RES_0402LF-150,1%,1/16W,CHIPA',
 WATTAGE='1/16W',
 TOLERANCE='1%',
 MATERIAL='CHIP',
 VALUE='150',
 PRIM_FILE='./archive_libs/logical/q_res/chips/chips.prt';

PART_NAME
 R759 'Q_RES_0402LF-150,1%,1/16W,CHIPA':;

SECTION_NUMBER 1
 '@S9S_MB_2U_LIB.S9S_MB_2U(SCH_1):PAGE134_I169@PURE_QUANTA.Q_RES(CHIPS)':
 C_PATH='@s9s_mb_2u_lib.s9s_mb_2u(sch_1):page134_i169@pure_quanta.q_res(chips)',
 P_PATH='@s9s_mb_2u_lib.s9s_mb_2u(sch_1):page132_i169@pure_quanta.q_res(chips)',
 PATH='I169',
 DRAWING='@S9S_MB_2U_LIB.S9S_MB_2U(SCH_1):PAGE134',
 PHYS_PAGE='132',
 XY='(1550,2225)',
 ROT='0',
 VER='2',
 PACK_TYPE='0402LF',
 CDS_LIB='pure_quanta',
 CDS_PART_NAME='Q_RES_0402LF-150,1%,1/16W,CHIPA',
 WATTAGE='1/16W',
 TOLERANCE='1%',
 MATERIAL='CHIP',
 VALUE='150',
 PRIM_FILE='./archive_libs/logical/q_res/chips/chips.prt';

PART_NAME
 R760 'Q_RES_0402LF-499,1%,1/16W,CHIPA':;

SECTION_NUMBER 1
 '@S9S_MB_2U_LIB.S9S_MB_2U(SCH_1):PAGE134_I174@PURE_QUANTA.Q_RES(CHIPS)':
 C_PATH='@s9s_mb_2u_lib.s9s_mb_2u(sch_1):page134_i174@pure_quanta.q_res(chips)',
 P_PATH='@s9s_mb_2u_lib.s9s_mb_2u(sch_1):page132_i174@pure_quanta.q_res(chips)',
 PATH='I174',
 DRAWING='@S9S_MB_2U_LIB.S9S_MB_2U(SCH_1):PAGE134',
 PHYS_PAGE='132',
 XY='(2000,2200)',
 ROT='0',
 VER='2',
 PACK_TYPE='0402LF',
 CDS_LIB='pure_quanta',
 CDS_PART_NAME='Q_RES_0402LF-499,1%,1/16W,CHIPA',
 WATTAGE='1/16W',
 TOLERANCE='1%',
 MATERIAL='CHIP',
 VALUE='499',
 PRIM_FILE='./archive_libs/logical/q_res/chips/chips.prt';

PART_NAME
 R761 'Q_RES_0402LF-499,1%,1/16W,CHIPA':;

SECTION_NUMBER 1
 '@S9S_MB_2U_LIB.S9S_MB_2U(SCH_1):PAGE134_I175@PURE_QUANTA.Q_RES(CHIPS)':
 C_PATH='@s9s_mb_2u_lib.s9s_mb_2u(sch_1):page134_i175@pure_quanta.q_res(chips)',
 P_PATH='@s9s_mb_2u_lib.s9s_mb_2u(sch_1):page132_i175@pure_quanta.q_res(chips)',
 PATH='I175',
 DRAWING='@S9S_MB_2U_LIB.S9S_MB_2U(SCH_1):PAGE134',
 PHYS_PAGE='132',
 XY='(2350,2200)',
 ROT='0',
 VER='2',
 PACK_TYPE='0402LF',
 CDS_LIB='pure_quanta',
 CDS_PART_NAME='Q_RES_0402LF-499,1%,1/16W,CHIPA',
 WATTAGE='1/16W',
 TOLERANCE='1%',
 MATERIAL='CHIP',
 VALUE='499',
 PRIM_FILE='./archive_libs/logical/q_res/chips/chips.prt';

PART_NAME
 R762 'Q_RES_0402LF-0,5%,1/16W,CHIP,CA':;

SECTION_NUMBER 1
 '@S9S_MB_2U_LIB.S9S_MB_2U(SCH_1):PAGE133_I71@PURE_QUANTA.Q_RES(CHIPS)':
 C_PATH='@s9s_mb_2u_lib.s9s_mb_2u(sch_1):page133_i71@pure_quanta.q_res(chips)',
 P_PATH='@s9s_mb_2u_lib.s9s_mb_2u(sch_1):page131_i71@pure_quanta.q_res(chips)',
 PATH='I71',
 DRAWING='@S9S_MB_2U_LIB.S9S_MB_2U(SCH_1):PAGE133',
 PHYS_PAGE='131',
 XY='(-1650,3125)',
 ROT='0',
 VER='1',
 PACK_TYPE='0402LF',
 CDS_LIB='pure_quanta',
 CDS_PART_NAME='Q_RES_0402LF-0,5%,1/16W,CHIP,CA',
 WATTAGE='1/16W',
 TOLERANCE='5%',
 MATERIAL='CHIP',
 VALUE='0',
 PRIM_FILE='./archive_libs/logical/q_res/chips/chips.prt';

PART_NAME
 R763 'Q_RES_0402LF-10,1%,1/16W,CHIP,A':;

SECTION_NUMBER 1
 '@S9S_MB_2U_LIB.S9S_MB_2U(SCH_1):PAGE133_I70@PURE_QUANTA.Q_RES(CHIPS)':
 C_PATH='@s9s_mb_2u_lib.s9s_mb_2u(sch_1):page133_i70@pure_quanta.q_res(chips)',
 P_PATH='@s9s_mb_2u_lib.s9s_mb_2u(sch_1):page131_i70@pure_quanta.q_res(chips)',
 PATH='I70',
 DRAWING='@S9S_MB_2U_LIB.S9S_MB_2U(SCH_1):PAGE133',
 PHYS_PAGE='131',
 XY='(-1650,3075)',
 ROT='0',
 VER='1',
 PACK_TYPE='0402LF',
 CDS_LIB='pure_quanta',
 CDS_PART_NAME='Q_RES_0402LF-10,1%,1/16W,CHIP,A',
 WATTAGE='1/16W',
 TOLERANCE='1%',
 MATERIAL='CHIP',
 VALUE='10',
 PRIM_FILE='./archive_libs/logical/q_res/chips/chips.prt';

PART_NAME
 R764 'Q_RES_0402LF-0,5%,1/16W,CHIP,CA':;

SECTION_NUMBER 1
 '@S9S_MB_2U_LIB.S9S_MB_2U(SCH_1):PAGE133_I83@PURE_QUANTA.Q_RES(CHIPS)':
 C_PATH='@s9s_mb_2u_lib.s9s_mb_2u(sch_1):page133_i83@pure_quanta.q_res(chips)',
 P_PATH='@s9s_mb_2u_lib.s9s_mb_2u(sch_1):page131_i83@pure_quanta.q_res(chips)',
 PATH='I83',
 DRAWING='@S9S_MB_2U_LIB.S9S_MB_2U(SCH_1):PAGE133',
 PHYS_PAGE='131',
 XY='(-1650,2925)',
 ROT='0',
 VER='1',
 PACK_TYPE='0402LF',
 CDS_LIB='pure_quanta',
 CDS_PART_NAME='Q_RES_0402LF-0,5%,1/16W,CHIP,CA',
 WATTAGE='1/16W',
 TOLERANCE='5%',
 MATERIAL='CHIP',
 VALUE='0',
 PRIM_FILE='./archive_libs/logical/q_res/chips/chips.prt';

PART_NAME
 R765 'Q_RES_0402LF-0,5%,1/16W,CHIP,CA':;

SECTION_NUMBER 1
 '@S9S_MB_2U_LIB.S9S_MB_2U(SCH_1):PAGE133_I74@PURE_QUANTA.Q_RES(CHIPS)':
 C_PATH='@s9s_mb_2u_lib.s9s_mb_2u(sch_1):page133_i74@pure_quanta.q_res(chips)',
 P_PATH='@s9s_mb_2u_lib.s9s_mb_2u(sch_1):page131_i74@pure_quanta.q_res(chips)',
 PATH='I74',
 DRAWING='@S9S_MB_2U_LIB.S9S_MB_2U(SCH_1):PAGE133',
 PHYS_PAGE='131',
 XY='(-1650,1925)',
 ROT='0',
 VER='1',
 PACK_TYPE='0402LF',
 CDS_LIB='pure_quanta',
 CDS_PART_NAME='Q_RES_0402LF-0,5%,1/16W,CHIP,CA',
 WATTAGE='1/16W',
 TOLERANCE='5%',
 MATERIAL='CHIP',
 VALUE='0',
 PRIM_FILE='./archive_libs/logical/q_res/chips/chips.prt';

PART_NAME
 R766 'Q_RES_0402LF-1K,1%,1/16W,EMPTYA':;

SECTION_NUMBER 1
 '@S9S_MB_2U_LIB.S9S_MB_2U(SCH_1):PAGE133_I111@PURE_QUANTA.Q_RES(CHIPS)':
 C_PATH='@s9s_mb_2u_lib.s9s_mb_2u(sch_1):page133_i111@pure_quanta.q_res(chips)',
 P_PATH='@s9s_mb_2u_lib.s9s_mb_2u(sch_1):page131_i111@pure_quanta.q_res(chips)',
 PATH='I111',
 DRAWING='@S9S_MB_2U_LIB.S9S_MB_2U(SCH_1):PAGE133',
 PHYS_PAGE='131',
 XY='(-125,-250)',
 ROT='0',
 VER='2',
 PACK_TYPE='0402LF',
 CDS_LIB='pure_quanta',
 CDS_PART_NAME='Q_RES_0402LF-1K,1%,1/16W,EMPTYA',
 WATTAGE='1/16W',
 TOLERANCE='1%',
 MATERIAL='EMPTY',
 VALUE='1K',
 PRIM_FILE='./archive_libs/logical/q_res/chips/chips.prt';

PART_NAME
 R767 'Q_RES_0402LF-1K,1%,1/16W,CHIP,A':;

SECTION_NUMBER 1
 '@S9S_MB_2U_LIB.S9S_MB_2U(SCH_1):PAGE133_I113@PURE_QUANTA.Q_RES(CHIPS)':
 C_PATH='@s9s_mb_2u_lib.s9s_mb_2u(sch_1):page133_i113@pure_quanta.q_res(chips)',
 P_PATH='@s9s_mb_2u_lib.s9s_mb_2u(sch_1):page131_i113@pure_quanta.q_res(chips)',
 PATH='I113',
 DRAWING='@S9S_MB_2U_LIB.S9S_MB_2U(SCH_1):PAGE133',
 PHYS_PAGE='131',
 XY='(100,-250)',
 ROT='0',
 VER='2',
 PACK_TYPE='0402LF',
 CDS_LIB='pure_quanta',
 CDS_PART_NAME='Q_RES_0402LF-1K,1%,1/16W,CHIP,A',
 WATTAGE='1/16W',
 TOLERANCE='1%',
 MATERIAL='CHIP',
 VALUE='1K',
 PRIM_FILE='./archive_libs/logical/q_res/chips/chips.prt';

PART_NAME
 R768 'Q_RES_0402LF-1K,1%,1/16W,CHIP,A':;

SECTION_NUMBER 1
 '@S9S_MB_2U_LIB.S9S_MB_2U(SCH_1):PAGE133_I112@PURE_QUANTA.Q_RES(CHIPS)':
 C_PATH='@s9s_mb_2u_lib.s9s_mb_2u(sch_1):page133_i112@pure_quanta.q_res(chips)',
 P_PATH='@s9s_mb_2u_lib.s9s_mb_2u(sch_1):page131_i112@pure_quanta.q_res(chips)',
 PATH='I112',
 DRAWING='@S9S_MB_2U_LIB.S9S_MB_2U(SCH_1):PAGE133',
 PHYS_PAGE='131',
 XY='(300,-250)',
 ROT='0',
 VER='2',
 PACK_TYPE='0402LF',
 CDS_LIB='pure_quanta',
 CDS_PART_NAME='Q_RES_0402LF-1K,1%,1/16W,CHIP,A',
 WATTAGE='1/16W',
 TOLERANCE='1%',
 MATERIAL='CHIP',
 VALUE='1K',
 PRIM_FILE='./archive_libs/logical/q_res/chips/chips.prt';

PART_NAME
 R769 'Q_RES_0402LF-10K,1%,1/16W,CHIPA':;

SECTION_NUMBER 1
 '@S9S_MB_2U_LIB.S9S_MB_2U(SCH_1):PAGE133_I102@PURE_QUANTA.Q_RES(CHIPS)':
 C_PATH='@s9s_mb_2u_lib.s9s_mb_2u(sch_1):page133_i102@pure_quanta.q_res(chips)',
 P_PATH='@s9s_mb_2u_lib.s9s_mb_2u(sch_1):page131_i102@pure_quanta.q_res(chips)',
 PATH='I102',
 DRAWING='@S9S_MB_2U_LIB.S9S_MB_2U(SCH_1):PAGE133',
 PHYS_PAGE='131',
 XY='(2650,2650)',
 ROT='0',
 VER='2',
 PACK_TYPE='0402LF',
 CDS_LIB='pure_quanta',
 CDS_PART_NAME='Q_RES_0402LF-10K,1%,1/16W,CHIPA',
 WATTAGE='1/16W',
 TOLERANCE='1%',
 MATERIAL='CHIP',
 VALUE='10K',
 PRIM_FILE='./archive_libs/logical/q_res/chips/chips.prt';

PART_NAME
 R770 'Q_RES_0402LF-10K,1%,1/16W,CHIPA':;

SECTION_NUMBER 1
 '@S9S_MB_2U_LIB.S9S_MB_2U(SCH_1):PAGE175_I239@PURE_QUANTA.Q_RES(CHIPS)':
 C_PATH='@s9s_mb_2u_lib.s9s_mb_2u(sch_1):page175_i239@pure_quanta.q_res(chips)',
 P_PATH='@s9s_mb_2u_lib.s9s_mb_2u(sch_1):page183_i239@pure_quanta.q_res(chips)',
 PATH='I239',
 DRAWING='@S9S_MB_2U_LIB.S9S_MB_2U(SCH_1):PAGE175',
 PHYS_PAGE='183',
 XY='(3475,-375)',
 ROT='0',
 VER='1',
 PACK_TYPE='0402LF',
 CDS_LIB='pure_quanta',
 CDS_PART_NAME='Q_RES_0402LF-10K,1%,1/16W,CHIPA',
 WATTAGE='1/16W',
 TOLERANCE='1%',
 MATERIAL='CHIP',
 VALUE='10K',
 PRIM_FILE='./archive_libs/logical/q_res/chips/chips.prt';

PART_NAME
 R771 'Q_RES_0402LF-1K,1%,1/16W,CHIP,A':;

SECTION_NUMBER 1
 '@S9S_MB_2U_LIB.S9S_MB_2U(SCH_1):PAGE133_I120@PURE_QUANTA.Q_RES(CHIPS)':
 C_PATH='@s9s_mb_2u_lib.s9s_mb_2u(sch_1):page133_i120@pure_quanta.q_res(chips)',
 P_PATH='@s9s_mb_2u_lib.s9s_mb_2u(sch_1):page131_i120@pure_quanta.q_res(chips)',
 PATH='I120',
 DRAWING='@S9S_MB_2U_LIB.S9S_MB_2U(SCH_1):PAGE133',
 PHYS_PAGE='131',
 XY='(625,-800)',
 ROT='0',
 VER='1',
 PACK_TYPE='0402LF',
 CDS_LIB='pure_quanta',
 CDS_PART_NAME='Q_RES_0402LF-1K,1%,1/16W,CHIP,A',
 WATTAGE='1/16W',
 TOLERANCE='1%',
 MATERIAL='CHIP',
 VALUE='1K',
 PRIM_FILE='./archive_libs/logical/q_res/chips/chips.prt';

PART_NAME
 R772 'Q_RES_0402LF-1K,1%,1/16W,CHIP,A':;

SECTION_NUMBER 1
 '@S9S_MB_2U_LIB.S9S_MB_2U(SCH_1):PAGE133_I118@PURE_QUANTA.Q_RES(CHIPS)':
 C_PATH='@s9s_mb_2u_lib.s9s_mb_2u(sch_1):page133_i118@pure_quanta.q_res(chips)',
 P_PATH='@s9s_mb_2u_lib.s9s_mb_2u(sch_1):page131_i118@pure_quanta.q_res(chips)',
 PATH='I118',
 DRAWING='@S9S_MB_2U_LIB.S9S_MB_2U(SCH_1):PAGE133',
 PHYS_PAGE='131',
 XY='(625,-875)',
 ROT='0',
 VER='1',
 PACK_TYPE='0402LF',
 CDS_LIB='pure_quanta',
 CDS_PART_NAME='Q_RES_0402LF-1K,1%,1/16W,CHIP,A',
 WATTAGE='1/16W',
 TOLERANCE='1%',
 MATERIAL='CHIP',
 VALUE='1K',
 PRIM_FILE='./archive_libs/logical/q_res/chips/chips.prt';

PART_NAME
 R773 'Q_RES_0402LF-1K,1%,1/16W,CHIP,A':;

SECTION_NUMBER 1
 '@S9S_MB_2U_LIB.S9S_MB_2U(SCH_1):PAGE133_I124@PURE_QUANTA.Q_RES(CHIPS)':
 C_PATH='@s9s_mb_2u_lib.s9s_mb_2u(sch_1):page133_i124@pure_quanta.q_res(chips)',
 P_PATH='@s9s_mb_2u_lib.s9s_mb_2u(sch_1):page131_i124@pure_quanta.q_res(chips)',
 PATH='I124',
 DRAWING='@S9S_MB_2U_LIB.S9S_MB_2U(SCH_1):PAGE133',
 PHYS_PAGE='131',
 XY='(625,-950)',
 ROT='0',
 VER='1',
 PACK_TYPE='0402LF',
 CDS_LIB='pure_quanta',
 CDS_PART_NAME='Q_RES_0402LF-1K,1%,1/16W,CHIP,A',
 WATTAGE='1/16W',
 TOLERANCE='1%',
 MATERIAL='CHIP',
 VALUE='1K',
 PRIM_FILE='./archive_libs/logical/q_res/chips/chips.prt';

PART_NAME
 R774 'Q_RES_0402LF-75,1%,1/16W,CHIP,A':;

SECTION_NUMBER 1
 '@S9S_MB_2U_LIB.S9S_MB_2U(SCH_1):PAGE133_I132@PURE_QUANTA.Q_RES(CHIPS)':
 C_PATH='@s9s_mb_2u_lib.s9s_mb_2u(sch_1):page133_i132@pure_quanta.q_res(chips)',
 P_PATH='@s9s_mb_2u_lib.s9s_mb_2u(sch_1):page131_i132@pure_quanta.q_res(chips)',
 PATH='I132',
 DRAWING='@S9S_MB_2U_LIB.S9S_MB_2U(SCH_1):PAGE133',
 PHYS_PAGE='131',
 XY='(725,-1225)',
 ROT='0',
 VER='2',
 PACK_TYPE='0402LF',
 CDS_LIB='pure_quanta',
 CDS_PART_NAME='Q_RES_0402LF-75,1%,1/16W,CHIP,A',
 WATTAGE='1/16W',
 TOLERANCE='1%',
 MATERIAL='CHIP',
 VALUE='75',
 PRIM_FILE='./archive_libs/logical/q_res/chips/chips.prt';

PART_NAME
 R775 'Q_RES_0402LF-10,1%,1/16W,CHIP,A':;

SECTION_NUMBER 1
 '@S9S_MB_2U_LIB.S9S_MB_2U(SCH_1):PAGE133_I5@PURE_QUANTA.Q_RES(CHIPS)':
 C_PATH='@s9s_mb_2u_lib.s9s_mb_2u(sch_1):page133_i5@pure_quanta.q_res(chips)',
 P_PATH='@s9s_mb_2u_lib.s9s_mb_2u(sch_1):page131_i5@pure_quanta.q_res(chips)',
 PATH='I5',
 DRAWING='@S9S_MB_2U_LIB.S9S_MB_2U(SCH_1):PAGE133',
 PHYS_PAGE='131',
 XY='(1625,3175)',
 ROT='0',
 VER='1',
 PACK_TYPE='0402LF',
 CDS_LIB='pure_quanta',
 CDS_PART_NAME='Q_RES_0402LF-10,1%,1/16W,CHIP,A',
 WATTAGE='1/16W',
 TOLERANCE='1%',
 MATERIAL='CHIP',
 VALUE='10',
 PRIM_FILE='./archive_libs/logical/q_res/chips/chips.prt';

PART_NAME
 R776 'Q_RES_0402LF-100,1%,1/16W,CHIPA':;

SECTION_NUMBER 1
 '@S9S_MB_2U_LIB.S9S_MB_2U(SCH_1):PAGE133_I7@PURE_QUANTA.Q_RES(CHIPS)':
 C_PATH='@s9s_mb_2u_lib.s9s_mb_2u(sch_1):page133_i7@pure_quanta.q_res(chips)',
 P_PATH='@s9s_mb_2u_lib.s9s_mb_2u(sch_1):page131_i7@pure_quanta.q_res(chips)',
 PATH='I7',
 DRAWING='@S9S_MB_2U_LIB.S9S_MB_2U(SCH_1):PAGE133',
 PHYS_PAGE='131',
 XY='(1625,3125)',
 ROT='0',
 VER='1',
 PACK_TYPE='0402LF',
 CDS_LIB='pure_quanta',
 CDS_PART_NAME='Q_RES_0402LF-100,1%,1/16W,CHIPA',
 WATTAGE='1/16W',
 TOLERANCE='1%',
 MATERIAL='CHIP',
 VALUE='100',
 PRIM_FILE='./archive_libs/logical/q_res/chips/chips.prt';

PART_NAME
 R777 'Q_RES_0402LF-10,1%,1/16W,CHIP,A':;

SECTION_NUMBER 1
 '@S9S_MB_2U_LIB.S9S_MB_2U(SCH_1):PAGE133_I10@PURE_QUANTA.Q_RES(CHIPS)':
 C_PATH='@s9s_mb_2u_lib.s9s_mb_2u(sch_1):page133_i10@pure_quanta.q_res(chips)',
 P_PATH='@s9s_mb_2u_lib.s9s_mb_2u(sch_1):page131_i10@pure_quanta.q_res(chips)',
 PATH='I10',
 DRAWING='@S9S_MB_2U_LIB.S9S_MB_2U(SCH_1):PAGE133',
 PHYS_PAGE='131',
 XY='(1625,2975)',
 ROT='0',
 VER='1',
 PACK_TYPE='0402LF',
 CDS_LIB='pure_quanta',
 CDS_PART_NAME='Q_RES_0402LF-10,1%,1/16W,CHIP,A',
 WATTAGE='1/16W',
 TOLERANCE='1%',
 MATERIAL='CHIP',
 VALUE='10',
 PRIM_FILE='./archive_libs/logical/q_res/chips/chips.prt';

PART_NAME
 R778 'Q_RES_0402LF-1K,1%,1/16W,CHIP,A':;

SECTION_NUMBER 1
 '@S9S_MB_2U_LIB.S9S_MB_2U(SCH_1):PAGE133_I15@PURE_QUANTA.Q_RES(CHIPS)':
 C_PATH='@s9s_mb_2u_lib.s9s_mb_2u(sch_1):page133_i15@pure_quanta.q_res(chips)',
 P_PATH='@s9s_mb_2u_lib.s9s_mb_2u(sch_1):page131_i15@pure_quanta.q_res(chips)',
 PATH='I15',
 DRAWING='@S9S_MB_2U_LIB.S9S_MB_2U(SCH_1):PAGE133',
 PHYS_PAGE='131',
 XY='(1750,2525)',
 ROT='0',
 VER='2',
 PACK_TYPE='0402LF',
 CDS_LIB='pure_quanta',
 CDS_PART_NAME='Q_RES_0402LF-1K,1%,1/16W,CHIP,A',
 WATTAGE='1/16W',
 TOLERANCE='1%',
 MATERIAL='CHIP',
 VALUE='1K',
 PRIM_FILE='./archive_libs/logical/q_res/chips/chips.prt';

PART_NAME
 R779 'Q_RES_0402LF-150,1%,1/16W,CHIPA':;

SECTION_NUMBER 1
 '@S9S_MB_2U_LIB.S9S_MB_2U(SCH_1):PAGE133_I95@PURE_QUANTA.Q_RES(CHIPS)':
 C_PATH='@s9s_mb_2u_lib.s9s_mb_2u(sch_1):page133_i95@pure_quanta.q_res(chips)',
 P_PATH='@s9s_mb_2u_lib.s9s_mb_2u(sch_1):page131_i95@pure_quanta.q_res(chips)',
 PATH='I95',
 DRAWING='@S9S_MB_2U_LIB.S9S_MB_2U(SCH_1):PAGE133',
 PHYS_PAGE='131',
 XY='(2200,2525)',
 ROT='0',
 VER='2',
 PACK_TYPE='0402LF',
 CDS_LIB='pure_quanta',
 CDS_PART_NAME='Q_RES_0402LF-150,1%,1/16W,CHIPA',
 WATTAGE='1/16W',
 TOLERANCE='1%',
 MATERIAL='CHIP',
 VALUE='150',
 PRIM_FILE='./archive_libs/logical/q_res/chips/chips.prt';

PART_NAME
 R780 'Q_RES_0402LF-49.9,1%,1/16W,CHIA':;

SECTION_NUMBER 1
 '@S9S_MB_2U_LIB.S9S_MB_2U(SCH_1):PAGE133_I92@PURE_QUANTA.Q_RES(CHIPS)':
 C_PATH='@s9s_mb_2u_lib.s9s_mb_2u(sch_1):page133_i92@pure_quanta.q_res(chips)',
 P_PATH='@s9s_mb_2u_lib.s9s_mb_2u(sch_1):page131_i92@pure_quanta.q_res(chips)',
 PATH='I92',
 DRAWING='@S9S_MB_2U_LIB.S9S_MB_2U(SCH_1):PAGE133',
 PHYS_PAGE='131',
 XY='(2500,2225)',
 ROT='0',
 VER='1',
 PACK_TYPE='0402LF',
 CDS_LIB='pure_quanta',
 CDS_PART_NAME='Q_RES_0402LF-49.9,1%,1/16W,CHIA',
 WATTAGE='1/16W',
 TOLERANCE='1%',
 MATERIAL='CHIP',
 VALUE='49.9',
 PRIM_FILE='./archive_libs/logical/q_res/chips/chips.prt';

PART_NAME
 R803 'Q_RES_0402LF-33.2,1%,1/16W,CHIA':;

SECTION_NUMBER 1
 '@S9S_MB_2U_LIB.S9S_MB_2U(SCH_1):PAGE210_I19@PURE_QUANTA.Q_RES(CHIPS)':
 C_PATH='@s9s_mb_2u_lib.s9s_mb_2u(sch_1):page210_i19@pure_quanta.q_res(chips)',
 P_PATH='@s9s_mb_2u_lib.s9s_mb_2u(sch_1):page221_i19@pure_quanta.q_res(chips)',
 PATH='I19',
 DRAWING='@S9S_MB_2U_LIB.S9S_MB_2U(SCH_1):PAGE210',
 PHYS_PAGE='221',
 XY='(-2125,3850)',
 ROT='0',
 VER='1',
 PACK_TYPE='0402LF',
 CDS_LIB='pure_quanta',
 CDS_PART_NAME='Q_RES_0402LF-33.2,1%,1/16W,CHIA',
 WATTAGE='1/16W',
 TOLERANCE='1%',
 MATERIAL='CHIP',
 VALUE='33.2',
 PRIM_FILE='./archive_libs/logical/q_res/chips/chips.prt';

PART_NAME
 R804 'Q_RES_0402LF-33.2,1%,1/16W,CHIA':;

SECTION_NUMBER 1
 '@S9S_MB_2U_LIB.S9S_MB_2U(SCH_1):PAGE210_I20@PURE_QUANTA.Q_RES(CHIPS)':
 C_PATH='@s9s_mb_2u_lib.s9s_mb_2u(sch_1):page210_i20@pure_quanta.q_res(chips)',
 P_PATH='@s9s_mb_2u_lib.s9s_mb_2u(sch_1):page221_i20@pure_quanta.q_res(chips)',
 PATH='I20',
 DRAWING='@S9S_MB_2U_LIB.S9S_MB_2U(SCH_1):PAGE210',
 PHYS_PAGE='221',
 XY='(-2125,3525)',
 ROT='0',
 VER='1',
 PACK_TYPE='0402LF',
 CDS_LIB='pure_quanta',
 CDS_PART_NAME='Q_RES_0402LF-33.2,1%,1/16W,CHIA',
 WATTAGE='1/16W',
 TOLERANCE='1%',
 MATERIAL='CHIP',
 VALUE='33.2',
 PRIM_FILE='./archive_libs/logical/q_res/chips/chips.prt';

PART_NAME
 R805 'Q_RES_0402LF-33.2,1%,1/16W,CHIA':;

SECTION_NUMBER 1
 '@S9S_MB_2U_LIB.S9S_MB_2U(SCH_1):PAGE210_I25@PURE_QUANTA.Q_RES(CHIPS)':
 C_PATH='@s9s_mb_2u_lib.s9s_mb_2u(sch_1):page210_i25@pure_quanta.q_res(chips)',
 P_PATH='@s9s_mb_2u_lib.s9s_mb_2u(sch_1):page221_i25@pure_quanta.q_res(chips)',
 PATH='I25',
 DRAWING='@S9S_MB_2U_LIB.S9S_MB_2U(SCH_1):PAGE210',
 PHYS_PAGE='221',
 XY='(-2125,3200)',
 ROT='0',
 VER='1',
 PACK_TYPE='0402LF',
 CDS_LIB='pure_quanta',
 CDS_PART_NAME='Q_RES_0402LF-33.2,1%,1/16W,CHIA',
 WATTAGE='1/16W',
 TOLERANCE='1%',
 MATERIAL='CHIP',
 VALUE='33.2',
 PRIM_FILE='./archive_libs/logical/q_res/chips/chips.prt';

PART_NAME
 R806 'Q_RES_0402LF-33.2,1%,1/16W,CHIA':;

SECTION_NUMBER 1
 '@S9S_MB_2U_LIB.S9S_MB_2U(SCH_1):PAGE210_I54@PURE_QUANTA.Q_RES(CHIPS)':
 C_PATH='@s9s_mb_2u_lib.s9s_mb_2u(sch_1):page210_i54@pure_quanta.q_res(chips)',
 P_PATH='@s9s_mb_2u_lib.s9s_mb_2u(sch_1):page221_i54@pure_quanta.q_res(chips)',
 PATH='I54',
 DRAWING='@S9S_MB_2U_LIB.S9S_MB_2U(SCH_1):PAGE210',
 PHYS_PAGE='221',
 XY='(-2125,2875)',
 ROT='0',
 VER='1',
 PACK_TYPE='0402LF',
 CDS_LIB='pure_quanta',
 CDS_PART_NAME='Q_RES_0402LF-33.2,1%,1/16W,CHIA',
 WATTAGE='1/16W',
 TOLERANCE='1%',
 MATERIAL='CHIP',
 VALUE='33.2',
 PRIM_FILE='./archive_libs/logical/q_res/chips/chips.prt';

PART_NAME
 R815 'Q_RES_0402LF-0,5%,1/16W,CHIP,CA':;

SECTION_NUMBER 1
 '@S9S_MB_2U_LIB.S9S_MB_2U(SCH_1):PAGE130_I11@PURE_QUANTA.Q_RES(CHIPS)':
 C_PATH='@s9s_mb_2u_lib.s9s_mb_2u(sch_1):page130_i11@pure_quanta.q_res(chips)',
 P_PATH='@s9s_mb_2u_lib.s9s_mb_2u(sch_1):page130_i11@pure_quanta.q_res(chips)',
 PATH='I11',
 DRAWING='@S9S_MB_2U_LIB.S9S_MB_2U(SCH_1):PAGE130',
 PHYS_PAGE='130',
 XY='(-5200,-350)',
 ROT='0',
 VER='1',
 PACK_TYPE='0402LF',
 CDS_LIB='pure_quanta',
 CDS_PART_NAME='Q_RES_0402LF-0,5%,1/16W,CHIP,CA',
 WATTAGE='1/16W',
 TOLERANCE='5%',
 MATERIAL='CHIP',
 VALUE='0',
 PRIM_FILE='./archive_libs/logical/q_res/chips/chips.prt';

PART_NAME
 R816 'Q_RES_0402LF-0,5%,1/16W,CHIP,CA':;

SECTION_NUMBER 1
 '@S9S_MB_2U_LIB.S9S_MB_2U(SCH_1):PAGE130_I37@PURE_QUANTA.Q_RES(CHIPS)':
 C_PATH='@s9s_mb_2u_lib.s9s_mb_2u(sch_1):page130_i37@pure_quanta.q_res(chips)',
 P_PATH='@s9s_mb_2u_lib.s9s_mb_2u(sch_1):page130_i37@pure_quanta.q_res(chips)',
 PATH='I37',
 DRAWING='@S9S_MB_2U_LIB.S9S_MB_2U(SCH_1):PAGE130',
 PHYS_PAGE='130',
 XY='(-5175,4200)',
 ROT='0',
 VER='1',
 PACK_TYPE='0402LF',
 CDS_LIB='pure_quanta',
 CDS_PART_NAME='Q_RES_0402LF-0,5%,1/16W,CHIP,CA',
 WATTAGE='1/16W',
 TOLERANCE='5%',
 MATERIAL='CHIP',
 VALUE='0',
 PRIM_FILE='./archive_libs/logical/q_res/chips/chips.prt';

PART_NAME
 R817 'Q_RES_0402LF-0,5%,1/16W,CHIP,CA':;

SECTION_NUMBER 1
 '@S9S_MB_2U_LIB.S9S_MB_2U(SCH_1):PAGE130_I26@PURE_QUANTA.Q_RES(CHIPS)':
 C_PATH='@s9s_mb_2u_lib.s9s_mb_2u(sch_1):page130_i26@pure_quanta.q_res(chips)',
 P_PATH='@s9s_mb_2u_lib.s9s_mb_2u(sch_1):page130_i26@pure_quanta.q_res(chips)',
 PATH='I26',
 DRAWING='@S9S_MB_2U_LIB.S9S_MB_2U(SCH_1):PAGE130',
 PHYS_PAGE='130',
 XY='(-5175,2675)',
 ROT='0',
 VER='1',
 PACK_TYPE='0402LF',
 CDS_LIB='pure_quanta',
 CDS_PART_NAME='Q_RES_0402LF-0,5%,1/16W,CHIP,CA',
 WATTAGE='1/16W',
 TOLERANCE='5%',
 MATERIAL='CHIP',
 VALUE='0',
 PRIM_FILE='./archive_libs/logical/q_res/chips/chips.prt';

PART_NAME
 R818 'Q_RES_0402LF-0,5%,1/16W,CHIP,CA':;

SECTION_NUMBER 1
 '@S9S_MB_2U_LIB.S9S_MB_2U(SCH_1):PAGE130_I22@PURE_QUANTA.Q_RES(CHIPS)':
 C_PATH='@s9s_mb_2u_lib.s9s_mb_2u(sch_1):page130_i22@pure_quanta.q_res(chips)',
 P_PATH='@s9s_mb_2u_lib.s9s_mb_2u(sch_1):page130_i22@pure_quanta.q_res(chips)',
 PATH='I22',
 DRAWING='@S9S_MB_2U_LIB.S9S_MB_2U(SCH_1):PAGE130',
 PHYS_PAGE='130',
 XY='(-5175,1175)',
 ROT='0',
 VER='1',
 PACK_TYPE='0402LF',
 CDS_LIB='pure_quanta',
 CDS_PART_NAME='Q_RES_0402LF-0,5%,1/16W,CHIP,CA',
 WATTAGE='1/16W',
 TOLERANCE='5%',
 MATERIAL='CHIP',
 VALUE='0',
 PRIM_FILE='./archive_libs/logical/q_res/chips/chips.prt';

PART_NAME
 R819 'Q_RES_0402LF-1K,1%,1/16W,CHIP,A':;

SECTION_NUMBER 1
 '@S9S_MB_2U_LIB.S9S_MB_2U(SCH_1):PAGE130_I90@PURE_QUANTA.Q_RES(CHIPS)':
 C_PATH='@s9s_mb_2u_lib.s9s_mb_2u(sch_1):page130_i90@pure_quanta.q_res(chips)',
 P_PATH='@s9s_mb_2u_lib.s9s_mb_2u(sch_1):page130_i90@pure_quanta.q_res(chips)',
 PATH='I90',
 DRAWING='@S9S_MB_2U_LIB.S9S_MB_2U(SCH_1):PAGE130',
 PHYS_PAGE='130',
 XY='(-3200,-100)',
 ROT='0',
 VER='2',
 PACK_TYPE='0402LF',
 CDS_LIB='pure_quanta',
 CDS_PART_NAME='Q_RES_0402LF-1K,1%,1/16W,CHIP,A',
 WATTAGE='1/16W',
 TOLERANCE='1%',
 MATERIAL='CHIP',
 VALUE='1K',
 PRIM_FILE='./archive_libs/logical/q_res/chips/chips.prt';

PART_NAME
 R820 'Q_RES_0402LF-1K,1%,1/16W,CHIP,A':;

SECTION_NUMBER 1
 '@S9S_MB_2U_LIB.S9S_MB_2U(SCH_1):PAGE130_I82@PURE_QUANTA.Q_RES(CHIPS)':
 C_PATH='@s9s_mb_2u_lib.s9s_mb_2u(sch_1):page130_i82@pure_quanta.q_res(chips)',
 P_PATH='@s9s_mb_2u_lib.s9s_mb_2u(sch_1):page130_i82@pure_quanta.q_res(chips)',
 PATH='I82',
 DRAWING='@S9S_MB_2U_LIB.S9S_MB_2U(SCH_1):PAGE130',
 PHYS_PAGE='130',
 XY='(-3175,4450)',
 ROT='0',
 VER='2',
 PACK_TYPE='0402LF',
 CDS_LIB='pure_quanta',
 CDS_PART_NAME='Q_RES_0402LF-1K,1%,1/16W,CHIP,A',
 WATTAGE='1/16W',
 TOLERANCE='1%',
 MATERIAL='CHIP',
 VALUE='1K',
 PRIM_FILE='./archive_libs/logical/q_res/chips/chips.prt';

PART_NAME
 R821 'Q_RES_0402LF-1K,1%,1/16W,CHIP,A':;

SECTION_NUMBER 1
 '@S9S_MB_2U_LIB.S9S_MB_2U(SCH_1):PAGE130_I84@PURE_QUANTA.Q_RES(CHIPS)':
 C_PATH='@s9s_mb_2u_lib.s9s_mb_2u(sch_1):page130_i84@pure_quanta.q_res(chips)',
 P_PATH='@s9s_mb_2u_lib.s9s_mb_2u(sch_1):page130_i84@pure_quanta.q_res(chips)',
 PATH='I84',
 DRAWING='@S9S_MB_2U_LIB.S9S_MB_2U(SCH_1):PAGE130',
 PHYS_PAGE='130',
 XY='(-3175,2925)',
 ROT='0',
 VER='2',
 PACK_TYPE='0402LF',
 CDS_LIB='pure_quanta',
 CDS_PART_NAME='Q_RES_0402LF-1K,1%,1/16W,CHIP,A',
 WATTAGE='1/16W',
 TOLERANCE='1%',
 MATERIAL='CHIP',
 VALUE='1K',
 PRIM_FILE='./archive_libs/logical/q_res/chips/chips.prt';

PART_NAME
 R822 'Q_RES_0402LF-1K,1%,1/16W,CHIP,A':;

SECTION_NUMBER 1
 '@S9S_MB_2U_LIB.S9S_MB_2U(SCH_1):PAGE130_I88@PURE_QUANTA.Q_RES(CHIPS)':
 C_PATH='@s9s_mb_2u_lib.s9s_mb_2u(sch_1):page130_i88@pure_quanta.q_res(chips)',
 P_PATH='@s9s_mb_2u_lib.s9s_mb_2u(sch_1):page130_i88@pure_quanta.q_res(chips)',
 PATH='I88',
 DRAWING='@S9S_MB_2U_LIB.S9S_MB_2U(SCH_1):PAGE130',
 PHYS_PAGE='130',
 XY='(-3175,1425)',
 ROT='0',
 VER='2',
 PACK_TYPE='0402LF',
 CDS_LIB='pure_quanta',
 CDS_PART_NAME='Q_RES_0402LF-1K,1%,1/16W,CHIP,A',
 WATTAGE='1/16W',
 TOLERANCE='1%',
 MATERIAL='CHIP',
 VALUE='1K',
 PRIM_FILE='./archive_libs/logical/q_res/chips/chips.prt';

PART_NAME
 R835 'Q_RES_0402LF-0,5%,1/16W,CHIP,CA':;

SECTION_NUMBER 1
 '@S9S_MB_2U_LIB.S9S_MB_2U(SCH_1):PAGE129_I86@PURE_QUANTA.Q_RES(CHIPS)':
 C_PATH='@s9s_mb_2u_lib.s9s_mb_2u(sch_1):page129_i86@pure_quanta.q_res(chips)',
 P_PATH='@s9s_mb_2u_lib.s9s_mb_2u(sch_1):page129_i86@pure_quanta.q_res(chips)',
 PATH='I86',
 DRAWING='@S9S_MB_2U_LIB.S9S_MB_2U(SCH_1):PAGE129',
 PHYS_PAGE='129',
 XY='(-4900,900)',
 ROT='0',
 VER='1',
 PACK_TYPE='0402LF',
 CDS_LIB='pure_quanta',
 CDS_PART_NAME='Q_RES_0402LF-0,5%,1/16W,CHIP,CA',
 WATTAGE='1/16W',
 TOLERANCE='5%',
 MATERIAL='CHIP',
 VALUE='0',
 PRIM_FILE='./archive_libs/logical/q_res/chips/chips.prt';

PART_NAME
 R836 'Q_RES_0402LF-0,5%,1/16W,CHIP,CA':;

SECTION_NUMBER 1
 '@S9S_MB_2U_LIB.S9S_MB_2U(SCH_1):PAGE129_I26@PURE_QUANTA.Q_RES(CHIPS)':
 C_PATH='@s9s_mb_2u_lib.s9s_mb_2u(sch_1):page129_i26@pure_quanta.q_res(chips)',
 P_PATH='@s9s_mb_2u_lib.s9s_mb_2u(sch_1):page129_i26@pure_quanta.q_res(chips)',
 PATH='I26',
 DRAWING='@S9S_MB_2U_LIB.S9S_MB_2U(SCH_1):PAGE129',
 PHYS_PAGE='129',
 XY='(-4900,5450)',
 ROT='0',
 VER='1',
 PACK_TYPE='0402LF',
 CDS_LIB='pure_quanta',
 CDS_PART_NAME='Q_RES_0402LF-0,5%,1/16W,CHIP,CA',
 WATTAGE='1/16W',
 TOLERANCE='5%',
 MATERIAL='CHIP',
 VALUE='0',
 PRIM_FILE='./archive_libs/logical/q_res/chips/chips.prt';

PART_NAME
 R837 'Q_RES_0402LF-0,5%,1/16W,CHIP,CA':;

SECTION_NUMBER 1
 '@S9S_MB_2U_LIB.S9S_MB_2U(SCH_1):PAGE129_I59@PURE_QUANTA.Q_RES(CHIPS)':
 C_PATH='@s9s_mb_2u_lib.s9s_mb_2u(sch_1):page129_i59@pure_quanta.q_res(chips)',
 P_PATH='@s9s_mb_2u_lib.s9s_mb_2u(sch_1):page129_i59@pure_quanta.q_res(chips)',
 PATH='I59',
 DRAWING='@S9S_MB_2U_LIB.S9S_MB_2U(SCH_1):PAGE129',
 PHYS_PAGE='129',
 XY='(-4900,3925)',
 ROT='0',
 VER='1',
 PACK_TYPE='0402LF',
 CDS_LIB='pure_quanta',
 CDS_PART_NAME='Q_RES_0402LF-0,5%,1/16W,CHIP,CA',
 WATTAGE='1/16W',
 TOLERANCE='5%',
 MATERIAL='CHIP',
 VALUE='0',
 PRIM_FILE='./archive_libs/logical/q_res/chips/chips.prt';

PART_NAME
 R838 'Q_RES_0402LF-0,5%,1/16W,CHIP,CA':;

SECTION_NUMBER 1
 '@S9S_MB_2U_LIB.S9S_MB_2U(SCH_1):PAGE129_I76@PURE_QUANTA.Q_RES(CHIPS)':
 C_PATH='@s9s_mb_2u_lib.s9s_mb_2u(sch_1):page129_i76@pure_quanta.q_res(chips)',
 P_PATH='@s9s_mb_2u_lib.s9s_mb_2u(sch_1):page129_i76@pure_quanta.q_res(chips)',
 PATH='I76',
 DRAWING='@S9S_MB_2U_LIB.S9S_MB_2U(SCH_1):PAGE129',
 PHYS_PAGE='129',
 XY='(-4900,2425)',
 ROT='0',
 VER='1',
 PACK_TYPE='0402LF',
 CDS_LIB='pure_quanta',
 CDS_PART_NAME='Q_RES_0402LF-0,5%,1/16W,CHIP,CA',
 WATTAGE='1/16W',
 TOLERANCE='5%',
 MATERIAL='CHIP',
 VALUE='0',
 PRIM_FILE='./archive_libs/logical/q_res/chips/chips.prt';

PART_NAME
 R839 'Q_RES_0402LF-1K,1%,1/16W,CHIP,A':;

SECTION_NUMBER 1
 '@S9S_MB_2U_LIB.S9S_MB_2U(SCH_1):PAGE129_I125@PURE_QUANTA.Q_RES(CHIPS)':
 C_PATH='@s9s_mb_2u_lib.s9s_mb_2u(sch_1):page129_i125@pure_quanta.q_res(chips)',
 P_PATH='@s9s_mb_2u_lib.s9s_mb_2u(sch_1):page129_i125@pure_quanta.q_res(chips)',
 PATH='I125',
 DRAWING='@S9S_MB_2U_LIB.S9S_MB_2U(SCH_1):PAGE129',
 PHYS_PAGE='129',
 XY='(-2725,1225)',
 ROT='0',
 VER='2',
 PACK_TYPE='0402LF',
 CDS_LIB='pure_quanta',
 CDS_PART_NAME='Q_RES_0402LF-1K,1%,1/16W,CHIP,A',
 WATTAGE='1/16W',
 TOLERANCE='1%',
 MATERIAL='CHIP',
 VALUE='1K',
 PRIM_FILE='./archive_libs/logical/q_res/chips/chips.prt';

PART_NAME
 R840 'Q_RES_0402LF-1K,1%,1/16W,CHIP,A':;

SECTION_NUMBER 1
 '@S9S_MB_2U_LIB.S9S_MB_2U(SCH_1):PAGE129_I119@PURE_QUANTA.Q_RES(CHIPS)':
 C_PATH='@s9s_mb_2u_lib.s9s_mb_2u(sch_1):page129_i119@pure_quanta.q_res(chips)',
 P_PATH='@s9s_mb_2u_lib.s9s_mb_2u(sch_1):page129_i119@pure_quanta.q_res(chips)',
 PATH='I119',
 DRAWING='@S9S_MB_2U_LIB.S9S_MB_2U(SCH_1):PAGE129',
 PHYS_PAGE='129',
 XY='(-2725,5775)',
 ROT='0',
 VER='2',
 PACK_TYPE='0402LF',
 CDS_LIB='pure_quanta',
 CDS_PART_NAME='Q_RES_0402LF-1K,1%,1/16W,CHIP,A',
 WATTAGE='1/16W',
 TOLERANCE='1%',
 MATERIAL='CHIP',
 VALUE='1K',
 PRIM_FILE='./archive_libs/logical/q_res/chips/chips.prt';

PART_NAME
 R841 'Q_RES_0402LF-1K,1%,1/16W,CHIP,A':;

SECTION_NUMBER 1
 '@S9S_MB_2U_LIB.S9S_MB_2U(SCH_1):PAGE129_I121@PURE_QUANTA.Q_RES(CHIPS)':
 C_PATH='@s9s_mb_2u_lib.s9s_mb_2u(sch_1):page129_i121@pure_quanta.q_res(chips)',
 P_PATH='@s9s_mb_2u_lib.s9s_mb_2u(sch_1):page129_i121@pure_quanta.q_res(chips)',
 PATH='I121',
 DRAWING='@S9S_MB_2U_LIB.S9S_MB_2U(SCH_1):PAGE129',
 PHYS_PAGE='129',
 XY='(-2725,4250)',
 ROT='0',
 VER='2',
 PACK_TYPE='0402LF',
 CDS_LIB='pure_quanta',
 CDS_PART_NAME='Q_RES_0402LF-1K,1%,1/16W,CHIP,A',
 WATTAGE='1/16W',
 TOLERANCE='1%',
 MATERIAL='CHIP',
 VALUE='1K',
 PRIM_FILE='./archive_libs/logical/q_res/chips/chips.prt';

PART_NAME
 R842 'Q_RES_0402LF-1K,1%,1/16W,CHIP,A':;

SECTION_NUMBER 1
 '@S9S_MB_2U_LIB.S9S_MB_2U(SCH_1):PAGE129_I123@PURE_QUANTA.Q_RES(CHIPS)':
 C_PATH='@s9s_mb_2u_lib.s9s_mb_2u(sch_1):page129_i123@pure_quanta.q_res(chips)',
 P_PATH='@s9s_mb_2u_lib.s9s_mb_2u(sch_1):page129_i123@pure_quanta.q_res(chips)',
 PATH='I123',
 DRAWING='@S9S_MB_2U_LIB.S9S_MB_2U(SCH_1):PAGE129',
 PHYS_PAGE='129',
 XY='(-2725,2750)',
 ROT='0',
 VER='2',
 PACK_TYPE='0402LF',
 CDS_LIB='pure_quanta',
 CDS_PART_NAME='Q_RES_0402LF-1K,1%,1/16W,CHIP,A',
 WATTAGE='1/16W',
 TOLERANCE='1%',
 MATERIAL='CHIP',
 VALUE='1K',
 PRIM_FILE='./archive_libs/logical/q_res/chips/chips.prt';

PART_NAME
 R851 'Q_RES_0402LF-0,5%,1/16W,CHIP,CA':;

SECTION_NUMBER 1
 '@S9S_MB_2U_LIB.S9S_MB_2U(SCH_1):PAGE128_I12@PURE_QUANTA.Q_RES(CHIPS)':
 C_PATH='@s9s_mb_2u_lib.s9s_mb_2u(sch_1):page128_i12@pure_quanta.q_res(chips)',
 P_PATH='@s9s_mb_2u_lib.s9s_mb_2u(sch_1):page128_i12@pure_quanta.q_res(chips)',
 PATH='I12',
 DRAWING='@S9S_MB_2U_LIB.S9S_MB_2U(SCH_1):PAGE128',
 PHYS_PAGE='128',
 XY='(-5325,3425)',
 ROT='0',
 VER='1',
 PACK_TYPE='0402LF',
 CDS_LIB='pure_quanta',
 CDS_PART_NAME='Q_RES_0402LF-0,5%,1/16W,CHIP,CA',
 WATTAGE='1/16W',
 TOLERANCE='5%',
 MATERIAL='CHIP',
 VALUE='0',
 PRIM_FILE='./archive_libs/logical/q_res/chips/chips.prt';

PART_NAME
 R852 'Q_RES_0402LF-0,5%,1/16W,CHIP,CA':;

SECTION_NUMBER 1
 '@S9S_MB_2U_LIB.S9S_MB_2U(SCH_1):PAGE128_I11@PURE_QUANTA.Q_RES(CHIPS)':
 C_PATH='@s9s_mb_2u_lib.s9s_mb_2u(sch_1):page128_i11@pure_quanta.q_res(chips)',
 P_PATH='@s9s_mb_2u_lib.s9s_mb_2u(sch_1):page128_i11@pure_quanta.q_res(chips)',
 PATH='I11',
 DRAWING='@S9S_MB_2U_LIB.S9S_MB_2U(SCH_1):PAGE128',
 PHYS_PAGE='128',
 XY='(-5325,3375)',
 ROT='0',
 VER='1',
 PACK_TYPE='0402LF',
 CDS_LIB='pure_quanta',
 CDS_PART_NAME='Q_RES_0402LF-0,5%,1/16W,CHIP,CA',
 WATTAGE='1/16W',
 TOLERANCE='5%',
 MATERIAL='CHIP',
 VALUE='0',
 PRIM_FILE='./archive_libs/logical/q_res/chips/chips.prt';

PART_NAME
 R853 'Q_RES_0402LF-0,5%,1/16W,CHIP,CA':;

SECTION_NUMBER 1
 '@S9S_MB_2U_LIB.S9S_MB_2U(SCH_1):PAGE128_I10@PURE_QUANTA.Q_RES(CHIPS)':
 C_PATH='@s9s_mb_2u_lib.s9s_mb_2u(sch_1):page128_i10@pure_quanta.q_res(chips)',
 P_PATH='@s9s_mb_2u_lib.s9s_mb_2u(sch_1):page128_i10@pure_quanta.q_res(chips)',
 PATH='I10',
 DRAWING='@S9S_MB_2U_LIB.S9S_MB_2U(SCH_1):PAGE128',
 PHYS_PAGE='128',
 XY='(-5325,3325)',
 ROT='0',
 VER='1',
 PACK_TYPE='0402LF',
 CDS_LIB='pure_quanta',
 CDS_PART_NAME='Q_RES_0402LF-0,5%,1/16W,CHIP,CA',
 WATTAGE='1/16W',
 TOLERANCE='5%',
 MATERIAL='CHIP',
 VALUE='0',
 PRIM_FILE='./archive_libs/logical/q_res/chips/chips.prt';

PART_NAME
 R854 'Q_RES_0402LF-0,5%,1/16W,CHIP,CA':;

SECTION_NUMBER 1
 '@S9S_MB_2U_LIB.S9S_MB_2U(SCH_1):PAGE128_I9@PURE_QUANTA.Q_RES(CHIPS)':
 C_PATH='@s9s_mb_2u_lib.s9s_mb_2u(sch_1):page128_i9@pure_quanta.q_res(chips)',
 P_PATH='@s9s_mb_2u_lib.s9s_mb_2u(sch_1):page128_i9@pure_quanta.q_res(chips)',
 PATH='I9',
 DRAWING='@S9S_MB_2U_LIB.S9S_MB_2U(SCH_1):PAGE128',
 PHYS_PAGE='128',
 XY='(-5325,3275)',
 ROT='0',
 VER='1',
 PACK_TYPE='0402LF',
 CDS_LIB='pure_quanta',
 CDS_PART_NAME='Q_RES_0402LF-0,5%,1/16W,CHIP,CA',
 WATTAGE='1/16W',
 TOLERANCE='5%',
 MATERIAL='CHIP',
 VALUE='0',
 PRIM_FILE='./archive_libs/logical/q_res/chips/chips.prt';

PART_NAME
 R859 'Q_RES_0402LF-0,5%,1/16W,CHIP,CA':;

SECTION_NUMBER 1
 '@S9S_MB_2U_LIB.S9S_MB_2U(SCH_1):PAGE128_I50@PURE_QUANTA.Q_RES(CHIPS)':
 C_PATH='@s9s_mb_2u_lib.s9s_mb_2u(sch_1):page128_i50@pure_quanta.q_res(chips)',
 P_PATH='@s9s_mb_2u_lib.s9s_mb_2u(sch_1):page128_i50@pure_quanta.q_res(chips)',
 PATH='I50',
 DRAWING='@S9S_MB_2U_LIB.S9S_MB_2U(SCH_1):PAGE128',
 PHYS_PAGE='128',
 XY='(-5325,525)',
 ROT='0',
 VER='1',
 PACK_TYPE='0402LF',
 CDS_LIB='pure_quanta',
 CDS_PART_NAME='Q_RES_0402LF-0,5%,1/16W,CHIP,CA',
 WATTAGE='1/16W',
 TOLERANCE='5%',
 MATERIAL='CHIP',
 VALUE='0',
 PRIM_FILE='./archive_libs/logical/q_res/chips/chips.prt';

PART_NAME
 R860 'Q_RES_0402LF-0,5%,1/16W,CHIP,CA':;

SECTION_NUMBER 1
 '@S9S_MB_2U_LIB.S9S_MB_2U(SCH_1):PAGE128_I51@PURE_QUANTA.Q_RES(CHIPS)':
 C_PATH='@s9s_mb_2u_lib.s9s_mb_2u(sch_1):page128_i51@pure_quanta.q_res(chips)',
 P_PATH='@s9s_mb_2u_lib.s9s_mb_2u(sch_1):page128_i51@pure_quanta.q_res(chips)',
 PATH='I51',
 DRAWING='@S9S_MB_2U_LIB.S9S_MB_2U(SCH_1):PAGE128',
 PHYS_PAGE='128',
 XY='(-5325,475)',
 ROT='0',
 VER='1',
 PACK_TYPE='0402LF',
 CDS_LIB='pure_quanta',
 CDS_PART_NAME='Q_RES_0402LF-0,5%,1/16W,CHIP,CA',
 WATTAGE='1/16W',
 TOLERANCE='5%',
 MATERIAL='CHIP',
 VALUE='0',
 PRIM_FILE='./archive_libs/logical/q_res/chips/chips.prt';

PART_NAME
 R861 'Q_RES_0402LF-0,5%,1/16W,CHIP,CA':;

SECTION_NUMBER 1
 '@S9S_MB_2U_LIB.S9S_MB_2U(SCH_1):PAGE128_I48@PURE_QUANTA.Q_RES(CHIPS)':
 C_PATH='@s9s_mb_2u_lib.s9s_mb_2u(sch_1):page128_i48@pure_quanta.q_res(chips)',
 P_PATH='@s9s_mb_2u_lib.s9s_mb_2u(sch_1):page128_i48@pure_quanta.q_res(chips)',
 PATH='I48',
 DRAWING='@S9S_MB_2U_LIB.S9S_MB_2U(SCH_1):PAGE128',
 PHYS_PAGE='128',
 XY='(-5325,425)',
 ROT='0',
 VER='1',
 PACK_TYPE='0402LF',
 CDS_LIB='pure_quanta',
 CDS_PART_NAME='Q_RES_0402LF-0,5%,1/16W,CHIP,CA',
 WATTAGE='1/16W',
 TOLERANCE='5%',
 MATERIAL='CHIP',
 VALUE='0',
 PRIM_FILE='./archive_libs/logical/q_res/chips/chips.prt';

PART_NAME
 R880 'Q_RES_0402LF-33.2,1%,1/16W,CHIA':;

SECTION_NUMBER 1
 '@S9S_MB_2U_LIB.S9S_MB_2U(SCH_1):PAGE114_I29@PURE_QUANTA.Q_RES(CHIPS)':
 C_PATH='@s9s_mb_2u_lib.s9s_mb_2u(sch_1):page114_i29@pure_quanta.q_res(chips)',
 P_PATH='@s9s_mb_2u_lib.s9s_mb_2u(sch_1):page114_i29@pure_quanta.q_res(chips)',
 PATH='I29',
 DRAWING='@S9S_MB_2U_LIB.S9S_MB_2U(SCH_1):PAGE114',
 PHYS_PAGE='114',
 XY='(-9375,6225)',
 ROT='0',
 VER='1',
 PACK_TYPE='0402LF',
 CDS_LIB='pure_quanta',
 CDS_PART_NAME='Q_RES_0402LF-33.2,1%,1/16W,CHIA',
 WATTAGE='1/16W',
 TOLERANCE='1%',
 MATERIAL='CHIP',
 VALUE='33.2',
 PRIM_FILE='./archive_libs/logical/q_res/chips/chips.prt';

PART_NAME
 R884 'Q_RES_0402LF-33.2,1%,1/16W,CHIA':;

SECTION_NUMBER 1
 '@S9S_MB_2U_LIB.S9S_MB_2U(SCH_1):PAGE114_I26@PURE_QUANTA.Q_RES(CHIPS)':
 C_PATH='@s9s_mb_2u_lib.s9s_mb_2u(sch_1):page114_i26@pure_quanta.q_res(chips)',
 P_PATH='@s9s_mb_2u_lib.s9s_mb_2u(sch_1):page114_i26@pure_quanta.q_res(chips)',
 PATH='I26',
 DRAWING='@S9S_MB_2U_LIB.S9S_MB_2U(SCH_1):PAGE114',
 PHYS_PAGE='114',
 XY='(-9375,5675)',
 ROT='0',
 VER='1',
 PACK_TYPE='0402LF',
 CDS_LIB='pure_quanta',
 CDS_PART_NAME='Q_RES_0402LF-33.2,1%,1/16W,CHIA',
 WATTAGE='1/16W',
 TOLERANCE='1%',
 MATERIAL='CHIP',
 VALUE='33.2',
 PRIM_FILE='./archive_libs/logical/q_res/chips/chips.prt';

PART_NAME
 R885 'Q_RES_0402LF-33.2,1%,1/16W,CHIA':;

SECTION_NUMBER 1
 '@S9S_MB_2U_LIB.S9S_MB_2U(SCH_1):PAGE114_I24@PURE_QUANTA.Q_RES(CHIPS)':
 C_PATH='@s9s_mb_2u_lib.s9s_mb_2u(sch_1):page114_i24@pure_quanta.q_res(chips)',
 P_PATH='@s9s_mb_2u_lib.s9s_mb_2u(sch_1):page114_i24@pure_quanta.q_res(chips)',
 PATH='I24',
 DRAWING='@S9S_MB_2U_LIB.S9S_MB_2U(SCH_1):PAGE114',
 PHYS_PAGE='114',
 XY='(-9375,5400)',
 ROT='0',
 VER='1',
 PACK_TYPE='0402LF',
 CDS_LIB='pure_quanta',
 CDS_PART_NAME='Q_RES_0402LF-33.2,1%,1/16W,CHIA',
 WATTAGE='1/16W',
 TOLERANCE='1%',
 MATERIAL='CHIP',
 VALUE='33.2',
 PRIM_FILE='./archive_libs/logical/q_res/chips/chips.prt';

PART_NAME
 R886 'Q_RES_0402LF-33.2,1%,1/16W,CHIA':;

SECTION_NUMBER 1
 '@S9S_MB_2U_LIB.S9S_MB_2U(SCH_1):PAGE114_I23@PURE_QUANTA.Q_RES(CHIPS)':
 C_PATH='@s9s_mb_2u_lib.s9s_mb_2u(sch_1):page114_i23@pure_quanta.q_res(chips)',
 P_PATH='@s9s_mb_2u_lib.s9s_mb_2u(sch_1):page114_i23@pure_quanta.q_res(chips)',
 PATH='I23',
 DRAWING='@S9S_MB_2U_LIB.S9S_MB_2U(SCH_1):PAGE114',
 PHYS_PAGE='114',
 XY='(-9375,5350)',
 ROT='0',
 VER='1',
 PACK_TYPE='0402LF',
 CDS_LIB='pure_quanta',
 CDS_PART_NAME='Q_RES_0402LF-33.2,1%,1/16W,CHIA',
 WATTAGE='1/16W',
 TOLERANCE='1%',
 MATERIAL='CHIP',
 VALUE='33.2',
 PRIM_FILE='./archive_libs/logical/q_res/chips/chips.prt';

PART_NAME
 R889 'Q_RES_0402LF-33.2,1%,1/16W,CHIA':;

SECTION_NUMBER 1
 '@S9S_MB_2U_LIB.S9S_MB_2U(SCH_1):PAGE114_I20@PURE_QUANTA.Q_RES(CHIPS)':
 C_PATH='@s9s_mb_2u_lib.s9s_mb_2u(sch_1):page114_i20@pure_quanta.q_res(chips)',
 P_PATH='@s9s_mb_2u_lib.s9s_mb_2u(sch_1):page114_i20@pure_quanta.q_res(chips)',
 PATH='I20',
 DRAWING='@S9S_MB_2U_LIB.S9S_MB_2U(SCH_1):PAGE114',
 PHYS_PAGE='114',
 XY='(-9375,4850)',
 ROT='0',
 VER='1',
 PACK_TYPE='0402LF',
 CDS_LIB='pure_quanta',
 CDS_PART_NAME='Q_RES_0402LF-33.2,1%,1/16W,CHIA',
 WATTAGE='1/16W',
 TOLERANCE='1%',
 MATERIAL='CHIP',
 VALUE='33.2',
 PRIM_FILE='./archive_libs/logical/q_res/chips/chips.prt';

PART_NAME
 R890 'Q_RES_0402LF-33.2,1%,1/16W,CHIA':;

SECTION_NUMBER 1
 '@S9S_MB_2U_LIB.S9S_MB_2U(SCH_1):PAGE114_I19@PURE_QUANTA.Q_RES(CHIPS)':
 C_PATH='@s9s_mb_2u_lib.s9s_mb_2u(sch_1):page114_i19@pure_quanta.q_res(chips)',
 P_PATH='@s9s_mb_2u_lib.s9s_mb_2u(sch_1):page114_i19@pure_quanta.q_res(chips)',
 PATH='I19',
 DRAWING='@S9S_MB_2U_LIB.S9S_MB_2U(SCH_1):PAGE114',
 PHYS_PAGE='114',
 XY='(-9375,4800)',
 ROT='0',
 VER='1',
 PACK_TYPE='0402LF',
 CDS_LIB='pure_quanta',
 CDS_PART_NAME='Q_RES_0402LF-33.2,1%,1/16W,CHIA',
 WATTAGE='1/16W',
 TOLERANCE='1%',
 MATERIAL='CHIP',
 VALUE='33.2',
 PRIM_FILE='./archive_libs/logical/q_res/chips/chips.prt';

PART_NAME
 R893 'Q_RES_0402LF-33.2,1%,1/16W,CHIA':;

SECTION_NUMBER 1
 '@S9S_MB_2U_LIB.S9S_MB_2U(SCH_1):PAGE114_I79@PURE_QUANTA.Q_RES(CHIPS)':
 C_PATH='@s9s_mb_2u_lib.s9s_mb_2u(sch_1):page114_i79@pure_quanta.q_res(chips)',
 P_PATH='@s9s_mb_2u_lib.s9s_mb_2u(sch_1):page114_i79@pure_quanta.q_res(chips)',
 PATH='I79',
 DRAWING='@S9S_MB_2U_LIB.S9S_MB_2U(SCH_1):PAGE114',
 PHYS_PAGE='114',
 XY='(-5700,6500)',
 ROT='0',
 VER='1',
 PACK_TYPE='0402LF',
 CDS_LIB='pure_quanta',
 CDS_PART_NAME='Q_RES_0402LF-33.2,1%,1/16W,CHIA',
 WATTAGE='1/16W',
 TOLERANCE='1%',
 MATERIAL='CHIP',
 VALUE='33.2',
 PRIM_FILE='./archive_libs/logical/q_res/chips/chips.prt';

PART_NAME
 R894 'Q_RES_0402LF-33.2,1%,1/16W,CHIA':;

SECTION_NUMBER 1
 '@S9S_MB_2U_LIB.S9S_MB_2U(SCH_1):PAGE114_I78@PURE_QUANTA.Q_RES(CHIPS)':
 C_PATH='@s9s_mb_2u_lib.s9s_mb_2u(sch_1):page114_i78@pure_quanta.q_res(chips)',
 P_PATH='@s9s_mb_2u_lib.s9s_mb_2u(sch_1):page114_i78@pure_quanta.q_res(chips)',
 PATH='I78',
 DRAWING='@S9S_MB_2U_LIB.S9S_MB_2U(SCH_1):PAGE114',
 PHYS_PAGE='114',
 XY='(-5700,6450)',
 ROT='0',
 VER='1',
 PACK_TYPE='0402LF',
 CDS_LIB='pure_quanta',
 CDS_PART_NAME='Q_RES_0402LF-33.2,1%,1/16W,CHIA',
 WATTAGE='1/16W',
 TOLERANCE='1%',
 MATERIAL='CHIP',
 VALUE='33.2',
 PRIM_FILE='./archive_libs/logical/q_res/chips/chips.prt';

PART_NAME
 R895 'Q_RES_0402LF-33.2,1%,1/16W,CHIA':;

SECTION_NUMBER 1
 '@S9S_MB_2U_LIB.S9S_MB_2U(SCH_1):PAGE114_I77@PURE_QUANTA.Q_RES(CHIPS)':
 C_PATH='@s9s_mb_2u_lib.s9s_mb_2u(sch_1):page114_i77@pure_quanta.q_res(chips)',
 P_PATH='@s9s_mb_2u_lib.s9s_mb_2u(sch_1):page114_i77@pure_quanta.q_res(chips)',
 PATH='I77',
 DRAWING='@S9S_MB_2U_LIB.S9S_MB_2U(SCH_1):PAGE114',
 PHYS_PAGE='114',
 XY='(-5700,6275)',
 ROT='0',
 VER='1',
 PACK_TYPE='0402LF',
 CDS_LIB='pure_quanta',
 CDS_PART_NAME='Q_RES_0402LF-33.2,1%,1/16W,CHIA',
 WATTAGE='1/16W',
 TOLERANCE='1%',
 MATERIAL='CHIP',
 VALUE='33.2',
 PRIM_FILE='./archive_libs/logical/q_res/chips/chips.prt';

PART_NAME
 R896 'Q_RES_0402LF-33.2,1%,1/16W,CHIA':;

SECTION_NUMBER 1
 '@S9S_MB_2U_LIB.S9S_MB_2U(SCH_1):PAGE114_I69@PURE_QUANTA.Q_RES(CHIPS)':
 C_PATH='@s9s_mb_2u_lib.s9s_mb_2u(sch_1):page114_i69@pure_quanta.q_res(chips)',
 P_PATH='@s9s_mb_2u_lib.s9s_mb_2u(sch_1):page114_i69@pure_quanta.q_res(chips)',
 PATH='I69',
 DRAWING='@S9S_MB_2U_LIB.S9S_MB_2U(SCH_1):PAGE114',
 PHYS_PAGE='114',
 XY='(-5700,6225)',
 ROT='0',
 VER='1',
 PACK_TYPE='0402LF',
 CDS_LIB='pure_quanta',
 CDS_PART_NAME='Q_RES_0402LF-33.2,1%,1/16W,CHIA',
 WATTAGE='1/16W',
 TOLERANCE='1%',
 MATERIAL='CHIP',
 VALUE='33.2',
 PRIM_FILE='./archive_libs/logical/q_res/chips/chips.prt';

PART_NAME
 R897 'Q_RES_0402LF-33.2,1%,1/16W,CHIA':;

SECTION_NUMBER 1
 '@S9S_MB_2U_LIB.S9S_MB_2U(SCH_1):PAGE114_I67@PURE_QUANTA.Q_RES(CHIPS)':
 C_PATH='@s9s_mb_2u_lib.s9s_mb_2u(sch_1):page114_i67@pure_quanta.q_res(chips)',
 P_PATH='@s9s_mb_2u_lib.s9s_mb_2u(sch_1):page114_i67@pure_quanta.q_res(chips)',
 PATH='I67',
 DRAWING='@S9S_MB_2U_LIB.S9S_MB_2U(SCH_1):PAGE114',
 PHYS_PAGE='114',
 XY='(-5700,5950)',
 ROT='0',
 VER='1',
 PACK_TYPE='0402LF',
 CDS_LIB='pure_quanta',
 CDS_PART_NAME='Q_RES_0402LF-33.2,1%,1/16W,CHIA',
 WATTAGE='1/16W',
 TOLERANCE='1%',
 MATERIAL='CHIP',
 VALUE='33.2',
 PRIM_FILE='./archive_libs/logical/q_res/chips/chips.prt';

PART_NAME
 R898 'Q_RES_0402LF-33.2,1%,1/16W,CHIA':;

SECTION_NUMBER 1
 '@S9S_MB_2U_LIB.S9S_MB_2U(SCH_1):PAGE114_I68@PURE_QUANTA.Q_RES(CHIPS)':
 C_PATH='@s9s_mb_2u_lib.s9s_mb_2u(sch_1):page114_i68@pure_quanta.q_res(chips)',
 P_PATH='@s9s_mb_2u_lib.s9s_mb_2u(sch_1):page114_i68@pure_quanta.q_res(chips)',
 PATH='I68',
 DRAWING='@S9S_MB_2U_LIB.S9S_MB_2U(SCH_1):PAGE114',
 PHYS_PAGE='114',
 XY='(-5700,5900)',
 ROT='0',
 VER='1',
 PACK_TYPE='0402LF',
 CDS_LIB='pure_quanta',
 CDS_PART_NAME='Q_RES_0402LF-33.2,1%,1/16W,CHIA',
 WATTAGE='1/16W',
 TOLERANCE='1%',
 MATERIAL='CHIP',
 VALUE='33.2',
 PRIM_FILE='./archive_libs/logical/q_res/chips/chips.prt';

PART_NAME
 R899 'Q_RES_0402LF-33.2,1%,1/16W,CHIA':;

SECTION_NUMBER 1
 '@S9S_MB_2U_LIB.S9S_MB_2U(SCH_1):PAGE114_I65@PURE_QUANTA.Q_RES(CHIPS)':
 C_PATH='@s9s_mb_2u_lib.s9s_mb_2u(sch_1):page114_i65@pure_quanta.q_res(chips)',
 P_PATH='@s9s_mb_2u_lib.s9s_mb_2u(sch_1):page114_i65@pure_quanta.q_res(chips)',
 PATH='I65',
 DRAWING='@S9S_MB_2U_LIB.S9S_MB_2U(SCH_1):PAGE114',
 PHYS_PAGE='114',
 XY='(-5700,5725)',
 ROT='0',
 VER='1',
 PACK_TYPE='0402LF',
 CDS_LIB='pure_quanta',
 CDS_PART_NAME='Q_RES_0402LF-33.2,1%,1/16W,CHIA',
 WATTAGE='1/16W',
 TOLERANCE='1%',
 MATERIAL='CHIP',
 VALUE='33.2',
 PRIM_FILE='./archive_libs/logical/q_res/chips/chips.prt';

PART_NAME
 R900 'Q_RES_0402LF-33.2,1%,1/16W,CHIA':;

SECTION_NUMBER 1
 '@S9S_MB_2U_LIB.S9S_MB_2U(SCH_1):PAGE114_I66@PURE_QUANTA.Q_RES(CHIPS)':
 C_PATH='@s9s_mb_2u_lib.s9s_mb_2u(sch_1):page114_i66@pure_quanta.q_res(chips)',
 P_PATH='@s9s_mb_2u_lib.s9s_mb_2u(sch_1):page114_i66@pure_quanta.q_res(chips)',
 PATH='I66',
 DRAWING='@S9S_MB_2U_LIB.S9S_MB_2U(SCH_1):PAGE114',
 PHYS_PAGE='114',
 XY='(-5700,5675)',
 ROT='0',
 VER='1',
 PACK_TYPE='0402LF',
 CDS_LIB='pure_quanta',
 CDS_PART_NAME='Q_RES_0402LF-33.2,1%,1/16W,CHIA',
 WATTAGE='1/16W',
 TOLERANCE='1%',
 MATERIAL='CHIP',
 VALUE='33.2',
 PRIM_FILE='./archive_libs/logical/q_res/chips/chips.prt';

PART_NAME
 R901 'Q_RES_0402LF-33.2,1%,1/16W,CHIA':;

SECTION_NUMBER 1
 '@S9S_MB_2U_LIB.S9S_MB_2U(SCH_1):PAGE114_I64@PURE_QUANTA.Q_RES(CHIPS)':
 C_PATH='@s9s_mb_2u_lib.s9s_mb_2u(sch_1):page114_i64@pure_quanta.q_res(chips)',
 P_PATH='@s9s_mb_2u_lib.s9s_mb_2u(sch_1):page114_i64@pure_quanta.q_res(chips)',
 PATH='I64',
 DRAWING='@S9S_MB_2U_LIB.S9S_MB_2U(SCH_1):PAGE114',
 PHYS_PAGE='114',
 XY='(-5700,5400)',
 ROT='0',
 VER='1',
 PACK_TYPE='0402LF',
 CDS_LIB='pure_quanta',
 CDS_PART_NAME='Q_RES_0402LF-33.2,1%,1/16W,CHIA',
 WATTAGE='1/16W',
 TOLERANCE='1%',
 MATERIAL='CHIP',
 VALUE='33.2',
 PRIM_FILE='./archive_libs/logical/q_res/chips/chips.prt';

PART_NAME
 R902 'Q_RES_0402LF-33.2,1%,1/16W,CHIA':;

SECTION_NUMBER 1
 '@S9S_MB_2U_LIB.S9S_MB_2U(SCH_1):PAGE114_I63@PURE_QUANTA.Q_RES(CHIPS)':
 C_PATH='@s9s_mb_2u_lib.s9s_mb_2u(sch_1):page114_i63@pure_quanta.q_res(chips)',
 P_PATH='@s9s_mb_2u_lib.s9s_mb_2u(sch_1):page114_i63@pure_quanta.q_res(chips)',
 PATH='I63',
 DRAWING='@S9S_MB_2U_LIB.S9S_MB_2U(SCH_1):PAGE114',
 PHYS_PAGE='114',
 XY='(-5700,5350)',
 ROT='0',
 VER='1',
 PACK_TYPE='0402LF',
 CDS_LIB='pure_quanta',
 CDS_PART_NAME='Q_RES_0402LF-33.2,1%,1/16W,CHIA',
 WATTAGE='1/16W',
 TOLERANCE='1%',
 MATERIAL='CHIP',
 VALUE='33.2',
 PRIM_FILE='./archive_libs/logical/q_res/chips/chips.prt';

PART_NAME
 R903 'Q_RES_0402LF-33.2,1%,1/16W,CHIA':;

SECTION_NUMBER 1
 '@S9S_MB_2U_LIB.S9S_MB_2U(SCH_1):PAGE114_I62@PURE_QUANTA.Q_RES(CHIPS)':
 C_PATH='@s9s_mb_2u_lib.s9s_mb_2u(sch_1):page114_i62@pure_quanta.q_res(chips)',
 P_PATH='@s9s_mb_2u_lib.s9s_mb_2u(sch_1):page114_i62@pure_quanta.q_res(chips)',
 PATH='I62',
 DRAWING='@S9S_MB_2U_LIB.S9S_MB_2U(SCH_1):PAGE114',
 PHYS_PAGE='114',
 XY='(-5700,5175)',
 ROT='0',
 VER='1',
 PACK_TYPE='0402LF',
 CDS_LIB='pure_quanta',
 CDS_PART_NAME='Q_RES_0402LF-33.2,1%,1/16W,CHIA',
 WATTAGE='1/16W',
 TOLERANCE='1%',
 MATERIAL='CHIP',
 VALUE='33.2',
 PRIM_FILE='./archive_libs/logical/q_res/chips/chips.prt';

PART_NAME
 R905 'Q_RES_0402LF-33.2,1%,1/16W,CHIA':;

SECTION_NUMBER 1
 '@S9S_MB_2U_LIB.S9S_MB_2U(SCH_1):PAGE114_I60@PURE_QUANTA.Q_RES(CHIPS)':
 C_PATH='@s9s_mb_2u_lib.s9s_mb_2u(sch_1):page114_i60@pure_quanta.q_res(chips)',
 P_PATH='@s9s_mb_2u_lib.s9s_mb_2u(sch_1):page114_i60@pure_quanta.q_res(chips)',
 PATH='I60',
 DRAWING='@S9S_MB_2U_LIB.S9S_MB_2U(SCH_1):PAGE114',
 PHYS_PAGE='114',
 XY='(-5700,4850)',
 ROT='0',
 VER='1',
 PACK_TYPE='0402LF',
 CDS_LIB='pure_quanta',
 CDS_PART_NAME='Q_RES_0402LF-33.2,1%,1/16W,CHIA',
 WATTAGE='1/16W',
 TOLERANCE='1%',
 MATERIAL='CHIP',
 VALUE='33.2',
 PRIM_FILE='./archive_libs/logical/q_res/chips/chips.prt';

PART_NAME
 R906 'Q_RES_0402LF-33.2,1%,1/16W,CHIA':;

SECTION_NUMBER 1
 '@S9S_MB_2U_LIB.S9S_MB_2U(SCH_1):PAGE114_I59@PURE_QUANTA.Q_RES(CHIPS)':
 C_PATH='@s9s_mb_2u_lib.s9s_mb_2u(sch_1):page114_i59@pure_quanta.q_res(chips)',
 P_PATH='@s9s_mb_2u_lib.s9s_mb_2u(sch_1):page114_i59@pure_quanta.q_res(chips)',
 PATH='I59',
 DRAWING='@S9S_MB_2U_LIB.S9S_MB_2U(SCH_1):PAGE114',
 PHYS_PAGE='114',
 XY='(-5700,4800)',
 ROT='0',
 VER='1',
 PACK_TYPE='0402LF',
 CDS_LIB='pure_quanta',
 CDS_PART_NAME='Q_RES_0402LF-33.2,1%,1/16W,CHIA',
 WATTAGE='1/16W',
 TOLERANCE='1%',
 MATERIAL='CHIP',
 VALUE='33.2',
 PRIM_FILE='./archive_libs/logical/q_res/chips/chips.prt';

PART_NAME
 R907 'Q_RES_0402LF-33.2,1%,1/16W,CHIA':;

SECTION_NUMBER 1
 '@S9S_MB_2U_LIB.S9S_MB_2U(SCH_1):PAGE114_I58@PURE_QUANTA.Q_RES(CHIPS)':
 C_PATH='@s9s_mb_2u_lib.s9s_mb_2u(sch_1):page114_i58@pure_quanta.q_res(chips)',
 P_PATH='@s9s_mb_2u_lib.s9s_mb_2u(sch_1):page114_i58@pure_quanta.q_res(chips)',
 PATH='I58',
 DRAWING='@S9S_MB_2U_LIB.S9S_MB_2U(SCH_1):PAGE114',
 PHYS_PAGE='114',
 XY='(-5700,4625)',
 ROT='0',
 VER='1',
 PACK_TYPE='0402LF',
 CDS_LIB='pure_quanta',
 CDS_PART_NAME='Q_RES_0402LF-33.2,1%,1/16W,CHIA',
 WATTAGE='1/16W',
 TOLERANCE='1%',
 MATERIAL='CHIP',
 VALUE='33.2',
 PRIM_FILE='./archive_libs/logical/q_res/chips/chips.prt';

PART_NAME
 R908 'Q_RES_0402LF-33.2,1%,1/16W,CHIA':;

SECTION_NUMBER 1
 '@S9S_MB_2U_LIB.S9S_MB_2U(SCH_1):PAGE114_I57@PURE_QUANTA.Q_RES(CHIPS)':
 C_PATH='@s9s_mb_2u_lib.s9s_mb_2u(sch_1):page114_i57@pure_quanta.q_res(chips)',
 P_PATH='@s9s_mb_2u_lib.s9s_mb_2u(sch_1):page114_i57@pure_quanta.q_res(chips)',
 PATH='I57',
 DRAWING='@S9S_MB_2U_LIB.S9S_MB_2U(SCH_1):PAGE114',
 PHYS_PAGE='114',
 XY='(-5700,4575)',
 ROT='0',
 VER='1',
 PACK_TYPE='0402LF',
 CDS_LIB='pure_quanta',
 CDS_PART_NAME='Q_RES_0402LF-33.2,1%,1/16W,CHIA',
 WATTAGE='1/16W',
 TOLERANCE='1%',
 MATERIAL='CHIP',
 VALUE='33.2',
 PRIM_FILE='./archive_libs/logical/q_res/chips/chips.prt';

PART_NAME
 R909 'Q_RES_0402LF-33.2,1%,1/16W,CHIA':;

SECTION_NUMBER 1
 '@S9S_MB_2U_LIB.S9S_MB_2U(SCH_1):PAGE223_I102@PURE_QUANTA.Q_RES(CHIPS)':
 C_PATH='@s9s_mb_2u_lib.s9s_mb_2u(sch_1):page223_i102@pure_quanta.q_res(chips)',
 P_PATH='@s9s_mb_2u_lib.s9s_mb_2u(sch_1):page235_i102@pure_quanta.q_res(chips)',
 PATH='I102',
 DRAWING='@S9S_MB_2U_LIB.S9S_MB_2U(SCH_1):PAGE223',
 PHYS_PAGE='235',
 XY='(-5600,7025)',
 ROT='0',
 VER='1',
 PACK_TYPE='0402LF',
 LOCATION='R909',
 CDS_LIB='pure_quanta',
 CDS_PART_NAME='Q_RES_0402LF-33.2,1%,1/16W,CHIA',
 WATTAGE='1/16W',
 TOLERANCE='1%',
 MATERIAL='CHIP',
 VALUE='33.2',
 PRIM_FILE='./archive_libs/logical/q_res/chips/chips.prt';

PART_NAME
 R910 'Q_RES_0402LF-240,1%,1/16W,CHIPA':;

SECTION_NUMBER 1
 '@S9S_MB_2U_LIB.S9S_MB_2U(SCH_1):PAGE223_I24@PURE_QUANTA.Q_RES(CHIPS)':
 C_PATH='@s9s_mb_2u_lib.s9s_mb_2u(sch_1):page223_i24@pure_quanta.q_res(chips)',
 P_PATH='@s9s_mb_2u_lib.s9s_mb_2u(sch_1):page235_i24@pure_quanta.q_res(chips)',
 PATH='I24',
 DRAWING='@S9S_MB_2U_LIB.S9S_MB_2U(SCH_1):PAGE223',
 PHYS_PAGE='235',
 XY='(-5125,7425)',
 ROT='2',
 VER='2',
 PACK_TYPE='0402LF',
 CDS_LIB='pure_quanta',
 CDS_PART_NAME='Q_RES_0402LF-240,1%,1/16W,CHIPA',
 WATTAGE='1/16W',
 TOLERANCE='1%',
 MATERIAL='CHIP',
 VALUE='240',
 PRIM_FILE='./archive_libs/logical/q_res/chips/chips.prt';

PART_NAME
 R911 'Q_RES_0402LF-240,1%,1/16W,CHIPA':;

SECTION_NUMBER 1
 '@S9S_MB_2U_LIB.S9S_MB_2U(SCH_1):PAGE223_I22@PURE_QUANTA.Q_RES(CHIPS)':
 C_PATH='@s9s_mb_2u_lib.s9s_mb_2u(sch_1):page223_i22@pure_quanta.q_res(chips)',
 P_PATH='@s9s_mb_2u_lib.s9s_mb_2u(sch_1):page235_i22@pure_quanta.q_res(chips)',
 PATH='I22',
 DRAWING='@S9S_MB_2U_LIB.S9S_MB_2U(SCH_1):PAGE223',
 PHYS_PAGE='235',
 XY='(-4925,7425)',
 ROT='2',
 VER='2',
 PACK_TYPE='0402LF',
 CDS_LIB='pure_quanta',
 CDS_PART_NAME='Q_RES_0402LF-240,1%,1/16W,CHIPA',
 WATTAGE='1/16W',
 TOLERANCE='1%',
 MATERIAL='CHIP',
 VALUE='240',
 PRIM_FILE='./archive_libs/logical/q_res/chips/chips.prt';

PART_NAME
 R912 'Q_RES_0402LF-4.75K,1%,1/16W,EMA':;

SECTION_NUMBER 1
 '@S9S_MB_2U_LIB.S9S_MB_2U(SCH_1):PAGE197_I278@PURE_QUANTA.Q_RES(CHIPS)':
 C_PATH='@s9s_mb_2u_lib.s9s_mb_2u(sch_1):page197_i278@pure_quanta.q_res(chips)',
 P_PATH='@s9s_mb_2u_lib.s9s_mb_2u(sch_1):page208_i278@pure_quanta.q_res(chips)',
 PATH='I278',
 DRAWING='@S9S_MB_2U_LIB.S9S_MB_2U(SCH_1):PAGE197',
 PHYS_PAGE='208',
 XY='(-5350,10725)',
 ROT='0',
 VER='2',
 PACK_TYPE='0402LF',
 CDS_LIB='pure_quanta',
 CDS_PART_NAME='Q_RES_0402LF-4.75K,1%,1/16W,EMA',
 WATTAGE='1/16W',
 TOLERANCE='1%',
 MATERIAL='EMPTY',
 VALUE='4.75K',
 PRIM_FILE='./archive_libs/logical/q_res/chips/chips.prt';

PART_NAME
 R913 'Q_RES_0402LF-10K,1%,1/16W,CHIPA':;

SECTION_NUMBER 1
 '@S9S_MB_2U_LIB.S9S_MB_2U(SCH_1):PAGE175_I241@PURE_QUANTA.Q_RES(CHIPS)':
 C_PATH='@s9s_mb_2u_lib.s9s_mb_2u(sch_1):page175_i241@pure_quanta.q_res(chips)',
 P_PATH='@s9s_mb_2u_lib.s9s_mb_2u(sch_1):page183_i241@pure_quanta.q_res(chips)',
 PATH='I241',
 DRAWING='@S9S_MB_2U_LIB.S9S_MB_2U(SCH_1):PAGE175',
 PHYS_PAGE='183',
 XY='(3475,-425)',
 ROT='0',
 VER='1',
 PACK_TYPE='0402LF',
 CDS_LIB='pure_quanta',
 CDS_PART_NAME='Q_RES_0402LF-10K,1%,1/16W,CHIPA',
 WATTAGE='1/16W',
 TOLERANCE='1%',
 MATERIAL='CHIP',
 VALUE='10K',
 PRIM_FILE='./archive_libs/logical/q_res/chips/chips.prt';

PART_NAME
 R915 'Q_RES_0402LF-0,5%,1/16W,CHIP,CA':;

SECTION_NUMBER 1
 '@S9S_MB_2U_LIB.S9S_MB_2U(SCH_1):PAGE177_I118@PURE_QUANTA.Q_RES(CHIPS)':
 C_PATH='@s9s_mb_2u_lib.s9s_mb_2u(sch_1):page177_i118@pure_quanta.q_res(chips)',
 P_PATH='@s9s_mb_2u_lib.s9s_mb_2u(sch_1):page185_i118@pure_quanta.q_res(chips)',
 PATH='I118',
 DRAWING='@S9S_MB_2U_LIB.S9S_MB_2U(SCH_1):PAGE177',
 PHYS_PAGE='185',
 XY='(4200,-1175)',
 ROT='0',
 VER='1',
 PACK_TYPE='0402LF',
 LOCATION='R915',
 CDS_LIB='pure_quanta',
 CDS_PART_NAME='Q_RES_0402LF-0,5%,1/16W,CHIP,CA',
 WATTAGE='1/16W',
 TOLERANCE='5%',
 MATERIAL='CHIP',
 VALUE='0',
 PRIM_FILE='./archive_libs/logical/q_res/chips/chips.prt';

PART_NAME
 R916 'Q_RES_0402LF-0,5%,1/16W,CHIP,CA':;

SECTION_NUMBER 1
 '@S9S_MB_2U_LIB.S9S_MB_2U(SCH_1):PAGE177_I119@PURE_QUANTA.Q_RES(CHIPS)':
 C_PATH='@s9s_mb_2u_lib.s9s_mb_2u(sch_1):page177_i119@pure_quanta.q_res(chips)',
 P_PATH='@s9s_mb_2u_lib.s9s_mb_2u(sch_1):page185_i119@pure_quanta.q_res(chips)',
 PATH='I119',
 DRAWING='@S9S_MB_2U_LIB.S9S_MB_2U(SCH_1):PAGE177',
 PHYS_PAGE='185',
 XY='(4200,-1250)',
 ROT='0',
 VER='1',
 PACK_TYPE='0402LF',
 LOCATION='R916',
 CDS_LIB='pure_quanta',
 CDS_PART_NAME='Q_RES_0402LF-0,5%,1/16W,CHIP,CA',
 WATTAGE='1/16W',
 TOLERANCE='5%',
 MATERIAL='CHIP',
 VALUE='0',
 PRIM_FILE='./archive_libs/logical/q_res/chips/chips.prt';

PART_NAME
 R917 'Q_RES_0402LF-0,5%,1/16W,CHIP,CA':;

SECTION_NUMBER 1
 '@S9S_MB_2U_LIB.S9S_MB_2U(SCH_1):PAGE177_I121@PURE_QUANTA.Q_RES(CHIPS)':
 C_PATH='@s9s_mb_2u_lib.s9s_mb_2u(sch_1):page177_i121@pure_quanta.q_res(chips)',
 P_PATH='@s9s_mb_2u_lib.s9s_mb_2u(sch_1):page185_i121@pure_quanta.q_res(chips)',
 PATH='I121',
 DRAWING='@S9S_MB_2U_LIB.S9S_MB_2U(SCH_1):PAGE177',
 PHYS_PAGE='185',
 XY='(4200,-1400)',
 ROT='0',
 VER='1',
 PACK_TYPE='0402LF',
 LOCATION='R917',
 CDS_LIB='pure_quanta',
 CDS_PART_NAME='Q_RES_0402LF-0,5%,1/16W,CHIP,CA',
 WATTAGE='1/16W',
 TOLERANCE='5%',
 MATERIAL='CHIP',
 VALUE='0',
 PRIM_FILE='./archive_libs/logical/q_res/chips/chips.prt';

PART_NAME
 R918 'Q_RES_0402LF-0,5%,1/16W,CHIP,CA':;

SECTION_NUMBER 1
 '@S9S_MB_2U_LIB.S9S_MB_2U(SCH_1):PAGE177_I120@PURE_QUANTA.Q_RES(CHIPS)':
 C_PATH='@s9s_mb_2u_lib.s9s_mb_2u(sch_1):page177_i120@pure_quanta.q_res(chips)',
 P_PATH='@s9s_mb_2u_lib.s9s_mb_2u(sch_1):page185_i120@pure_quanta.q_res(chips)',
 PATH='I120',
 DRAWING='@S9S_MB_2U_LIB.S9S_MB_2U(SCH_1):PAGE177',
 PHYS_PAGE='185',
 XY='(4200,-1325)',
 ROT='0',
 VER='1',
 PACK_TYPE='0402LF',
 LOCATION='R918',
 CDS_LIB='pure_quanta',
 CDS_PART_NAME='Q_RES_0402LF-0,5%,1/16W,CHIP,CA',
 WATTAGE='1/16W',
 TOLERANCE='5%',
 MATERIAL='CHIP',
 VALUE='0',
 PRIM_FILE='./archive_libs/logical/q_res/chips/chips.prt';

PART_NAME
 R919 'Q_RES_0402LF-10K,1%,1/16W,CHIPA':;

SECTION_NUMBER 1
 '@S9S_MB_2U_LIB.S9S_MB_2U(SCH_1):PAGE210_I75@PURE_QUANTA.Q_RES(CHIPS)':
 C_PATH='@s9s_mb_2u_lib.s9s_mb_2u(sch_1):page210_i75@pure_quanta.q_res(chips)',
 P_PATH='@s9s_mb_2u_lib.s9s_mb_2u(sch_1):page221_i75@pure_quanta.q_res(chips)',
 PATH='I75',
 DRAWING='@S9S_MB_2U_LIB.S9S_MB_2U(SCH_1):PAGE210',
 PHYS_PAGE='221',
 XY='(1650,1500)',
 ROT='0',
 VER='2',
 PACK_TYPE='0402LF',
 CDS_LIB='pure_quanta',
 CDS_PART_NAME='Q_RES_0402LF-10K,1%,1/16W,CHIPA',
 WATTAGE='1/16W',
 TOLERANCE='1%',
 MATERIAL='CHIP',
 VALUE='10K',
 PRIM_FILE='./archive_libs/logical/q_res/chips/chips.prt';

PART_NAME
 R920 'Q_RES_0402LF-1K,1%,1/16W,EMPTYA':;

SECTION_NUMBER 1
 '@S9S_MB_2U_LIB.S9S_MB_2U(SCH_1):PAGE210_I76@PURE_QUANTA.Q_RES(CHIPS)':
 C_PATH='@s9s_mb_2u_lib.s9s_mb_2u(sch_1):page210_i76@pure_quanta.q_res(chips)',
 P_PATH='@s9s_mb_2u_lib.s9s_mb_2u(sch_1):page221_i76@pure_quanta.q_res(chips)',
 PATH='I76',
 DRAWING='@S9S_MB_2U_LIB.S9S_MB_2U(SCH_1):PAGE210',
 PHYS_PAGE='221',
 XY='(1650,975)',
 ROT='0',
 VER='2',
 PACK_TYPE='0402LF',
 CDS_LIB='pure_quanta',
 CDS_PART_NAME='Q_RES_0402LF-1K,1%,1/16W,EMPTYA',
 WATTAGE='1/16W',
 TOLERANCE='1%',
 MATERIAL='EMPTY',
 VALUE='1K',
 PRIM_FILE='./archive_libs/logical/q_res/chips/chips.prt';

PART_NAME
 R927 'Q_RES_0402LF-10K,1%,1/16W,CHIPA':;

SECTION_NUMBER 1
 '@S9S_MB_2U_LIB.S9S_MB_2U(SCH_1):PAGE210_I61@PURE_QUANTA.Q_RES(CHIPS)':
 C_PATH='@s9s_mb_2u_lib.s9s_mb_2u(sch_1):page210_i61@pure_quanta.q_res(chips)',
 P_PATH='@s9s_mb_2u_lib.s9s_mb_2u(sch_1):page221_i61@pure_quanta.q_res(chips)',
 PATH='I61',
 DRAWING='@S9S_MB_2U_LIB.S9S_MB_2U(SCH_1):PAGE210',
 PHYS_PAGE='221',
 XY='(-775,4125)',
 ROT='0',
 VER='2',
 PACK_TYPE='0402LF',
 CDS_LIB='pure_quanta',
 CDS_PART_NAME='Q_RES_0402LF-10K,1%,1/16W,CHIPA',
 WATTAGE='1/16W',
 TOLERANCE='1%',
 MATERIAL='CHIP',
 VALUE='10K',
 PRIM_FILE='./archive_libs/logical/q_res/chips/chips.prt';

PART_NAME
 R928 'Q_RES_0402LF-10K,1%,1/16W,CHIPA':;

SECTION_NUMBER 1
 '@S9S_MB_2U_LIB.S9S_MB_2U(SCH_1):PAGE210_I60@PURE_QUANTA.Q_RES(CHIPS)':
 C_PATH='@s9s_mb_2u_lib.s9s_mb_2u(sch_1):page210_i60@pure_quanta.q_res(chips)',
 P_PATH='@s9s_mb_2u_lib.s9s_mb_2u(sch_1):page221_i60@pure_quanta.q_res(chips)',
 PATH='I60',
 DRAWING='@S9S_MB_2U_LIB.S9S_MB_2U(SCH_1):PAGE210',
 PHYS_PAGE='221',
 XY='(-450,4125)',
 ROT='0',
 VER='2',
 PACK_TYPE='0402LF',
 CDS_LIB='pure_quanta',
 CDS_PART_NAME='Q_RES_0402LF-10K,1%,1/16W,CHIPA',
 WATTAGE='1/16W',
 TOLERANCE='1%',
 MATERIAL='CHIP',
 VALUE='10K',
 PRIM_FILE='./archive_libs/logical/q_res/chips/chips.prt';

PART_NAME
 R929 'Q_RES_0402LF-10K,1%,1/16W,CHIPA':;

SECTION_NUMBER 1
 '@S9S_MB_2U_LIB.S9S_MB_2U(SCH_1):PAGE210_I59@PURE_QUANTA.Q_RES(CHIPS)':
 C_PATH='@s9s_mb_2u_lib.s9s_mb_2u(sch_1):page210_i59@pure_quanta.q_res(chips)',
 P_PATH='@s9s_mb_2u_lib.s9s_mb_2u(sch_1):page221_i59@pure_quanta.q_res(chips)',
 PATH='I59',
 DRAWING='@S9S_MB_2U_LIB.S9S_MB_2U(SCH_1):PAGE210',
 PHYS_PAGE='221',
 XY='(-150,4125)',
 ROT='0',
 VER='2',
 PACK_TYPE='0402LF',
 CDS_LIB='pure_quanta',
 CDS_PART_NAME='Q_RES_0402LF-10K,1%,1/16W,CHIPA',
 WATTAGE='1/16W',
 TOLERANCE='1%',
 MATERIAL='CHIP',
 VALUE='10K',
 PRIM_FILE='./archive_libs/logical/q_res/chips/chips.prt';

PART_NAME
 R930 'Q_RES_0402LF-4.7K,1%,1/16W,CHIA':;

SECTION_NUMBER 1
 '@S9S_MB_2U_LIB.S9S_MB_2U(SCH_1):PAGE210_I63@PURE_QUANTA.Q_RES(CHIPS)':
 C_PATH='@s9s_mb_2u_lib.s9s_mb_2u(sch_1):page210_i63@pure_quanta.q_res(chips)',
 P_PATH='@s9s_mb_2u_lib.s9s_mb_2u(sch_1):page221_i63@pure_quanta.q_res(chips)',
 PATH='I63',
 DRAWING='@S9S_MB_2U_LIB.S9S_MB_2U(SCH_1):PAGE210',
 PHYS_PAGE='221',
 XY='(-150,2625)',
 ROT='0',
 VER='2',
 PACK_TYPE='0402LF',
 CDS_LIB='pure_quanta',
 CDS_PART_NAME='Q_RES_0402LF-4.7K,1%,1/16W,CHIA',
 WATTAGE='1/16W',
 TOLERANCE='1%',
 MATERIAL='CHIP',
 VALUE='4.7K',
 PRIM_FILE='./archive_libs/logical/q_res/chips/chips.prt';

PART_NAME
 R932 'Q_RES_0402LF-10K,1%,1/16W,CHIPA':;

SECTION_NUMBER 1
 '@S9S_MB_2U_LIB.S9S_MB_2U(SCH_1):PAGE128_I80@PURE_QUANTA.Q_RES(CHIPS)':
 C_PATH='@s9s_mb_2u_lib.s9s_mb_2u(sch_1):page128_i80@pure_quanta.q_res(chips)',
 P_PATH='@s9s_mb_2u_lib.s9s_mb_2u(sch_1):page128_i80@pure_quanta.q_res(chips)',
 PATH='I80',
 DRAWING='@S9S_MB_2U_LIB.S9S_MB_2U(SCH_1):PAGE128',
 PHYS_PAGE='128',
 XY='(-7100,3000)',
 ROT='0',
 VER='2',
 PACK_TYPE='0402LF',
 CDS_LIB='pure_quanta',
 CDS_PART_NAME='Q_RES_0402LF-10K,1%,1/16W,CHIPA',
 WATTAGE='1/16W',
 TOLERANCE='1%',
 MATERIAL='CHIP',
 VALUE='10K',
 PRIM_FILE='./archive_libs/logical/q_res/chips/chips.prt';

PART_NAME
 R933 'Q_RES_0402LF-10K,1%,1/16W,CHIPA':;

SECTION_NUMBER 1
 '@S9S_MB_2U_LIB.S9S_MB_2U(SCH_1):PAGE128_I82@PURE_QUANTA.Q_RES(CHIPS)':
 C_PATH='@s9s_mb_2u_lib.s9s_mb_2u(sch_1):page128_i82@pure_quanta.q_res(chips)',
 P_PATH='@s9s_mb_2u_lib.s9s_mb_2u(sch_1):page128_i82@pure_quanta.q_res(chips)',
 PATH='I82',
 DRAWING='@S9S_MB_2U_LIB.S9S_MB_2U(SCH_1):PAGE128',
 PHYS_PAGE='128',
 XY='(-7100,100)',
 ROT='0',
 VER='2',
 PACK_TYPE='0402LF',
 CDS_LIB='pure_quanta',
 CDS_PART_NAME='Q_RES_0402LF-10K,1%,1/16W,CHIPA',
 WATTAGE='1/16W',
 TOLERANCE='1%',
 MATERIAL='CHIP',
 VALUE='10K',
 PRIM_FILE='./archive_libs/logical/q_res/chips/chips.prt';

PART_NAME
 R934 'Q_RES_0402LF-10K,1%,1/16W,CHIPA':;

SECTION_NUMBER 1
 '@S9S_MB_2U_LIB.S9S_MB_2U(SCH_1):PAGE128_I79@PURE_QUANTA.Q_RES(CHIPS)':
 C_PATH='@s9s_mb_2u_lib.s9s_mb_2u(sch_1):page128_i79@pure_quanta.q_res(chips)',
 P_PATH='@s9s_mb_2u_lib.s9s_mb_2u(sch_1):page128_i79@pure_quanta.q_res(chips)',
 PATH='I79',
 DRAWING='@S9S_MB_2U_LIB.S9S_MB_2U(SCH_1):PAGE128',
 PHYS_PAGE='128',
 XY='(-6900,3000)',
 ROT='0',
 VER='2',
 PACK_TYPE='0402LF',
 CDS_LIB='pure_quanta',
 CDS_PART_NAME='Q_RES_0402LF-10K,1%,1/16W,CHIPA',
 WATTAGE='1/16W',
 TOLERANCE='1%',
 MATERIAL='CHIP',
 VALUE='10K',
 PRIM_FILE='./archive_libs/logical/q_res/chips/chips.prt';

PART_NAME
 R935 'Q_RES_0402LF-10K,1%,1/16W,CHIPA':;

SECTION_NUMBER 1
 '@S9S_MB_2U_LIB.S9S_MB_2U(SCH_1):PAGE128_I86@PURE_QUANTA.Q_RES(CHIPS)':
 C_PATH='@s9s_mb_2u_lib.s9s_mb_2u(sch_1):page128_i86@pure_quanta.q_res(chips)',
 P_PATH='@s9s_mb_2u_lib.s9s_mb_2u(sch_1):page128_i86@pure_quanta.q_res(chips)',
 PATH='I86',
 DRAWING='@S9S_MB_2U_LIB.S9S_MB_2U(SCH_1):PAGE128',
 PHYS_PAGE='128',
 XY='(-6900,100)',
 ROT='0',
 VER='2',
 PACK_TYPE='0402LF',
 CDS_LIB='pure_quanta',
 CDS_PART_NAME='Q_RES_0402LF-10K,1%,1/16W,CHIPA',
 WATTAGE='1/16W',
 TOLERANCE='1%',
 MATERIAL='CHIP',
 VALUE='10K',
 PRIM_FILE='./archive_libs/logical/q_res/chips/chips.prt';

PART_NAME
 R936 'Q_RES_0402LF-10K,1%,1/16W,CHIPA':;

SECTION_NUMBER 1
 '@S9S_MB_2U_LIB.S9S_MB_2U(SCH_1):PAGE128_I78@PURE_QUANTA.Q_RES(CHIPS)':
 C_PATH='@s9s_mb_2u_lib.s9s_mb_2u(sch_1):page128_i78@pure_quanta.q_res(chips)',
 P_PATH='@s9s_mb_2u_lib.s9s_mb_2u(sch_1):page128_i78@pure_quanta.q_res(chips)',
 PATH='I78',
 DRAWING='@S9S_MB_2U_LIB.S9S_MB_2U(SCH_1):PAGE128',
 PHYS_PAGE='128',
 XY='(-6700,3000)',
 ROT='0',
 VER='2',
 PACK_TYPE='0402LF',
 CDS_LIB='pure_quanta',
 CDS_PART_NAME='Q_RES_0402LF-10K,1%,1/16W,CHIPA',
 WATTAGE='1/16W',
 TOLERANCE='1%',
 MATERIAL='CHIP',
 VALUE='10K',
 PRIM_FILE='./archive_libs/logical/q_res/chips/chips.prt';

PART_NAME
 R937 'Q_RES_0402LF-10K,1%,1/16W,CHIPA':;

SECTION_NUMBER 1
 '@S9S_MB_2U_LIB.S9S_MB_2U(SCH_1):PAGE128_I85@PURE_QUANTA.Q_RES(CHIPS)':
 C_PATH='@s9s_mb_2u_lib.s9s_mb_2u(sch_1):page128_i85@pure_quanta.q_res(chips)',
 P_PATH='@s9s_mb_2u_lib.s9s_mb_2u(sch_1):page128_i85@pure_quanta.q_res(chips)',
 PATH='I85',
 DRAWING='@S9S_MB_2U_LIB.S9S_MB_2U(SCH_1):PAGE128',
 PHYS_PAGE='128',
 XY='(-6700,100)',
 ROT='0',
 VER='2',
 PACK_TYPE='0402LF',
 CDS_LIB='pure_quanta',
 CDS_PART_NAME='Q_RES_0402LF-10K,1%,1/16W,CHIPA',
 WATTAGE='1/16W',
 TOLERANCE='1%',
 MATERIAL='CHIP',
 VALUE='10K',
 PRIM_FILE='./archive_libs/logical/q_res/chips/chips.prt';

PART_NAME
 R938 'Q_RES_0402LF-10K,1%,1/16W,CHIPA':;

SECTION_NUMBER 1
 '@S9S_MB_2U_LIB.S9S_MB_2U(SCH_1):PAGE128_I77@PURE_QUANTA.Q_RES(CHIPS)':
 C_PATH='@s9s_mb_2u_lib.s9s_mb_2u(sch_1):page128_i77@pure_quanta.q_res(chips)',
 P_PATH='@s9s_mb_2u_lib.s9s_mb_2u(sch_1):page128_i77@pure_quanta.q_res(chips)',
 PATH='I77',
 DRAWING='@S9S_MB_2U_LIB.S9S_MB_2U(SCH_1):PAGE128',
 PHYS_PAGE='128',
 XY='(-6500,3000)',
 ROT='0',
 VER='2',
 PACK_TYPE='0402LF',
 CDS_LIB='pure_quanta',
 CDS_PART_NAME='Q_RES_0402LF-10K,1%,1/16W,CHIPA',
 WATTAGE='1/16W',
 TOLERANCE='1%',
 MATERIAL='CHIP',
 VALUE='10K',
 PRIM_FILE='./archive_libs/logical/q_res/chips/chips.prt';

PART_NAME
 R939 'Q_RES_0402LF-10K,1%,1/16W,CHIPA':;

SECTION_NUMBER 1
 '@S9S_MB_2U_LIB.S9S_MB_2U(SCH_1):PAGE128_I83@PURE_QUANTA.Q_RES(CHIPS)':
 C_PATH='@s9s_mb_2u_lib.s9s_mb_2u(sch_1):page128_i83@pure_quanta.q_res(chips)',
 P_PATH='@s9s_mb_2u_lib.s9s_mb_2u(sch_1):page128_i83@pure_quanta.q_res(chips)',
 PATH='I83',
 DRAWING='@S9S_MB_2U_LIB.S9S_MB_2U(SCH_1):PAGE128',
 PHYS_PAGE='128',
 XY='(-6500,100)',
 ROT='0',
 VER='2',
 PACK_TYPE='0402LF',
 CDS_LIB='pure_quanta',
 CDS_PART_NAME='Q_RES_0402LF-10K,1%,1/16W,CHIPA',
 WATTAGE='1/16W',
 TOLERANCE='1%',
 MATERIAL='CHIP',
 VALUE='10K',
 PRIM_FILE='./archive_libs/logical/q_res/chips/chips.prt';

PART_NAME
 R940 'Q_RES_0402LF-10K,1%,1/16W,CHIPA':;

SECTION_NUMBER 1
 '@S9S_MB_2U_LIB.S9S_MB_2U(SCH_1):PAGE115_I48@PURE_QUANTA.Q_RES(CHIPS)':
 C_PATH='@s9s_mb_2u_lib.s9s_mb_2u(sch_1):page115_i48@pure_quanta.q_res(chips)',
 P_PATH='@s9s_mb_2u_lib.s9s_mb_2u(sch_1):page115_i48@pure_quanta.q_res(chips)',
 PATH='I48',
 DRAWING='@S9S_MB_2U_LIB.S9S_MB_2U(SCH_1):PAGE115',
 PHYS_PAGE='115',
 XY='(1825,2225)',
 ROT='0',
 VER='1',
 PACK_TYPE='0402LF',
 CDS_LIB='pure_quanta',
 CDS_PART_NAME='Q_RES_0402LF-10K,1%,1/16W,CHIPA',
 WATTAGE='1/16W',
 TOLERANCE='1%',
 MATERIAL='CHIP',
 VALUE='10K',
 PRIM_FILE='./archive_libs/logical/q_res/chips/chips.prt';

PART_NAME
 R941 'Q_RES_0402LF-10K,1%,1/16W,CHIPA':;

SECTION_NUMBER 1
 '@S9S_MB_2U_LIB.S9S_MB_2U(SCH_1):PAGE115_I45@PURE_QUANTA.Q_RES(CHIPS)':
 C_PATH='@s9s_mb_2u_lib.s9s_mb_2u(sch_1):page115_i45@pure_quanta.q_res(chips)',
 P_PATH='@s9s_mb_2u_lib.s9s_mb_2u(sch_1):page115_i45@pure_quanta.q_res(chips)',
 PATH='I45',
 DRAWING='@S9S_MB_2U_LIB.S9S_MB_2U(SCH_1):PAGE115',
 PHYS_PAGE='115',
 XY='(1825,1600)',
 ROT='0',
 VER='1',
 PACK_TYPE='0402LF',
 CDS_LIB='pure_quanta',
 CDS_PART_NAME='Q_RES_0402LF-10K,1%,1/16W,CHIPA',
 WATTAGE='1/16W',
 TOLERANCE='1%',
 MATERIAL='CHIP',
 VALUE='10K',
 PRIM_FILE='./archive_libs/logical/q_res/chips/chips.prt';

PART_NAME
 R942 'Q_RES_0402LF-10K,1%,1/16W,CHIPA':;

SECTION_NUMBER 1
 '@S9S_MB_2U_LIB.S9S_MB_2U(SCH_1):PAGE115_I40@PURE_QUANTA.Q_RES(CHIPS)':
 C_PATH='@s9s_mb_2u_lib.s9s_mb_2u(sch_1):page115_i40@pure_quanta.q_res(chips)',
 P_PATH='@s9s_mb_2u_lib.s9s_mb_2u(sch_1):page115_i40@pure_quanta.q_res(chips)',
 PATH='I40',
 DRAWING='@S9S_MB_2U_LIB.S9S_MB_2U(SCH_1):PAGE115',
 PHYS_PAGE='115',
 XY='(1825,975)',
 ROT='0',
 VER='1',
 PACK_TYPE='0402LF',
 CDS_LIB='pure_quanta',
 CDS_PART_NAME='Q_RES_0402LF-10K,1%,1/16W,CHIPA',
 WATTAGE='1/16W',
 TOLERANCE='1%',
 MATERIAL='CHIP',
 VALUE='10K',
 PRIM_FILE='./archive_libs/logical/q_res/chips/chips.prt';

PART_NAME
 R943 'Q_RES_0402LF-10K,1%,1/16W,CHIPA':;

SECTION_NUMBER 1
 '@S9S_MB_2U_LIB.S9S_MB_2U(SCH_1):PAGE115_I37@PURE_QUANTA.Q_RES(CHIPS)':
 C_PATH='@s9s_mb_2u_lib.s9s_mb_2u(sch_1):page115_i37@pure_quanta.q_res(chips)',
 P_PATH='@s9s_mb_2u_lib.s9s_mb_2u(sch_1):page115_i37@pure_quanta.q_res(chips)',
 PATH='I37',
 DRAWING='@S9S_MB_2U_LIB.S9S_MB_2U(SCH_1):PAGE115',
 PHYS_PAGE='115',
 XY='(1825,350)',
 ROT='0',
 VER='1',
 PACK_TYPE='0402LF',
 CDS_LIB='pure_quanta',
 CDS_PART_NAME='Q_RES_0402LF-10K,1%,1/16W,CHIPA',
 WATTAGE='1/16W',
 TOLERANCE='1%',
 MATERIAL='CHIP',
 VALUE='10K',
 PRIM_FILE='./archive_libs/logical/q_res/chips/chips.prt';

PART_NAME
 R944 'Q_RES_0402LF-10K,1%,1/16W,CHIPA':;

SECTION_NUMBER 1
 '@S9S_MB_2U_LIB.S9S_MB_2U(SCH_1):PAGE115_I19@PURE_QUANTA.Q_RES(CHIPS)':
 C_PATH='@s9s_mb_2u_lib.s9s_mb_2u(sch_1):page115_i19@pure_quanta.q_res(chips)',
 P_PATH='@s9s_mb_2u_lib.s9s_mb_2u(sch_1):page115_i19@pure_quanta.q_res(chips)',
 PATH='I19',
 DRAWING='@S9S_MB_2U_LIB.S9S_MB_2U(SCH_1):PAGE115',
 PHYS_PAGE='115',
 XY='(1825,-625)',
 ROT='0',
 VER='1',
 PACK_TYPE='0402LF',
 CDS_LIB='pure_quanta',
 CDS_PART_NAME='Q_RES_0402LF-10K,1%,1/16W,CHIPA',
 WATTAGE='1/16W',
 TOLERANCE='1%',
 MATERIAL='CHIP',
 VALUE='10K',
 PRIM_FILE='./archive_libs/logical/q_res/chips/chips.prt';

PART_NAME
 R945 'Q_RES_0402LF-10K,1%,1/16W,CHIPA':;

SECTION_NUMBER 1
 '@S9S_MB_2U_LIB.S9S_MB_2U(SCH_1):PAGE115_I16@PURE_QUANTA.Q_RES(CHIPS)':
 C_PATH='@s9s_mb_2u_lib.s9s_mb_2u(sch_1):page115_i16@pure_quanta.q_res(chips)',
 P_PATH='@s9s_mb_2u_lib.s9s_mb_2u(sch_1):page115_i16@pure_quanta.q_res(chips)',
 PATH='I16',
 DRAWING='@S9S_MB_2U_LIB.S9S_MB_2U(SCH_1):PAGE115',
 PHYS_PAGE='115',
 XY='(1825,-1250)',
 ROT='0',
 VER='1',
 PACK_TYPE='0402LF',
 CDS_LIB='pure_quanta',
 CDS_PART_NAME='Q_RES_0402LF-10K,1%,1/16W,CHIPA',
 WATTAGE='1/16W',
 TOLERANCE='1%',
 MATERIAL='CHIP',
 VALUE='10K',
 PRIM_FILE='./archive_libs/logical/q_res/chips/chips.prt';

PART_NAME
 R946 'Q_RES_0402LF-10K,1%,1/16W,CHIPA':;

SECTION_NUMBER 1
 '@S9S_MB_2U_LIB.S9S_MB_2U(SCH_1):PAGE115_I14@PURE_QUANTA.Q_RES(CHIPS)':
 C_PATH='@s9s_mb_2u_lib.s9s_mb_2u(sch_1):page115_i14@pure_quanta.q_res(chips)',
 P_PATH='@s9s_mb_2u_lib.s9s_mb_2u(sch_1):page115_i14@pure_quanta.q_res(chips)',
 PATH='I14',
 DRAWING='@S9S_MB_2U_LIB.S9S_MB_2U(SCH_1):PAGE115',
 PHYS_PAGE='115',
 XY='(1825,-1875)',
 ROT='0',
 VER='1',
 PACK_TYPE='0402LF',
 CDS_LIB='pure_quanta',
 CDS_PART_NAME='Q_RES_0402LF-10K,1%,1/16W,CHIPA',
 WATTAGE='1/16W',
 TOLERANCE='1%',
 MATERIAL='CHIP',
 VALUE='10K',
 PRIM_FILE='./archive_libs/logical/q_res/chips/chips.prt';

PART_NAME
 R947 'Q_RES_0402LF-10K,1%,1/16W,CHIPA':;

SECTION_NUMBER 1
 '@S9S_MB_2U_LIB.S9S_MB_2U(SCH_1):PAGE115_I11@PURE_QUANTA.Q_RES(CHIPS)':
 C_PATH='@s9s_mb_2u_lib.s9s_mb_2u(sch_1):page115_i11@pure_quanta.q_res(chips)',
 P_PATH='@s9s_mb_2u_lib.s9s_mb_2u(sch_1):page115_i11@pure_quanta.q_res(chips)',
 PATH='I11',
 DRAWING='@S9S_MB_2U_LIB.S9S_MB_2U(SCH_1):PAGE115',
 PHYS_PAGE='115',
 XY='(1825,-2500)',
 ROT='0',
 VER='1',
 PACK_TYPE='0402LF',
 CDS_LIB='pure_quanta',
 CDS_PART_NAME='Q_RES_0402LF-10K,1%,1/16W,CHIPA',
 WATTAGE='1/16W',
 TOLERANCE='1%',
 MATERIAL='CHIP',
 VALUE='10K',
 PRIM_FILE='./archive_libs/logical/q_res/chips/chips.prt';

PART_NAME
 R953 'Q_RES_0402LF-4.75K,1%,1/16W,CHA':;

SECTION_NUMBER 1
 '@S9S_MB_2U_LIB.S9S_MB_2U(SCH_1):PAGE197_I282@PURE_QUANTA.Q_RES(CHIPS)':
 C_PATH='@s9s_mb_2u_lib.s9s_mb_2u(sch_1):page197_i282@pure_quanta.q_res(chips)',
 P_PATH='@s9s_mb_2u_lib.s9s_mb_2u(sch_1):page208_i282@pure_quanta.q_res(chips)',
 PATH='I282',
 DRAWING='@S9S_MB_2U_LIB.S9S_MB_2U(SCH_1):PAGE197',
 PHYS_PAGE='208',
 XY='(-5350,9800)',
 ROT='0',
 VER='2',
 PACK_TYPE='0402LF',
 CDS_LIB='pure_quanta',
 CDS_PART_NAME='Q_RES_0402LF-4.75K,1%,1/16W,CHA',
 WATTAGE='1/16W',
 TOLERANCE='1%',
 MATERIAL='CHIP',
 VALUE='4.75K',
 PRIM_FILE='./archive_libs/logical/q_res/chips/chips.prt';

PART_NAME
 R960 'Q_RES_0402LF-33.2,1%,1/16W,CHIA':;

SECTION_NUMBER 1
 '@S9S_MB_2U_LIB.S9S_MB_2U(SCH_1):PAGE223_I101@PURE_QUANTA.Q_RES(CHIPS)':
 C_PATH='@s9s_mb_2u_lib.s9s_mb_2u(sch_1):page223_i101@pure_quanta.q_res(chips)',
 P_PATH='@s9s_mb_2u_lib.s9s_mb_2u(sch_1):page235_i101@pure_quanta.q_res(chips)',
 PATH='I101',
 DRAWING='@S9S_MB_2U_LIB.S9S_MB_2U(SCH_1):PAGE223',
 PHYS_PAGE='235',
 XY='(-5600,7125)',
 ROT='0',
 VER='1',
 PACK_TYPE='0402LF',
 LOCATION='R960',
 CDS_LIB='pure_quanta',
 CDS_PART_NAME='Q_RES_0402LF-33.2,1%,1/16W,CHIA',
 WATTAGE='1/16W',
 TOLERANCE='1%',
 MATERIAL='CHIP',
 VALUE='33.2',
 PRIM_FILE='./archive_libs/logical/q_res/chips/chips.prt';

PART_NAME
 R961 'Q_RES_0402LF-33.2,1%,1/16W,CHIA':;

SECTION_NUMBER 1
 '@S9S_MB_2U_LIB.S9S_MB_2U(SCH_1):PAGE223_I99@PURE_QUANTA.Q_RES(CHIPS)':
 C_PATH='@s9s_mb_2u_lib.s9s_mb_2u(sch_1):page223_i99@pure_quanta.q_res(chips)',
 P_PATH='@s9s_mb_2u_lib.s9s_mb_2u(sch_1):page235_i99@pure_quanta.q_res(chips)',
 PATH='I99',
 DRAWING='@S9S_MB_2U_LIB.S9S_MB_2U(SCH_1):PAGE223',
 PHYS_PAGE='235',
 XY='(-5600,5525)',
 ROT='0',
 VER='1',
 PACK_TYPE='0402LF',
 LOCATION='R961',
 CDS_LIB='pure_quanta',
 CDS_PART_NAME='Q_RES_0402LF-33.2,1%,1/16W,CHIA',
 WATTAGE='1/16W',
 TOLERANCE='1%',
 MATERIAL='CHIP',
 VALUE='33.2',
 PRIM_FILE='./archive_libs/logical/q_res/chips/chips.prt';

PART_NAME
 R962 'Q_RES_0402LF-33.2,1%,1/16W,CHIA':;

SECTION_NUMBER 1
 '@S9S_MB_2U_LIB.S9S_MB_2U(SCH_1):PAGE223_I100@PURE_QUANTA.Q_RES(CHIPS)':
 C_PATH='@s9s_mb_2u_lib.s9s_mb_2u(sch_1):page223_i100@pure_quanta.q_res(chips)',
 P_PATH='@s9s_mb_2u_lib.s9s_mb_2u(sch_1):page235_i100@pure_quanta.q_res(chips)',
 PATH='I100',
 DRAWING='@S9S_MB_2U_LIB.S9S_MB_2U(SCH_1):PAGE223',
 PHYS_PAGE='235',
 XY='(-5600,5425)',
 ROT='0',
 VER='1',
 PACK_TYPE='0402LF',
 LOCATION='R962',
 CDS_LIB='pure_quanta',
 CDS_PART_NAME='Q_RES_0402LF-33.2,1%,1/16W,CHIA',
 WATTAGE='1/16W',
 TOLERANCE='1%',
 MATERIAL='CHIP',
 VALUE='33.2',
 PRIM_FILE='./archive_libs/logical/q_res/chips/chips.prt';

PART_NAME
 R963 'Q_RES_0402LF-240,1%,1/16W,CHIPA':;

SECTION_NUMBER 1
 '@S9S_MB_2U_LIB.S9S_MB_2U(SCH_1):PAGE223_I48@PURE_QUANTA.Q_RES(CHIPS)':
 C_PATH='@s9s_mb_2u_lib.s9s_mb_2u(sch_1):page223_i48@pure_quanta.q_res(chips)',
 P_PATH='@s9s_mb_2u_lib.s9s_mb_2u(sch_1):page235_i48@pure_quanta.q_res(chips)',
 PATH='I48',
 DRAWING='@S9S_MB_2U_LIB.S9S_MB_2U(SCH_1):PAGE223',
 PHYS_PAGE='235',
 XY='(-5125,5825)',
 ROT='2',
 VER='2',
 PACK_TYPE='0402LF',
 CDS_LIB='pure_quanta',
 CDS_PART_NAME='Q_RES_0402LF-240,1%,1/16W,CHIPA',
 WATTAGE='1/16W',
 TOLERANCE='1%',
 MATERIAL='CHIP',
 VALUE='240',
 PRIM_FILE='./archive_libs/logical/q_res/chips/chips.prt';

PART_NAME
 R964 'Q_RES_0402LF-240,1%,1/16W,CHIPA':;

SECTION_NUMBER 1
 '@S9S_MB_2U_LIB.S9S_MB_2U(SCH_1):PAGE223_I46@PURE_QUANTA.Q_RES(CHIPS)':
 C_PATH='@s9s_mb_2u_lib.s9s_mb_2u(sch_1):page223_i46@pure_quanta.q_res(chips)',
 P_PATH='@s9s_mb_2u_lib.s9s_mb_2u(sch_1):page235_i46@pure_quanta.q_res(chips)',
 PATH='I46',
 DRAWING='@S9S_MB_2U_LIB.S9S_MB_2U(SCH_1):PAGE223',
 PHYS_PAGE='235',
 XY='(-4900,5825)',
 ROT='2',
 VER='2',
 PACK_TYPE='0402LF',
 CDS_LIB='pure_quanta',
 CDS_PART_NAME='Q_RES_0402LF-240,1%,1/16W,CHIPA',
 WATTAGE='1/16W',
 TOLERANCE='1%',
 MATERIAL='CHIP',
 VALUE='240',
 PRIM_FILE='./archive_libs/logical/q_res/chips/chips.prt';

PART_NAME
 R965 'Q_RES_0402LF-1K,1%,1/16W,CHIP,A':;

SECTION_NUMBER 1
 '@S9S_MB_2U_LIB.S9S_MB_2U(SCH_1):PAGE223_I93@PURE_QUANTA.Q_RES(CHIPS)':
 C_PATH='@s9s_mb_2u_lib.s9s_mb_2u(sch_1):page223_i93@pure_quanta.q_res(chips)',
 P_PATH='@s9s_mb_2u_lib.s9s_mb_2u(sch_1):page235_i93@pure_quanta.q_res(chips)',
 PATH='I93',
 DRAWING='@S9S_MB_2U_LIB.S9S_MB_2U(SCH_1):PAGE223',
 PHYS_PAGE='235',
 XY='(-750,7575)',
 ROT='0',
 VER='2',
 PACK_TYPE='0402LF',
 CDS_LIB='pure_quanta',
 CDS_PART_NAME='Q_RES_0402LF-1K,1%,1/16W,CHIP,A',
 WATTAGE='1/16W',
 TOLERANCE='1%',
 MATERIAL='CHIP',
 VALUE='1K',
 PRIM_FILE='./archive_libs/logical/q_res/chips/chips.prt';

PART_NAME
 R966 'Q_RES_0402LF-1K,1%,1/16W,CHIP,A':;

SECTION_NUMBER 1
 '@S9S_MB_2U_LIB.S9S_MB_2U(SCH_1):PAGE223_I82@PURE_QUANTA.Q_RES(CHIPS)':
 C_PATH='@s9s_mb_2u_lib.s9s_mb_2u(sch_1):page223_i82@pure_quanta.q_res(chips)',
 P_PATH='@s9s_mb_2u_lib.s9s_mb_2u(sch_1):page235_i82@pure_quanta.q_res(chips)',
 PATH='I82',
 DRAWING='@S9S_MB_2U_LIB.S9S_MB_2U(SCH_1):PAGE223',
 PHYS_PAGE='235',
 XY='(-750,5975)',
 ROT='0',
 VER='2',
 PACK_TYPE='0402LF',
 CDS_LIB='pure_quanta',
 CDS_PART_NAME='Q_RES_0402LF-1K,1%,1/16W,CHIP,A',
 WATTAGE='1/16W',
 TOLERANCE='1%',
 MATERIAL='CHIP',
 VALUE='1K',
 PRIM_FILE='./archive_libs/logical/q_res/chips/chips.prt';

PART_NAME
 R967 'Q_RES_0402LF-1K,1%,1/16W,CHIP,A':;

SECTION_NUMBER 1
 '@S9S_MB_2U_LIB.S9S_MB_2U(SCH_1):PAGE223_I94@PURE_QUANTA.Q_RES(CHIPS)':
 C_PATH='@s9s_mb_2u_lib.s9s_mb_2u(sch_1):page223_i94@pure_quanta.q_res(chips)',
 P_PATH='@s9s_mb_2u_lib.s9s_mb_2u(sch_1):page235_i94@pure_quanta.q_res(chips)',
 PATH='I94',
 DRAWING='@S9S_MB_2U_LIB.S9S_MB_2U(SCH_1):PAGE223',
 PHYS_PAGE='235',
 XY='(-550,7575)',
 ROT='0',
 VER='2',
 PACK_TYPE='0402LF',
 CDS_LIB='pure_quanta',
 CDS_PART_NAME='Q_RES_0402LF-1K,1%,1/16W,CHIP,A',
 WATTAGE='1/16W',
 TOLERANCE='1%',
 MATERIAL='CHIP',
 VALUE='1K',
 PRIM_FILE='./archive_libs/logical/q_res/chips/chips.prt';

PART_NAME
 R968 'Q_RES_0402LF-1K,1%,1/16W,CHIP,A':;

SECTION_NUMBER 1
 '@S9S_MB_2U_LIB.S9S_MB_2U(SCH_1):PAGE223_I81@PURE_QUANTA.Q_RES(CHIPS)':
 C_PATH='@s9s_mb_2u_lib.s9s_mb_2u(sch_1):page223_i81@pure_quanta.q_res(chips)',
 P_PATH='@s9s_mb_2u_lib.s9s_mb_2u(sch_1):page235_i81@pure_quanta.q_res(chips)',
 PATH='I81',
 DRAWING='@S9S_MB_2U_LIB.S9S_MB_2U(SCH_1):PAGE223',
 PHYS_PAGE='235',
 XY='(-550,5975)',
 ROT='0',
 VER='2',
 PACK_TYPE='0402LF',
 CDS_LIB='pure_quanta',
 CDS_PART_NAME='Q_RES_0402LF-1K,1%,1/16W,CHIP,A',
 WATTAGE='1/16W',
 TOLERANCE='1%',
 MATERIAL='CHIP',
 VALUE='1K',
 PRIM_FILE='./archive_libs/logical/q_res/chips/chips.prt';

PART_NAME
 R969 'Q_RES_0402LF-240,1%,1/16W,CHIPA':;

SECTION_NUMBER 1
 '@S9S_MB_2U_LIB.S9S_MB_2U(SCH_1):PAGE224_I43@PURE_QUANTA.Q_RES(CHIPS)':
 C_PATH='@s9s_mb_2u_lib.s9s_mb_2u(sch_1):page224_i43@pure_quanta.q_res(chips)',
 P_PATH='@s9s_mb_2u_lib.s9s_mb_2u(sch_1):page236_i43@pure_quanta.q_res(chips)',
 PATH='I43',
 DRAWING='@S9S_MB_2U_LIB.S9S_MB_2U(SCH_1):PAGE224',
 PHYS_PAGE='236',
 XY='(-2725,6200)',
 ROT='2',
 VER='2',
 PACK_TYPE='0402LF',
 CDS_LIB='pure_quanta',
 CDS_PART_NAME='Q_RES_0402LF-240,1%,1/16W,CHIPA',
 WATTAGE='1/16W',
 TOLERANCE='1%',
 MATERIAL='CHIP',
 VALUE='240',
 PRIM_FILE='./archive_libs/logical/q_res/chips/chips.prt';

PART_NAME
 R970 'Q_RES_0402LF-240,1%,1/16W,CHIPA':;

SECTION_NUMBER 1
 '@S9S_MB_2U_LIB.S9S_MB_2U(SCH_1):PAGE224_I50@PURE_QUANTA.Q_RES(CHIPS)':
 C_PATH='@s9s_mb_2u_lib.s9s_mb_2u(sch_1):page224_i50@pure_quanta.q_res(chips)',
 P_PATH='@s9s_mb_2u_lib.s9s_mb_2u(sch_1):page236_i50@pure_quanta.q_res(chips)',
 PATH='I50',
 DRAWING='@S9S_MB_2U_LIB.S9S_MB_2U(SCH_1):PAGE224',
 PHYS_PAGE='236',
 XY='(-2725,4400)',
 ROT='2',
 VER='2',
 PACK_TYPE='0402LF',
 CDS_LIB='pure_quanta',
 CDS_PART_NAME='Q_RES_0402LF-240,1%,1/16W,CHIPA',
 WATTAGE='1/16W',
 TOLERANCE='1%',
 MATERIAL='CHIP',
 VALUE='240',
 PRIM_FILE='./archive_libs/logical/q_res/chips/chips.prt';

PART_NAME
 R971 'Q_RES_0402LF-240,1%,1/16W,CHIPA':;

SECTION_NUMBER 1
 '@S9S_MB_2U_LIB.S9S_MB_2U(SCH_1):PAGE224_I42@PURE_QUANTA.Q_RES(CHIPS)':
 C_PATH='@s9s_mb_2u_lib.s9s_mb_2u(sch_1):page224_i42@pure_quanta.q_res(chips)',
 P_PATH='@s9s_mb_2u_lib.s9s_mb_2u(sch_1):page236_i42@pure_quanta.q_res(chips)',
 PATH='I42',
 DRAWING='@S9S_MB_2U_LIB.S9S_MB_2U(SCH_1):PAGE224',
 PHYS_PAGE='236',
 XY='(-2500,6200)',
 ROT='2',
 VER='2',
 PACK_TYPE='0402LF',
 CDS_LIB='pure_quanta',
 CDS_PART_NAME='Q_RES_0402LF-240,1%,1/16W,CHIPA',
 WATTAGE='1/16W',
 TOLERANCE='1%',
 MATERIAL='CHIP',
 VALUE='240',
 PRIM_FILE='./archive_libs/logical/q_res/chips/chips.prt';

PART_NAME
 R972 'Q_RES_0402LF-240,1%,1/16W,CHIPA':;

SECTION_NUMBER 1
 '@S9S_MB_2U_LIB.S9S_MB_2U(SCH_1):PAGE224_I49@PURE_QUANTA.Q_RES(CHIPS)':
 C_PATH='@s9s_mb_2u_lib.s9s_mb_2u(sch_1):page224_i49@pure_quanta.q_res(chips)',
 P_PATH='@s9s_mb_2u_lib.s9s_mb_2u(sch_1):page236_i49@pure_quanta.q_res(chips)',
 PATH='I49',
 DRAWING='@S9S_MB_2U_LIB.S9S_MB_2U(SCH_1):PAGE224',
 PHYS_PAGE='236',
 XY='(-2500,4400)',
 ROT='2',
 VER='2',
 PACK_TYPE='0402LF',
 CDS_LIB='pure_quanta',
 CDS_PART_NAME='Q_RES_0402LF-240,1%,1/16W,CHIPA',
 WATTAGE='1/16W',
 TOLERANCE='1%',
 MATERIAL='CHIP',
 VALUE='240',
 PRIM_FILE='./archive_libs/logical/q_res/chips/chips.prt';

PART_NAME
 R977 'Q_RES_0402LF-560,1%,1/16W,CHIPA':;

SECTION_NUMBER 1
 '@S9S_MB_2U_LIB.S9S_MB_2U(SCH_1):PAGE224_I8@PURE_QUANTA.Q_RES(CHIPS)':
 C_PATH='@s9s_mb_2u_lib.s9s_mb_2u(sch_1):page224_i8@pure_quanta.q_res(chips)',
 P_PATH='@s9s_mb_2u_lib.s9s_mb_2u(sch_1):page236_i8@pure_quanta.q_res(chips)',
 PATH='I8',
 DRAWING='@S9S_MB_2U_LIB.S9S_MB_2U(SCH_1):PAGE224',
 PHYS_PAGE='236',
 XY='(1150,6200)',
 ROT='0',
 VER='2',
 PACK_TYPE='0402LF',
 CDS_LIB='pure_quanta',
 CDS_PART_NAME='Q_RES_0402LF-560,1%,1/16W,CHIPA',
 WATTAGE='1/16W',
 TOLERANCE='1%',
 MATERIAL='CHIP',
 VALUE='560',
 PRIM_FILE='./archive_libs/logical/q_res/chips/chips.prt';

PART_NAME
 R978 'Q_RES_0402LF-560,1%,1/16W,CHIPA':;

SECTION_NUMBER 1
 '@S9S_MB_2U_LIB.S9S_MB_2U(SCH_1):PAGE224_I16@PURE_QUANTA.Q_RES(CHIPS)':
 C_PATH='@s9s_mb_2u_lib.s9s_mb_2u(sch_1):page224_i16@pure_quanta.q_res(chips)',
 P_PATH='@s9s_mb_2u_lib.s9s_mb_2u(sch_1):page236_i16@pure_quanta.q_res(chips)',
 PATH='I16',
 DRAWING='@S9S_MB_2U_LIB.S9S_MB_2U(SCH_1):PAGE224',
 PHYS_PAGE='236',
 XY='(1150,4400)',
 ROT='0',
 VER='2',
 PACK_TYPE='0402LF',
 CDS_LIB='pure_quanta',
 CDS_PART_NAME='Q_RES_0402LF-560,1%,1/16W,CHIPA',
 WATTAGE='1/16W',
 TOLERANCE='1%',
 MATERIAL='CHIP',
 VALUE='560',
 PRIM_FILE='./archive_libs/logical/q_res/chips/chips.prt';

PART_NAME
 R979 'Q_RES_0402LF-560,1%,1/16W,CHIPA':;

SECTION_NUMBER 1
 '@S9S_MB_2U_LIB.S9S_MB_2U(SCH_1):PAGE224_I6@PURE_QUANTA.Q_RES(CHIPS)':
 C_PATH='@s9s_mb_2u_lib.s9s_mb_2u(sch_1):page224_i6@pure_quanta.q_res(chips)',
 P_PATH='@s9s_mb_2u_lib.s9s_mb_2u(sch_1):page236_i6@pure_quanta.q_res(chips)',
 PATH='I6',
 DRAWING='@S9S_MB_2U_LIB.S9S_MB_2U(SCH_1):PAGE224',
 PHYS_PAGE='236',
 XY='(1350,6200)',
 ROT='0',
 VER='2',
 PACK_TYPE='0402LF',
 CDS_LIB='pure_quanta',
 CDS_PART_NAME='Q_RES_0402LF-560,1%,1/16W,CHIPA',
 WATTAGE='1/16W',
 TOLERANCE='1%',
 MATERIAL='CHIP',
 VALUE='560',
 PRIM_FILE='./archive_libs/logical/q_res/chips/chips.prt';

PART_NAME
 R980 'Q_RES_0402LF-560,1%,1/16W,CHIPA':;

SECTION_NUMBER 1
 '@S9S_MB_2U_LIB.S9S_MB_2U(SCH_1):PAGE224_I14@PURE_QUANTA.Q_RES(CHIPS)':
 C_PATH='@s9s_mb_2u_lib.s9s_mb_2u(sch_1):page224_i14@pure_quanta.q_res(chips)',
 P_PATH='@s9s_mb_2u_lib.s9s_mb_2u(sch_1):page236_i14@pure_quanta.q_res(chips)',
 PATH='I14',
 DRAWING='@S9S_MB_2U_LIB.S9S_MB_2U(SCH_1):PAGE224',
 PHYS_PAGE='236',
 XY='(1350,4400)',
 ROT='0',
 VER='2',
 PACK_TYPE='0402LF',
 CDS_LIB='pure_quanta',
 CDS_PART_NAME='Q_RES_0402LF-560,1%,1/16W,CHIPA',
 WATTAGE='1/16W',
 TOLERANCE='1%',
 MATERIAL='CHIP',
 VALUE='560',
 PRIM_FILE='./archive_libs/logical/q_res/chips/chips.prt';

PART_NAME
 R981 'Q_RES_0402LF-33.2,1%,1/16W,CHIA':;

SECTION_NUMBER 1
 '@S9S_MB_2U_LIB.S9S_MB_2U(SCH_1):PAGE211_I9@PURE_QUANTA.Q_RES(CHIPS)':
 C_PATH='@s9s_mb_2u_lib.s9s_mb_2u(sch_1):page211_i9@pure_quanta.q_res(chips)',
 P_PATH='@s9s_mb_2u_lib.s9s_mb_2u(sch_1):page222_i9@pure_quanta.q_res(chips)',
 PATH='I9',
 DRAWING='@S9S_MB_2U_LIB.S9S_MB_2U(SCH_1):PAGE211',
 PHYS_PAGE='222',
 XY='(-1625,4200)',
 ROT='0',
 VER='1',
 PACK_TYPE='0402LF',
 CDS_LIB='pure_quanta',
 CDS_PART_NAME='Q_RES_0402LF-33.2,1%,1/16W,CHIA',
 WATTAGE='1/16W',
 TOLERANCE='1%',
 MATERIAL='CHIP',
 VALUE='33.2',
 PRIM_FILE='./archive_libs/logical/q_res/chips/chips.prt';

PART_NAME
 R982 'Q_RES_0402LF-33.2,1%,1/16W,CHIA':;

SECTION_NUMBER 1
 '@S9S_MB_2U_LIB.S9S_MB_2U(SCH_1):PAGE211_I10@PURE_QUANTA.Q_RES(CHIPS)':
 C_PATH='@s9s_mb_2u_lib.s9s_mb_2u(sch_1):page211_i10@pure_quanta.q_res(chips)',
 P_PATH='@s9s_mb_2u_lib.s9s_mb_2u(sch_1):page222_i10@pure_quanta.q_res(chips)',
 PATH='I10',
 DRAWING='@S9S_MB_2U_LIB.S9S_MB_2U(SCH_1):PAGE211',
 PHYS_PAGE='222',
 XY='(-1625,3975)',
 ROT='0',
 VER='1',
 PACK_TYPE='0402LF',
 CDS_LIB='pure_quanta',
 CDS_PART_NAME='Q_RES_0402LF-33.2,1%,1/16W,CHIA',
 WATTAGE='1/16W',
 TOLERANCE='1%',
 MATERIAL='CHIP',
 VALUE='33.2',
 PRIM_FILE='./archive_libs/logical/q_res/chips/chips.prt';

PART_NAME
 R983 'Q_RES_0402LF-33.2,1%,1/16W,CHIA':;

SECTION_NUMBER 1
 '@S9S_MB_2U_LIB.S9S_MB_2U(SCH_1):PAGE211_I13@PURE_QUANTA.Q_RES(CHIPS)':
 C_PATH='@s9s_mb_2u_lib.s9s_mb_2u(sch_1):page211_i13@pure_quanta.q_res(chips)',
 P_PATH='@s9s_mb_2u_lib.s9s_mb_2u(sch_1):page222_i13@pure_quanta.q_res(chips)',
 PATH='I13',
 DRAWING='@S9S_MB_2U_LIB.S9S_MB_2U(SCH_1):PAGE211',
 PHYS_PAGE='222',
 XY='(-1625,3725)',
 ROT='0',
 VER='1',
 PACK_TYPE='0402LF',
 CDS_LIB='pure_quanta',
 CDS_PART_NAME='Q_RES_0402LF-33.2,1%,1/16W,CHIA',
 WATTAGE='1/16W',
 TOLERANCE='1%',
 MATERIAL='CHIP',
 VALUE='33.2',
 PRIM_FILE='./archive_libs/logical/q_res/chips/chips.prt';

PART_NAME
 R984 'Q_RES_0402LF-33.2,1%,1/16W,CHIA':;

SECTION_NUMBER 1
 '@S9S_MB_2U_LIB.S9S_MB_2U(SCH_1):PAGE211_I15@PURE_QUANTA.Q_RES(CHIPS)':
 C_PATH='@s9s_mb_2u_lib.s9s_mb_2u(sch_1):page211_i15@pure_quanta.q_res(chips)',
 P_PATH='@s9s_mb_2u_lib.s9s_mb_2u(sch_1):page222_i15@pure_quanta.q_res(chips)',
 PATH='I15',
 DRAWING='@S9S_MB_2U_LIB.S9S_MB_2U(SCH_1):PAGE211',
 PHYS_PAGE='222',
 XY='(-1625,3500)',
 ROT='0',
 VER='1',
 PACK_TYPE='0402LF',
 CDS_LIB='pure_quanta',
 CDS_PART_NAME='Q_RES_0402LF-33.2,1%,1/16W,CHIA',
 WATTAGE='1/16W',
 TOLERANCE='1%',
 MATERIAL='CHIP',
 VALUE='33.2',
 PRIM_FILE='./archive_libs/logical/q_res/chips/chips.prt';

PART_NAME
 R985 'Q_RES_0402LF-33.2,1%,1/16W,CHIA':;

SECTION_NUMBER 1
 '@S9S_MB_2U_LIB.S9S_MB_2U(SCH_1):PAGE211_I21@PURE_QUANTA.Q_RES(CHIPS)':
 C_PATH='@s9s_mb_2u_lib.s9s_mb_2u(sch_1):page211_i21@pure_quanta.q_res(chips)',
 P_PATH='@s9s_mb_2u_lib.s9s_mb_2u(sch_1):page222_i21@pure_quanta.q_res(chips)',
 PATH='I21',
 DRAWING='@S9S_MB_2U_LIB.S9S_MB_2U(SCH_1):PAGE211',
 PHYS_PAGE='222',
 XY='(-1625,3075)',
 ROT='0',
 VER='1',
 PACK_TYPE='0402LF',
 CDS_LIB='pure_quanta',
 CDS_PART_NAME='Q_RES_0402LF-33.2,1%,1/16W,CHIA',
 WATTAGE='1/16W',
 TOLERANCE='1%',
 MATERIAL='CHIP',
 VALUE='33.2',
 PRIM_FILE='./archive_libs/logical/q_res/chips/chips.prt';

PART_NAME
 R986 'Q_RES_0402LF-33.2,1%,1/16W,CHIA':;

SECTION_NUMBER 1
 '@S9S_MB_2U_LIB.S9S_MB_2U(SCH_1):PAGE211_I25@PURE_QUANTA.Q_RES(CHIPS)':
 C_PATH='@s9s_mb_2u_lib.s9s_mb_2u(sch_1):page211_i25@pure_quanta.q_res(chips)',
 P_PATH='@s9s_mb_2u_lib.s9s_mb_2u(sch_1):page222_i25@pure_quanta.q_res(chips)',
 PATH='I25',
 DRAWING='@S9S_MB_2U_LIB.S9S_MB_2U(SCH_1):PAGE211',
 PHYS_PAGE='222',
 XY='(-1625,2850)',
 ROT='0',
 VER='1',
 PACK_TYPE='0402LF',
 CDS_LIB='pure_quanta',
 CDS_PART_NAME='Q_RES_0402LF-33.2,1%,1/16W,CHIA',
 WATTAGE='1/16W',
 TOLERANCE='1%',
 MATERIAL='CHIP',
 VALUE='33.2',
 PRIM_FILE='./archive_libs/logical/q_res/chips/chips.prt';

PART_NAME
 R987 'Q_RES_0402LF-33.2,1%,1/16W,CHIA':;

SECTION_NUMBER 1
 '@S9S_MB_2U_LIB.S9S_MB_2U(SCH_1):PAGE211_I24@PURE_QUANTA.Q_RES(CHIPS)':
 C_PATH='@s9s_mb_2u_lib.s9s_mb_2u(sch_1):page211_i24@pure_quanta.q_res(chips)',
 P_PATH='@s9s_mb_2u_lib.s9s_mb_2u(sch_1):page222_i24@pure_quanta.q_res(chips)',
 PATH='I24',
 DRAWING='@S9S_MB_2U_LIB.S9S_MB_2U(SCH_1):PAGE211',
 PHYS_PAGE='222',
 XY='(-1625,2600)',
 ROT='0',
 VER='1',
 PACK_TYPE='0402LF',
 CDS_LIB='pure_quanta',
 CDS_PART_NAME='Q_RES_0402LF-33.2,1%,1/16W,CHIA',
 WATTAGE='1/16W',
 TOLERANCE='1%',
 MATERIAL='CHIP',
 VALUE='33.2',
 PRIM_FILE='./archive_libs/logical/q_res/chips/chips.prt';

PART_NAME
 R988 'Q_RES_0402LF-33.2,1%,1/16W,CHIA':;

SECTION_NUMBER 1
 '@S9S_MB_2U_LIB.S9S_MB_2U(SCH_1):PAGE211_I23@PURE_QUANTA.Q_RES(CHIPS)':
 C_PATH='@s9s_mb_2u_lib.s9s_mb_2u(sch_1):page211_i23@pure_quanta.q_res(chips)',
 P_PATH='@s9s_mb_2u_lib.s9s_mb_2u(sch_1):page222_i23@pure_quanta.q_res(chips)',
 PATH='I23',
 DRAWING='@S9S_MB_2U_LIB.S9S_MB_2U(SCH_1):PAGE211',
 PHYS_PAGE='222',
 XY='(-1625,2375)',
 ROT='0',
 VER='1',
 PACK_TYPE='0402LF',
 CDS_LIB='pure_quanta',
 CDS_PART_NAME='Q_RES_0402LF-33.2,1%,1/16W,CHIA',
 WATTAGE='1/16W',
 TOLERANCE='1%',
 MATERIAL='CHIP',
 VALUE='33.2',
 PRIM_FILE='./archive_libs/logical/q_res/chips/chips.prt';

PART_NAME
 R990 'Q_RES_0402LF-2K,1%,1/16W,CHIP,A':;

SECTION_NUMBER 1
 '@S9S_MB_2U_LIB.S9S_MB_2U(SCH_1):PAGE208_I18@PURE_QUANTA.Q_RES(CHIPS)':
 C_PATH='@s9s_mb_2u_lib.s9s_mb_2u(sch_1):page208_i18@pure_quanta.q_res(chips)',
 P_PATH='@s9s_mb_2u_lib.s9s_mb_2u(sch_1):page219_i18@pure_quanta.q_res(chips)',
 PATH='I18',
 DRAWING='@S9S_MB_2U_LIB.S9S_MB_2U(SCH_1):PAGE208',
 PHYS_PAGE='219',
 XY='(-300,1250)',
 ROT='0',
 VER='1',
 PACK_TYPE='0402LF',
 CDS_LIB='pure_quanta',
 CDS_PART_NAME='Q_RES_0402LF-2K,1%,1/16W,CHIP,A',
 WATTAGE='1/16W',
 TOLERANCE='1%',
 MATERIAL='CHIP',
 VALUE='2K',
 PRIM_FILE='./archive_libs/logical/q_res/chips/chips.prt';

PART_NAME
 R991 'Q_RES_0402LF-2K,1%,1/16W,CHIP,A':;

SECTION_NUMBER 1
 '@S9S_MB_2U_LIB.S9S_MB_2U(SCH_1):PAGE208_I20@PURE_QUANTA.Q_RES(CHIPS)':
 C_PATH='@s9s_mb_2u_lib.s9s_mb_2u(sch_1):page208_i20@pure_quanta.q_res(chips)',
 P_PATH='@s9s_mb_2u_lib.s9s_mb_2u(sch_1):page219_i20@pure_quanta.q_res(chips)',
 PATH='I20',
 DRAWING='@S9S_MB_2U_LIB.S9S_MB_2U(SCH_1):PAGE208',
 PHYS_PAGE='219',
 XY='(-300,1100)',
 ROT='0',
 VER='1',
 PACK_TYPE='0402LF',
 CDS_LIB='pure_quanta',
 CDS_PART_NAME='Q_RES_0402LF-2K,1%,1/16W,CHIP,A',
 WATTAGE='1/16W',
 TOLERANCE='1%',
 MATERIAL='CHIP',
 VALUE='2K',
 PRIM_FILE='./archive_libs/logical/q_res/chips/chips.prt';

PART_NAME
 R992 'Q_RES_0402LF-2K,1%,1/16W,EMPTYA':;

SECTION_NUMBER 1
 '@S9S_MB_2U_LIB.S9S_MB_2U(SCH_1):PAGE208_I21@PURE_QUANTA.Q_RES(CHIPS)':
 C_PATH='@s9s_mb_2u_lib.s9s_mb_2u(sch_1):page208_i21@pure_quanta.q_res(chips)',
 P_PATH='@s9s_mb_2u_lib.s9s_mb_2u(sch_1):page219_i21@pure_quanta.q_res(chips)',
 PATH='I21',
 DRAWING='@S9S_MB_2U_LIB.S9S_MB_2U(SCH_1):PAGE208',
 PHYS_PAGE='219',
 XY='(-300,950)',
 ROT='0',
 VER='1',
 PACK_TYPE='0402LF',
 CDS_LIB='pure_quanta',
 CDS_PART_NAME='Q_RES_0402LF-2K,1%,1/16W,EMPTYA',
 WATTAGE='1/16W',
 TOLERANCE='1%',
 MATERIAL='EMPTY',
 VALUE='2K',
 PRIM_FILE='./archive_libs/logical/q_res/chips/chips.prt';

PART_NAME
 R993 'Q_RES_0402LF-33.2,1%,1/16W,CHIA':;

SECTION_NUMBER 1
 '@S9S_MB_2U_LIB.S9S_MB_2U(SCH_1):PAGE224_I44@PURE_QUANTA.Q_RES(CHIPS)':
 C_PATH='@s9s_mb_2u_lib.s9s_mb_2u(sch_1):page224_i44@pure_quanta.q_res(chips)',
 P_PATH='@s9s_mb_2u_lib.s9s_mb_2u(sch_1):page236_i44@pure_quanta.q_res(chips)',
 PATH='I44',
 DRAWING='@S9S_MB_2U_LIB.S9S_MB_2U(SCH_1):PAGE224',
 PHYS_PAGE='236',
 XY='(-3175,5750)',
 ROT='0',
 VER='1',
 PACK_TYPE='0402LF',
 CDS_LIB='pure_quanta',
 CDS_PART_NAME='Q_RES_0402LF-33.2,1%,1/16W,CHIA',
 WATTAGE='1/16W',
 TOLERANCE='1%',
 MATERIAL='CHIP',
 VALUE='33.2',
 PRIM_FILE='./archive_libs/logical/q_res/chips/chips.prt';

PART_NAME
 R994 'Q_RES_0402LF-33.2,1%,1/16W,CHIA':;

SECTION_NUMBER 1
 '@S9S_MB_2U_LIB.S9S_MB_2U(SCH_1):PAGE224_I142@PURE_QUANTA.Q_RES(CHIPS)':
 C_PATH='@s9s_mb_2u_lib.s9s_mb_2u(sch_1):page224_i142@pure_quanta.q_res(chips)',
 P_PATH='@s9s_mb_2u_lib.s9s_mb_2u(sch_1):page236_i142@pure_quanta.q_res(chips)',
 PATH='I142',
 DRAWING='@S9S_MB_2U_LIB.S9S_MB_2U(SCH_1):PAGE224',
 PHYS_PAGE='236',
 XY='(-3175,5650)',
 ROT='0',
 VER='1',
 PACK_TYPE='0402LF',
 LOCATION='R994',
 CDS_LIB='pure_quanta',
 CDS_PART_NAME='Q_RES_0402LF-33.2,1%,1/16W,CHIA',
 WATTAGE='1/16W',
 TOLERANCE='1%',
 MATERIAL='CHIP',
 VALUE='33.2',
 PRIM_FILE='./archive_libs/logical/q_res/chips/chips.prt';

PART_NAME
 R995 'Q_RES_0402LF-33.2,1%,1/16W,CHIA':;

SECTION_NUMBER 1
 '@S9S_MB_2U_LIB.S9S_MB_2U(SCH_1):PAGE224_I51@PURE_QUANTA.Q_RES(CHIPS)':
 C_PATH='@s9s_mb_2u_lib.s9s_mb_2u(sch_1):page224_i51@pure_quanta.q_res(chips)',
 P_PATH='@s9s_mb_2u_lib.s9s_mb_2u(sch_1):page236_i51@pure_quanta.q_res(chips)',
 PATH='I51',
 DRAWING='@S9S_MB_2U_LIB.S9S_MB_2U(SCH_1):PAGE224',
 PHYS_PAGE='236',
 XY='(-3175,3950)',
 ROT='0',
 VER='1',
 PACK_TYPE='0402LF',
 CDS_LIB='pure_quanta',
 CDS_PART_NAME='Q_RES_0402LF-33.2,1%,1/16W,CHIA',
 WATTAGE='1/16W',
 TOLERANCE='1%',
 MATERIAL='CHIP',
 VALUE='33.2',
 PRIM_FILE='./archive_libs/logical/q_res/chips/chips.prt';

PART_NAME
 R996 'Q_RES_0402LF-33.2,1%,1/16W,CHIA':;

SECTION_NUMBER 1
 '@S9S_MB_2U_LIB.S9S_MB_2U(SCH_1):PAGE224_I143@PURE_QUANTA.Q_RES(CHIPS)':
 C_PATH='@s9s_mb_2u_lib.s9s_mb_2u(sch_1):page224_i143@pure_quanta.q_res(chips)',
 P_PATH='@s9s_mb_2u_lib.s9s_mb_2u(sch_1):page236_i143@pure_quanta.q_res(chips)',
 PATH='I143',
 DRAWING='@S9S_MB_2U_LIB.S9S_MB_2U(SCH_1):PAGE224',
 PHYS_PAGE='236',
 XY='(-3175,3850)',
 ROT='0',
 VER='1',
 PACK_TYPE='0402LF',
 LOCATION='R996',
 CDS_LIB='pure_quanta',
 CDS_PART_NAME='Q_RES_0402LF-33.2,1%,1/16W,CHIA',
 WATTAGE='1/16W',
 TOLERANCE='1%',
 MATERIAL='CHIP',
 VALUE='33.2',
 PRIM_FILE='./archive_libs/logical/q_res/chips/chips.prt';

PART_NAME
 R997 'Q_RES_0402LF-10K,1%,1/16W,EMPTA':;

SECTION_NUMBER 1
 '@S9S_MB_2U_LIB.S9S_MB_2U(SCH_1):PAGE127_I31@PURE_QUANTA.Q_RES(CHIPS)':
 C_PATH='@s9s_mb_2u_lib.s9s_mb_2u(sch_1):page127_i31@pure_quanta.q_res(chips)',
 P_PATH='@s9s_mb_2u_lib.s9s_mb_2u(sch_1):page127_i31@pure_quanta.q_res(chips)',
 PATH='I31',
 DRAWING='@S9S_MB_2U_LIB.S9S_MB_2U(SCH_1):PAGE127',
 PHYS_PAGE='127',
 XY='(-2175,1475)',
 ROT='0',
 VER='2',
 PACK_TYPE='0402LF',
 CDS_LIB='pure_quanta',
 CDS_PART_NAME='Q_RES_0402LF-10K,1%,1/16W,EMPTA',
 WATTAGE='1/16W',
 TOLERANCE='1%',
 MATERIAL='EMPTY',
 VALUE='10K',
 PRIM_FILE='./archive_libs/logical/q_res/chips/chips.prt';

PART_NAME
 R998 'Q_RES_0402LF-0,5%,1/16W,CHIP,CA':;

SECTION_NUMBER 1
 '@S9S_MB_2U_LIB.S9S_MB_2U(SCH_1):PAGE223_I53@PURE_QUANTA.Q_RES(CHIPS)':
 C_PATH='@s9s_mb_2u_lib.s9s_mb_2u(sch_1):page223_i53@pure_quanta.q_res(chips)',
 P_PATH='@s9s_mb_2u_lib.s9s_mb_2u(sch_1):page235_i53@pure_quanta.q_res(chips)',
 PATH='I53',
 DRAWING='@S9S_MB_2U_LIB.S9S_MB_2U(SCH_1):PAGE223',
 PHYS_PAGE='235',
 XY='(-4325,3750)',
 ROT='0',
 VER='1',
 PACK_TYPE='0402LF',
 CDS_LIB='pure_quanta',
 CDS_PART_NAME='Q_RES_0402LF-0,5%,1/16W,CHIP,CA',
 WATTAGE='1/16W',
 TOLERANCE='5%',
 MATERIAL='CHIP',
 VALUE='0',
 PRIM_FILE='./archive_libs/logical/q_res/chips/chips.prt';

PART_NAME
 R999 'Q_RES_0402LF-0,5%,1/16W,CHIP,CA':;

SECTION_NUMBER 1
 '@S9S_MB_2U_LIB.S9S_MB_2U(SCH_1):PAGE223_I69@PURE_QUANTA.Q_RES(CHIPS)':
 C_PATH='@s9s_mb_2u_lib.s9s_mb_2u(sch_1):page223_i69@pure_quanta.q_res(chips)',
 P_PATH='@s9s_mb_2u_lib.s9s_mb_2u(sch_1):page235_i69@pure_quanta.q_res(chips)',
 PATH='I69',
 DRAWING='@S9S_MB_2U_LIB.S9S_MB_2U(SCH_1):PAGE223',
 PHYS_PAGE='235',
 XY='(-5150,2450)',
 ROT='0',
 VER='1',
 PACK_TYPE='0402LF',
 CDS_LIB='pure_quanta',
 CDS_PART_NAME='Q_RES_0402LF-0,5%,1/16W,CHIP,CA',
 WATTAGE='1/16W',
 TOLERANCE='5%',
 MATERIAL='CHIP',
 VALUE='0',
 PRIM_FILE='./archive_libs/logical/q_res/chips/chips.prt';

PART_NAME
 R1000 'Q_RES_0402LF-4.7K,5%,1/16W,CHIA':;

SECTION_NUMBER 1
 '@S9S_MB_2U_LIB.S9S_MB_2U(SCH_1):PAGE223_I52@PURE_QUANTA.Q_RES(CHIPS)':
 C_PATH='@s9s_mb_2u_lib.s9s_mb_2u(sch_1):page223_i52@pure_quanta.q_res(chips)',
 P_PATH='@s9s_mb_2u_lib.s9s_mb_2u(sch_1):page235_i52@pure_quanta.q_res(chips)',
 PATH='I52',
 DRAWING='@S9S_MB_2U_LIB.S9S_MB_2U(SCH_1):PAGE223',
 PHYS_PAGE='235',
 XY='(-3975,4325)',
 ROT='0',
 VER='2',
 PACK_TYPE='0402LF',
 CDS_LIB='pure_quanta',
 CDS_PART_NAME='Q_RES_0402LF-4.7K,5%,1/16W,CHIA',
 WATTAGE='1/16W',
 TOLERANCE='5%',
 MATERIAL='CHIP',
 VALUE='4.7K',
 PRIM_FILE='./archive_libs/logical/q_res/chips/chips.prt';

PART_NAME
 R1001 'Q_RES_0402LF-4.7K,5%,1/16W,CHIA':;

SECTION_NUMBER 1
 '@S9S_MB_2U_LIB.S9S_MB_2U(SCH_1):PAGE223_I55@PURE_QUANTA.Q_RES(CHIPS)':
 C_PATH='@s9s_mb_2u_lib.s9s_mb_2u(sch_1):page223_i55@pure_quanta.q_res(chips)',
 P_PATH='@s9s_mb_2u_lib.s9s_mb_2u(sch_1):page235_i55@pure_quanta.q_res(chips)',
 PATH='I55',
 DRAWING='@S9S_MB_2U_LIB.S9S_MB_2U(SCH_1):PAGE223',
 PHYS_PAGE='235',
 XY='(-3975,3025)',
 ROT='0',
 VER='2',
 PACK_TYPE='0402LF',
 CDS_LIB='pure_quanta',
 CDS_PART_NAME='Q_RES_0402LF-4.7K,5%,1/16W,CHIA',
 WATTAGE='1/16W',
 TOLERANCE='5%',
 MATERIAL='CHIP',
 VALUE='4.7K',
 PRIM_FILE='./archive_libs/logical/q_res/chips/chips.prt';

PART_NAME
 R1002 'Q_RES_0402LF-4.7K,5%,1/16W,CHIA':;

SECTION_NUMBER 1
 '@S9S_MB_2U_LIB.S9S_MB_2U(SCH_1):PAGE223_I34@PURE_QUANTA.Q_RES(CHIPS)':
 C_PATH='@s9s_mb_2u_lib.s9s_mb_2u(sch_1):page223_i34@pure_quanta.q_res(chips)',
 P_PATH='@s9s_mb_2u_lib.s9s_mb_2u(sch_1):page235_i34@pure_quanta.q_res(chips)',
 PATH='I34',
 DRAWING='@S9S_MB_2U_LIB.S9S_MB_2U(SCH_1):PAGE223',
 PHYS_PAGE='235',
 XY='(-2500,4325)',
 ROT='0',
 VER='2',
 PACK_TYPE='0402LF',
 CDS_LIB='pure_quanta',
 CDS_PART_NAME='Q_RES_0402LF-4.7K,5%,1/16W,CHIA',
 WATTAGE='1/16W',
 TOLERANCE='5%',
 MATERIAL='CHIP',
 VALUE='4.7K',
 PRIM_FILE='./archive_libs/logical/q_res/chips/chips.prt';

PART_NAME
 R1003 'Q_RES_0402LF-4.7K,5%,1/16W,CHIA':;

SECTION_NUMBER 1
 '@S9S_MB_2U_LIB.S9S_MB_2U(SCH_1):PAGE223_I38@PURE_QUANTA.Q_RES(CHIPS)':
 C_PATH='@s9s_mb_2u_lib.s9s_mb_2u(sch_1):page223_i38@pure_quanta.q_res(chips)',
 P_PATH='@s9s_mb_2u_lib.s9s_mb_2u(sch_1):page235_i38@pure_quanta.q_res(chips)',
 PATH='I38',
 DRAWING='@S9S_MB_2U_LIB.S9S_MB_2U(SCH_1):PAGE223',
 PHYS_PAGE='235',
 XY='(-2500,3025)',
 ROT='0',
 VER='2',
 PACK_TYPE='0402LF',
 CDS_LIB='pure_quanta',
 CDS_PART_NAME='Q_RES_0402LF-4.7K,5%,1/16W,CHIA',
 WATTAGE='1/16W',
 TOLERANCE='5%',
 MATERIAL='CHIP',
 VALUE='4.7K',
 PRIM_FILE='./archive_libs/logical/q_res/chips/chips.prt';

PART_NAME
 R1004 'Q_RES_0402LF-1K,1%,1/16W,CHIP,A':;

SECTION_NUMBER 1
 '@S9S_MB_2U_LIB.S9S_MB_2U(SCH_1):PAGE127_I35@PURE_QUANTA.Q_RES(CHIPS)':
 C_PATH='@s9s_mb_2u_lib.s9s_mb_2u(sch_1):page127_i35@pure_quanta.q_res(chips)',
 P_PATH='@s9s_mb_2u_lib.s9s_mb_2u(sch_1):page127_i35@pure_quanta.q_res(chips)',
 PATH='I35',
 DRAWING='@S9S_MB_2U_LIB.S9S_MB_2U(SCH_1):PAGE127',
 PHYS_PAGE='127',
 XY='(1075,2000)',
 ROT='0',
 VER='2',
 PACK_TYPE='0402LF',
 CDS_LIB='pure_quanta',
 CDS_PART_NAME='Q_RES_0402LF-1K,1%,1/16W,CHIP,A',
 WATTAGE='1/16W',
 TOLERANCE='1%',
 MATERIAL='CHIP',
 VALUE='1K',
 PRIM_FILE='./archive_libs/logical/q_res/chips/chips.prt';

PART_NAME
 R1005 'Q_RES_0402LF-10K,1%,1/16W,EMPTA':;

SECTION_NUMBER 1
 '@S9S_MB_2U_LIB.S9S_MB_2U(SCH_1):PAGE127_I36@PURE_QUANTA.Q_RES(CHIPS)':
 C_PATH='@s9s_mb_2u_lib.s9s_mb_2u(sch_1):page127_i36@pure_quanta.q_res(chips)',
 P_PATH='@s9s_mb_2u_lib.s9s_mb_2u(sch_1):page127_i36@pure_quanta.q_res(chips)',
 PATH='I36',
 DRAWING='@S9S_MB_2U_LIB.S9S_MB_2U(SCH_1):PAGE127',
 PHYS_PAGE='127',
 XY='(1075,1475)',
 ROT='0',
 VER='2',
 PACK_TYPE='0402LF',
 CDS_LIB='pure_quanta',
 CDS_PART_NAME='Q_RES_0402LF-10K,1%,1/16W,EMPTA',
 WATTAGE='1/16W',
 TOLERANCE='1%',
 MATERIAL='EMPTY',
 VALUE='10K',
 PRIM_FILE='./archive_libs/logical/q_res/chips/chips.prt';

PART_NAME
 R1006 'Q_RES_0402LF-4.7K,5%,1/16W,CHIA':;

SECTION_NUMBER 1
 '@S9S_MB_2U_LIB.S9S_MB_2U(SCH_1):PAGE223_I8@PURE_QUANTA.Q_RES(CHIPS)':
 C_PATH='@s9s_mb_2u_lib.s9s_mb_2u(sch_1):page223_i8@pure_quanta.q_res(chips)',
 P_PATH='@s9s_mb_2u_lib.s9s_mb_2u(sch_1):page235_i8@pure_quanta.q_res(chips)',
 PATH='I8',
 DRAWING='@S9S_MB_2U_LIB.S9S_MB_2U(SCH_1):PAGE223',
 PHYS_PAGE='235',
 XY='(-1350,4325)',
 ROT='0',
 VER='2',
 PACK_TYPE='0402LF',
 CDS_LIB='pure_quanta',
 CDS_PART_NAME='Q_RES_0402LF-4.7K,5%,1/16W,CHIA',
 WATTAGE='1/16W',
 TOLERANCE='5%',
 MATERIAL='CHIP',
 VALUE='4.7K',
 PRIM_FILE='./archive_libs/logical/q_res/chips/chips.prt';

PART_NAME
 R1007 'Q_RES_0402LF-4.7K,5%,1/16W,CHIA':;

SECTION_NUMBER 1
 '@S9S_MB_2U_LIB.S9S_MB_2U(SCH_1):PAGE223_I12@PURE_QUANTA.Q_RES(CHIPS)':
 C_PATH='@s9s_mb_2u_lib.s9s_mb_2u(sch_1):page223_i12@pure_quanta.q_res(chips)',
 P_PATH='@s9s_mb_2u_lib.s9s_mb_2u(sch_1):page235_i12@pure_quanta.q_res(chips)',
 PATH='I12',
 DRAWING='@S9S_MB_2U_LIB.S9S_MB_2U(SCH_1):PAGE223',
 PHYS_PAGE='235',
 XY='(-1350,3025)',
 ROT='0',
 VER='2',
 PACK_TYPE='0402LF',
 CDS_LIB='pure_quanta',
 CDS_PART_NAME='Q_RES_0402LF-4.7K,5%,1/16W,CHIA',
 WATTAGE='1/16W',
 TOLERANCE='5%',
 MATERIAL='CHIP',
 VALUE='4.7K',
 PRIM_FILE='./archive_libs/logical/q_res/chips/chips.prt';

PART_NAME
 R1008 'Q_RES_0402LF-1K,1%,1/16W,EMPTYA':;

SECTION_NUMBER 1
 '@S9S_MB_2U_LIB.S9S_MB_2U(SCH_1):PAGE119_I139@PURE_QUANTA.Q_RES(CHIPS)':
 C_PATH='@s9s_mb_2u_lib.s9s_mb_2u(sch_1):page119_i139@pure_quanta.q_res(chips)',
 P_PATH='@s9s_mb_2u_lib.s9s_mb_2u(sch_1):page119_i139@pure_quanta.q_res(chips)',
 PATH='I139',
 DRAWING='@S9S_MB_2U_LIB.S9S_MB_2U(SCH_1):PAGE119',
 PHYS_PAGE='119',
 XY='(-2100,-1225)',
 ROT='0',
 VER='1',
 PACK_TYPE='0402LF',
 CDS_LIB='pure_quanta',
 CDS_PART_NAME='Q_RES_0402LF-1K,1%,1/16W,EMPTYA',
 WATTAGE='1/16W',
 TOLERANCE='1%',
 MATERIAL='EMPTY',
 VALUE='1K',
 PRIM_FILE='./archive_libs/logical/q_res/chips/chips.prt';

PART_NAME
 R1009 'Q_RES_0402LF-1K,1%,1/16W,EMPTYA':;

SECTION_NUMBER 1
 '@S9S_MB_2U_LIB.S9S_MB_2U(SCH_1):PAGE119_I136@PURE_QUANTA.Q_RES(CHIPS)':
 C_PATH='@s9s_mb_2u_lib.s9s_mb_2u(sch_1):page119_i136@pure_quanta.q_res(chips)',
 P_PATH='@s9s_mb_2u_lib.s9s_mb_2u(sch_1):page119_i136@pure_quanta.q_res(chips)',
 PATH='I136',
 DRAWING='@S9S_MB_2U_LIB.S9S_MB_2U(SCH_1):PAGE119',
 PHYS_PAGE='119',
 XY='(-2075,1925)',
 ROT='0',
 VER='1',
 PACK_TYPE='0402LF',
 CDS_LIB='pure_quanta',
 CDS_PART_NAME='Q_RES_0402LF-1K,1%,1/16W,EMPTYA',
 WATTAGE='1/16W',
 TOLERANCE='1%',
 MATERIAL='EMPTY',
 VALUE='1K',
 PRIM_FILE='./archive_libs/logical/q_res/chips/chips.prt';

PART_NAME
 R1010 'Q_RES_0402LF-0,5%,1/16W,CHIP,CA':;

SECTION_NUMBER 1
 '@S9S_MB_2U_LIB.S9S_MB_2U(SCH_1):PAGE198_I8@PURE_QUANTA.Q_RES(CHIPS)':
 C_PATH='@s9s_mb_2u_lib.s9s_mb_2u(sch_1):page198_i8@pure_quanta.q_res(chips)',
 P_PATH='@s9s_mb_2u_lib.s9s_mb_2u(sch_1):page209_i8@pure_quanta.q_res(chips)',
 PATH='I8',
 DRAWING='@S9S_MB_2U_LIB.S9S_MB_2U(SCH_1):PAGE198',
 PHYS_PAGE='209',
 XY='(-6125,-3650)',
 ROT='0',
 VER='1',
 PACK_TYPE='0402LF',
 CDS_LIB='pure_quanta',
 CDS_PART_NAME='Q_RES_0402LF-0,5%,1/16W,CHIP,CA',
 WATTAGE='1/16W',
 TOLERANCE='5%',
 MATERIAL='CHIP',
 VALUE='0',
 PRIM_FILE='./archive_libs/logical/q_res/chips/chips.prt';

PART_NAME
 R1011 'Q_RES_0402LF-0,5%,1/16W,CHIP,CA':;

SECTION_NUMBER 1
 '@S9S_MB_2U_LIB.S9S_MB_2U(SCH_1):PAGE198_I7@PURE_QUANTA.Q_RES(CHIPS)':
 C_PATH='@s9s_mb_2u_lib.s9s_mb_2u(sch_1):page198_i7@pure_quanta.q_res(chips)',
 P_PATH='@s9s_mb_2u_lib.s9s_mb_2u(sch_1):page209_i7@pure_quanta.q_res(chips)',
 PATH='I7',
 DRAWING='@S9S_MB_2U_LIB.S9S_MB_2U(SCH_1):PAGE198',
 PHYS_PAGE='209',
 XY='(-6125,-3825)',
 ROT='0',
 VER='1',
 PACK_TYPE='0402LF',
 CDS_LIB='pure_quanta',
 CDS_PART_NAME='Q_RES_0402LF-0,5%,1/16W,CHIP,CA',
 WATTAGE='1/16W',
 TOLERANCE='5%',
 MATERIAL='CHIP',
 VALUE='0',
 PRIM_FILE='./archive_libs/logical/q_res/chips/chips.prt';

PART_NAME
 R1012 'Q_RES_0402LF-0,5%,1/16W,CHIP,CA':;

SECTION_NUMBER 1
 '@S9S_MB_2U_LIB.S9S_MB_2U(SCH_1):PAGE198_I22@PURE_QUANTA.Q_RES(CHIPS)':
 C_PATH='@s9s_mb_2u_lib.s9s_mb_2u(sch_1):page198_i22@pure_quanta.q_res(chips)',
 P_PATH='@s9s_mb_2u_lib.s9s_mb_2u(sch_1):page209_i22@pure_quanta.q_res(chips)',
 PATH='I22',
 DRAWING='@S9S_MB_2U_LIB.S9S_MB_2U(SCH_1):PAGE198',
 PHYS_PAGE='209',
 XY='(-6100,-1075)',
 ROT='0',
 VER='1',
 PACK_TYPE='0402LF',
 CDS_LIB='pure_quanta',
 CDS_PART_NAME='Q_RES_0402LF-0,5%,1/16W,CHIP,CA',
 WATTAGE='1/16W',
 TOLERANCE='5%',
 MATERIAL='CHIP',
 VALUE='0',
 PRIM_FILE='./archive_libs/logical/q_res/chips/chips.prt';

PART_NAME
 R1013 'Q_RES_0402LF-0,5%,1/16W,EMPTY,A':;

SECTION_NUMBER 1
 '@S9S_MB_2U_LIB.S9S_MB_2U(SCH_1):PAGE198_I21@PURE_QUANTA.Q_RES(CHIPS)':
 C_PATH='@s9s_mb_2u_lib.s9s_mb_2u(sch_1):page198_i21@pure_quanta.q_res(chips)',
 P_PATH='@s9s_mb_2u_lib.s9s_mb_2u(sch_1):page209_i21@pure_quanta.q_res(chips)',
 PATH='I21',
 DRAWING='@S9S_MB_2U_LIB.S9S_MB_2U(SCH_1):PAGE198',
 PHYS_PAGE='209',
 XY='(-6100,-1250)',
 ROT='0',
 VER='1',
 PACK_TYPE='0402LF',
 CDS_LIB='pure_quanta',
 CDS_PART_NAME='Q_RES_0402LF-0,5%,1/16W,EMPTY,A',
 WATTAGE='1/16W',
 TOLERANCE='5%',
 MATERIAL='EMPTY',
 VALUE='0',
 PRIM_FILE='./archive_libs/logical/q_res/chips/chips.prt';

PART_NAME
 R1014 'Q_RES_0402LF-0,5%,1/16W,CHIP,CA':;

SECTION_NUMBER 1
 '@S9S_MB_2U_LIB.S9S_MB_2U(SCH_1):PAGE198_I20@PURE_QUANTA.Q_RES(CHIPS)':
 C_PATH='@s9s_mb_2u_lib.s9s_mb_2u(sch_1):page198_i20@pure_quanta.q_res(chips)',
 P_PATH='@s9s_mb_2u_lib.s9s_mb_2u(sch_1):page209_i20@pure_quanta.q_res(chips)',
 PATH='I20',
 DRAWING='@S9S_MB_2U_LIB.S9S_MB_2U(SCH_1):PAGE198',
 PHYS_PAGE='209',
 XY='(-6100,-1425)',
 ROT='0',
 VER='1',
 PACK_TYPE='0402LF',
 CDS_LIB='pure_quanta',
 CDS_PART_NAME='Q_RES_0402LF-0,5%,1/16W,CHIP,CA',
 WATTAGE='1/16W',
 TOLERANCE='5%',
 MATERIAL='CHIP',
 VALUE='0',
 PRIM_FILE='./archive_libs/logical/q_res/chips/chips.prt';

PART_NAME
 R1015 'Q_RES_0402LF-0,5%,1/16W,EMPTY,A':;

SECTION_NUMBER 1
 '@S9S_MB_2U_LIB.S9S_MB_2U(SCH_1):PAGE198_I19@PURE_QUANTA.Q_RES(CHIPS)':
 C_PATH='@s9s_mb_2u_lib.s9s_mb_2u(sch_1):page198_i19@pure_quanta.q_res(chips)',
 P_PATH='@s9s_mb_2u_lib.s9s_mb_2u(sch_1):page209_i19@pure_quanta.q_res(chips)',
 PATH='I19',
 DRAWING='@S9S_MB_2U_LIB.S9S_MB_2U(SCH_1):PAGE198',
 PHYS_PAGE='209',
 XY='(-6100,-1600)',
 ROT='0',
 VER='1',
 PACK_TYPE='0402LF',
 CDS_LIB='pure_quanta',
 CDS_PART_NAME='Q_RES_0402LF-0,5%,1/16W,EMPTY,A',
 WATTAGE='1/16W',
 TOLERANCE='5%',
 MATERIAL='EMPTY',
 VALUE='0',
 PRIM_FILE='./archive_libs/logical/q_res/chips/chips.prt';

PART_NAME
 R1016 'Q_RES_0402LF-0,5%,1/16W,CHIP,CA':;

SECTION_NUMBER 1
 '@S9S_MB_2U_LIB.S9S_MB_2U(SCH_1):PAGE198_I12@PURE_QUANTA.Q_RES(CHIPS)':
 C_PATH='@s9s_mb_2u_lib.s9s_mb_2u(sch_1):page198_i12@pure_quanta.q_res(chips)',
 P_PATH='@s9s_mb_2u_lib.s9s_mb_2u(sch_1):page209_i12@pure_quanta.q_res(chips)',
 PATH='I12',
 DRAWING='@S9S_MB_2U_LIB.S9S_MB_2U(SCH_1):PAGE198',
 PHYS_PAGE='209',
 XY='(-6100,-2375)',
 ROT='0',
 VER='1',
 PACK_TYPE='0402LF',
 CDS_LIB='pure_quanta',
 CDS_PART_NAME='Q_RES_0402LF-0,5%,1/16W,CHIP,CA',
 WATTAGE='1/16W',
 TOLERANCE='5%',
 MATERIAL='CHIP',
 VALUE='0',
 PRIM_FILE='./archive_libs/logical/q_res/chips/chips.prt';

PART_NAME
 R1017 'Q_RES_0402LF-0,5%,1/16W,EMPTY,A':;

SECTION_NUMBER 1
 '@S9S_MB_2U_LIB.S9S_MB_2U(SCH_1):PAGE198_I11@PURE_QUANTA.Q_RES(CHIPS)':
 C_PATH='@s9s_mb_2u_lib.s9s_mb_2u(sch_1):page198_i11@pure_quanta.q_res(chips)',
 P_PATH='@s9s_mb_2u_lib.s9s_mb_2u(sch_1):page209_i11@pure_quanta.q_res(chips)',
 PATH='I11',
 DRAWING='@S9S_MB_2U_LIB.S9S_MB_2U(SCH_1):PAGE198',
 PHYS_PAGE='209',
 XY='(-6100,-2550)',
 ROT='0',
 VER='1',
 PACK_TYPE='0402LF',
 CDS_LIB='pure_quanta',
 CDS_PART_NAME='Q_RES_0402LF-0,5%,1/16W,EMPTY,A',
 WATTAGE='1/16W',
 TOLERANCE='5%',
 MATERIAL='EMPTY',
 VALUE='0',
 PRIM_FILE='./archive_libs/logical/q_res/chips/chips.prt';

PART_NAME
 R1018 'Q_RES_0402LF-0,5%,1/16W,CHIP,CA':;

SECTION_NUMBER 1
 '@S9S_MB_2U_LIB.S9S_MB_2U(SCH_1):PAGE198_I10@PURE_QUANTA.Q_RES(CHIPS)':
 C_PATH='@s9s_mb_2u_lib.s9s_mb_2u(sch_1):page198_i10@pure_quanta.q_res(chips)',
 P_PATH='@s9s_mb_2u_lib.s9s_mb_2u(sch_1):page209_i10@pure_quanta.q_res(chips)',
 PATH='I10',
 DRAWING='@S9S_MB_2U_LIB.S9S_MB_2U(SCH_1):PAGE198',
 PHYS_PAGE='209',
 XY='(-6100,-2725)',
 ROT='0',
 VER='1',
 PACK_TYPE='0402LF',
 CDS_LIB='pure_quanta',
 CDS_PART_NAME='Q_RES_0402LF-0,5%,1/16W,CHIP,CA',
 WATTAGE='1/16W',
 TOLERANCE='5%',
 MATERIAL='CHIP',
 VALUE='0',
 PRIM_FILE='./archive_libs/logical/q_res/chips/chips.prt';

PART_NAME
 R1019 'Q_RES_0402LF-0,5%,1/16W,EMPTY,A':;

SECTION_NUMBER 1
 '@S9S_MB_2U_LIB.S9S_MB_2U(SCH_1):PAGE198_I9@PURE_QUANTA.Q_RES(CHIPS)':
 C_PATH='@s9s_mb_2u_lib.s9s_mb_2u(sch_1):page198_i9@pure_quanta.q_res(chips)',
 P_PATH='@s9s_mb_2u_lib.s9s_mb_2u(sch_1):page209_i9@pure_quanta.q_res(chips)',
 PATH='I9',
 DRAWING='@S9S_MB_2U_LIB.S9S_MB_2U(SCH_1):PAGE198',
 PHYS_PAGE='209',
 XY='(-6100,-2900)',
 ROT='0',
 VER='1',
 PACK_TYPE='0402LF',
 CDS_LIB='pure_quanta',
 CDS_PART_NAME='Q_RES_0402LF-0,5%,1/16W,EMPTY,A',
 WATTAGE='1/16W',
 TOLERANCE='5%',
 MATERIAL='EMPTY',
 VALUE='0',
 PRIM_FILE='./archive_libs/logical/q_res/chips/chips.prt';

PART_NAME
 R1020 'Q_RES_0402LF-0,5%,1/16W,CHIP,CA':;

SECTION_NUMBER 1
 '@S9S_MB_2U_LIB.S9S_MB_2U(SCH_1):PAGE198_I30@PURE_QUANTA.Q_RES(CHIPS)':
 C_PATH='@s9s_mb_2u_lib.s9s_mb_2u(sch_1):page198_i30@pure_quanta.q_res(chips)',
 P_PATH='@s9s_mb_2u_lib.s9s_mb_2u(sch_1):page209_i30@pure_quanta.q_res(chips)',
 PATH='I30',
 DRAWING='@S9S_MB_2U_LIB.S9S_MB_2U(SCH_1):PAGE198',
 PHYS_PAGE='209',
 XY='(-4375,-1075)',
 ROT='0',
 VER='1',
 PACK_TYPE='0402LF',
 CDS_LIB='pure_quanta',
 CDS_PART_NAME='Q_RES_0402LF-0,5%,1/16W,CHIP,CA',
 WATTAGE='1/16W',
 TOLERANCE='5%',
 MATERIAL='CHIP',
 VALUE='0',
 PRIM_FILE='./archive_libs/logical/q_res/chips/chips.prt';

PART_NAME
 R1021 'Q_RES_0402LF-0,5%,1/16W,CHIP,CA':;

SECTION_NUMBER 1
 '@S9S_MB_2U_LIB.S9S_MB_2U(SCH_1):PAGE198_I29@PURE_QUANTA.Q_RES(CHIPS)':
 C_PATH='@s9s_mb_2u_lib.s9s_mb_2u(sch_1):page198_i29@pure_quanta.q_res(chips)',
 P_PATH='@s9s_mb_2u_lib.s9s_mb_2u(sch_1):page209_i29@pure_quanta.q_res(chips)',
 PATH='I29',
 DRAWING='@S9S_MB_2U_LIB.S9S_MB_2U(SCH_1):PAGE198',
 PHYS_PAGE='209',
 XY='(-4375,-1425)',
 ROT='0',
 VER='1',
 PACK_TYPE='0402LF',
 CDS_LIB='pure_quanta',
 CDS_PART_NAME='Q_RES_0402LF-0,5%,1/16W,CHIP,CA',
 WATTAGE='1/16W',
 TOLERANCE='5%',
 MATERIAL='CHIP',
 VALUE='0',
 PRIM_FILE='./archive_libs/logical/q_res/chips/chips.prt';

PART_NAME
 R1022 'Q_RES_0402LF-0,5%,1/16W,CHIP,CA':;

SECTION_NUMBER 1
 '@S9S_MB_2U_LIB.S9S_MB_2U(SCH_1):PAGE198_I28@PURE_QUANTA.Q_RES(CHIPS)':
 C_PATH='@s9s_mb_2u_lib.s9s_mb_2u(sch_1):page198_i28@pure_quanta.q_res(chips)',
 P_PATH='@s9s_mb_2u_lib.s9s_mb_2u(sch_1):page209_i28@pure_quanta.q_res(chips)',
 PATH='I28',
 DRAWING='@S9S_MB_2U_LIB.S9S_MB_2U(SCH_1):PAGE198',
 PHYS_PAGE='209',
 XY='(-4375,-2375)',
 ROT='0',
 VER='1',
 PACK_TYPE='0402LF',
 CDS_LIB='pure_quanta',
 CDS_PART_NAME='Q_RES_0402LF-0,5%,1/16W,CHIP,CA',
 WATTAGE='1/16W',
 TOLERANCE='5%',
 MATERIAL='CHIP',
 VALUE='0',
 PRIM_FILE='./archive_libs/logical/q_res/chips/chips.prt';

PART_NAME
 R1023 'Q_RES_0402LF-0,5%,1/16W,CHIP,CA':;

SECTION_NUMBER 1
 '@S9S_MB_2U_LIB.S9S_MB_2U(SCH_1):PAGE198_I27@PURE_QUANTA.Q_RES(CHIPS)':
 C_PATH='@s9s_mb_2u_lib.s9s_mb_2u(sch_1):page198_i27@pure_quanta.q_res(chips)',
 P_PATH='@s9s_mb_2u_lib.s9s_mb_2u(sch_1):page209_i27@pure_quanta.q_res(chips)',
 PATH='I27',
 DRAWING='@S9S_MB_2U_LIB.S9S_MB_2U(SCH_1):PAGE198',
 PHYS_PAGE='209',
 XY='(-4375,-2725)',
 ROT='0',
 VER='1',
 PACK_TYPE='0402LF',
 CDS_LIB='pure_quanta',
 CDS_PART_NAME='Q_RES_0402LF-0,5%,1/16W,CHIP,CA',
 WATTAGE='1/16W',
 TOLERANCE='5%',
 MATERIAL='CHIP',
 VALUE='0',
 PRIM_FILE='./archive_libs/logical/q_res/chips/chips.prt';

PART_NAME
 R1024 'Q_RES_0402LF-100,1%,1/16W,CHIPA':;

SECTION_NUMBER 1
 '@S9S_MB_2U_LIB.S9S_MB_2U(SCH_1):PAGE174_I41@PURE_QUANTA.Q_RES(CHIPS)':
 C_PATH='@s9s_mb_2u_lib.s9s_mb_2u(sch_1):page174_i41@pure_quanta.q_res(chips)',
 P_PATH='@s9s_mb_2u_lib.s9s_mb_2u(sch_1):page182_i41@pure_quanta.q_res(chips)',
 PATH='I41',
 DRAWING='@S9S_MB_2U_LIB.S9S_MB_2U(SCH_1):PAGE174',
 PHYS_PAGE='182',
 XY='(-250,1500)',
 ROT='2',
 VER='2',
 PACK_TYPE='0402LF',
 CDS_LIB='pure_quanta',
 CDS_PART_NAME='Q_RES_0402LF-100,1%,1/16W,CHIPA',
 WATTAGE='1/16W',
 TOLERANCE='1%',
 MATERIAL='CHIP',
 VALUE='100',
 PRIM_FILE='./archive_libs/logical/q_res/chips/chips.prt';

PART_NAME
 R1025 'Q_RES_0402LF-75,1%,1/16W,EMPTYA':;

SECTION_NUMBER 1
 '@S9S_MB_2U_LIB.S9S_MB_2U(SCH_1):PAGE174_I38@PURE_QUANTA.Q_RES(CHIPS)':
 C_PATH='@s9s_mb_2u_lib.s9s_mb_2u(sch_1):page174_i38@pure_quanta.q_res(chips)',
 P_PATH='@s9s_mb_2u_lib.s9s_mb_2u(sch_1):page182_i38@pure_quanta.q_res(chips)',
 PATH='I38',
 DRAWING='@S9S_MB_2U_LIB.S9S_MB_2U(SCH_1):PAGE174',
 PHYS_PAGE='182',
 XY='(-100,1500)',
 ROT='0',
 VER='2',
 PACK_TYPE='0402LF',
 CDS_LIB='pure_quanta',
 CDS_PART_NAME='Q_RES_0402LF-75,1%,1/16W,EMPTYA',
 WATTAGE='1/16W',
 TOLERANCE='1%',
 MATERIAL='EMPTY',
 VALUE='75',
 PRIM_FILE='./archive_libs/logical/q_res/chips/chips.prt';

PART_NAME
 R1026 'Q_RES_0402LF-1K,1%,1/16W,CHIP,A':;

SECTION_NUMBER 1
 '@S9S_MB_2U_LIB.S9S_MB_2U(SCH_1):PAGE174_I37@PURE_QUANTA.Q_RES(CHIPS)':
 C_PATH='@s9s_mb_2u_lib.s9s_mb_2u(sch_1):page174_i37@pure_quanta.q_res(chips)',
 P_PATH='@s9s_mb_2u_lib.s9s_mb_2u(sch_1):page182_i37@pure_quanta.q_res(chips)',
 PATH='I37',
 DRAWING='@S9S_MB_2U_LIB.S9S_MB_2U(SCH_1):PAGE174',
 PHYS_PAGE='182',
 XY='(525,1500)',
 ROT='0',
 VER='2',
 PACK_TYPE='0402LF',
 CDS_LIB='pure_quanta',
 CDS_PART_NAME='Q_RES_0402LF-1K,1%,1/16W,CHIP,A',
 WATTAGE='1/16W',
 TOLERANCE='1%',
 MATERIAL='CHIP',
 VALUE='1K',
 PRIM_FILE='./archive_libs/logical/q_res/chips/chips.prt';

PART_NAME
 R1044 'Q_RES_0402LF-130,1%,1/16W,CHIPA':;

SECTION_NUMBER 1
 '@S9S_MB_2U_LIB.S9S_MB_2U(SCH_1):PAGE241_I40@PURE_QUANTA.Q_RES(CHIPS)':
 C_PATH='@s9s_mb_2u_lib.s9s_mb_2u(sch_1):page241_i40@pure_quanta.q_res(chips)',
 P_PATH='@s9s_mb_2u_lib.s9s_mb_2u(sch_1):page255_i40@pure_quanta.q_res(chips)',
 PATH='I40',
 DRAWING='@S9S_MB_2U_LIB.S9S_MB_2U(SCH_1):PAGE241',
 PHYS_PAGE='255',
 XY='(-11075,700)',
 ROT='0',
 VER='1',
 PACK_TYPE='0402LF',
 CDS_LIB='pure_quanta',
 CDS_PART_NAME='Q_RES_0402LF-130,1%,1/16W,CHIPA',
 WATTAGE='1/16W',
 TOLERANCE='1%',
 MATERIAL='CHIP',
 VALUE='130',
 PRIM_FILE='./archive_libs/logical/q_res/chips/chips.prt';

PART_NAME
 R1089 'Q_RES_0402LF-2.2K,5%,1/16W,CHIA':;

SECTION_NUMBER 1
 '@S9S_MB_2U_LIB.S9S_MB_2U(SCH_1):PAGE219_I21@PURE_QUANTA.Q_RES(CHIPS)':
 C_PATH='@s9s_mb_2u_lib.s9s_mb_2u(sch_1):page219_i21@pure_quanta.q_res(chips)',
 P_PATH='@s9s_mb_2u_lib.s9s_mb_2u(sch_1):page231_i21@pure_quanta.q_res(chips)',
 PATH='I21',
 DRAWING='@S9S_MB_2U_LIB.S9S_MB_2U(SCH_1):PAGE219',
 PHYS_PAGE='231',
 XY='(3875,-1225)',
 ROT='0',
 VER='1',
 PACK_TYPE='0402LF',
 CDS_LIB='pure_quanta',
 CDS_PART_NAME='Q_RES_0402LF-2.2K,5%,1/16W,CHIA',
 WATTAGE='1/16W',
 TOLERANCE='5%',
 MATERIAL='CHIP',
 VALUE='2.2K',
 PRIM_FILE='./archive_libs/logical/q_res/chips/chips.prt';

PART_NAME
 R1090 'Q_RES_0402LF-2.2K,5%,1/16W,CHIA':;

SECTION_NUMBER 1
 '@S9S_MB_2U_LIB.S9S_MB_2U(SCH_1):PAGE219_I20@PURE_QUANTA.Q_RES(CHIPS)':
 C_PATH='@s9s_mb_2u_lib.s9s_mb_2u(sch_1):page219_i20@pure_quanta.q_res(chips)',
 P_PATH='@s9s_mb_2u_lib.s9s_mb_2u(sch_1):page231_i20@pure_quanta.q_res(chips)',
 PATH='I20',
 DRAWING='@S9S_MB_2U_LIB.S9S_MB_2U(SCH_1):PAGE219',
 PHYS_PAGE='231',
 XY='(3875,-1275)',
 ROT='0',
 VER='1',
 PACK_TYPE='0402LF',
 CDS_LIB='pure_quanta',
 CDS_PART_NAME='Q_RES_0402LF-2.2K,5%,1/16W,CHIA',
 WATTAGE='1/16W',
 TOLERANCE='5%',
 MATERIAL='CHIP',
 VALUE='2.2K',
 PRIM_FILE='./archive_libs/logical/q_res/chips/chips.prt';

PART_NAME
 R1099 'Q_RES_0402LF-10K,1%,1/16W,CHIPA':;

SECTION_NUMBER 1
 '@S9S_MB_2U_LIB.S9S_MB_2U(SCH_1):PAGE313_I129@PURE_QUANTA.Q_RES(CHIPS)':
 C_PATH='@s9s_mb_2u_lib.s9s_mb_2u(sch_1):page313_i129@pure_quanta.q_res(chips)',
 P_PATH='@s9s_mb_2u_lib.s9s_mb_2u(sch_1):page214_i129@pure_quanta.q_res(chips)',
 PATH='I129',
 DRAWING='@S9S_MB_2U_LIB.S9S_MB_2U(SCH_1):PAGE313',
 PHYS_PAGE='214',
 XY='(-3725,-2950)',
 ROT='2',
 VER='2',
 PACK_TYPE='0402LF',
 CDS_LIB='pure_quanta',
 CDS_PART_NAME='Q_RES_0402LF-10K,1%,1/16W,CHIPA',
 WATTAGE='1/16W',
 TOLERANCE='1%',
 MATERIAL='CHIP',
 VALUE='10K',
 PRIM_FILE='./archive_libs/logical/q_res/chips/chips.prt';

PART_NAME
 R1100 'Q_RES_0402LF-33.2,1%,1/16W,CHIA':;

SECTION_NUMBER 1
 '@S9S_MB_2U_LIB.S9S_MB_2U(SCH_1):PAGE313_I115@PURE_QUANTA.Q_RES(CHIPS)':
 C_PATH='@s9s_mb_2u_lib.s9s_mb_2u(sch_1):page313_i115@pure_quanta.q_res(chips)',
 P_PATH='@s9s_mb_2u_lib.s9s_mb_2u(sch_1):page214_i115@pure_quanta.q_res(chips)',
 PATH='I115',
 DRAWING='@S9S_MB_2U_LIB.S9S_MB_2U(SCH_1):PAGE313',
 PHYS_PAGE='214',
 XY='(-950,-3025)',
 ROT='0',
 VER='1',
 PACK_TYPE='0402LF',
 CDS_LIB='pure_quanta',
 CDS_PART_NAME='Q_RES_0402LF-33.2,1%,1/16W,CHIA',
 WATTAGE='1/16W',
 TOLERANCE='1%',
 MATERIAL='CHIP',
 VALUE='33.2',
 PRIM_FILE='./archive_libs/logical/q_res/chips/chips.prt';

PART_NAME
 R1106 'Q_RES_0402LF-10K,1%,1/16W,CHIPA':;

SECTION_NUMBER 1
 '@S9S_MB_2U_LIB.S9S_MB_2U(SCH_1):PAGE312_I5@PURE_QUANTA.Q_RES(CHIPS)':
 C_PATH='@s9s_mb_2u_lib.s9s_mb_2u(sch_1):page312_i5@pure_quanta.q_res(chips)',
 P_PATH='@s9s_mb_2u_lib.s9s_mb_2u(sch_1):page215_i5@pure_quanta.q_res(chips)',
 PATH='I5',
 DRAWING='@S9S_MB_2U_LIB.S9S_MB_2U(SCH_1):PAGE312',
 PHYS_PAGE='215',
 XY='(1775,2500)',
 ROT='0',
 VER='2',
 PACK_TYPE='0402LF',
 CDS_LIB='pure_quanta',
 CDS_PART_NAME='Q_RES_0402LF-10K,1%,1/16W,CHIPA',
 WATTAGE='1/16W',
 TOLERANCE='1%',
 MATERIAL='CHIP',
 VALUE='10K',
 PRIM_FILE='./archive_libs/logical/q_res/chips/chips.prt';

PART_NAME
 R1117 'Q_RES_0402LF-6.19K,1%,1/16W,CHA':
 ROOM='HSC1_BOM1';

SECTION_NUMBER 1
 '@S9S_MB_2U_LIB.S9S_MB_2U(SCH_1):PAGE303_I61@PURE_QUANTA.Q_RES(CHIPS)':
 C_PATH='@s9s_mb_2u_lib.s9s_mb_2u(sch_1):page303_i61@pure_quanta.q_res(chips)',
 P_PATH='@s9s_mb_2u_lib.s9s_mb_2u(sch_1):page301_i61@pure_quanta.q_res(chips)',
 PATH='I61',
 DRAWING='@S9S_MB_2U_LIB.S9S_MB_2U(SCH_1):PAGE303',
 PHYS_PAGE='301',
 XY='(-11700,2150)',
 ROT='0',
 VER='2',
 PACK_TYPE='0402LF',
 LOCATION='R1117',
 CDS_LIB='pure_quanta',
 CDS_PART_NAME='Q_RES_0402LF-6.19K,1%,1/16W,CHA',
 WATTAGE='1/16W',
 TOLERANCE='1%',
 MATERIAL='CHIP',
 ROOM='HSC1_BOM1',
 VALUE='6.19K',
 PRIM_FILE='./archive_libs/logical/q_res/chips/chips.prt';

PART_NAME
 R1123 'Q_RES_0402LF-1K,1%,1/16W,EMPTYA':;

SECTION_NUMBER 1
 '@S9S_MB_2U_LIB.S9S_MB_2U(SCH_1):PAGE154_I142@PURE_QUANTA.Q_RES(CHIPS)':
 C_PATH='@s9s_mb_2u_lib.s9s_mb_2u(sch_1):page154_i142@pure_quanta.q_res(chips)',
 P_PATH='@s9s_mb_2u_lib.s9s_mb_2u(sch_1):page158_i142@pure_quanta.q_res(chips)',
 PATH='I142',
 DRAWING='@S9S_MB_2U_LIB.S9S_MB_2U(SCH_1):PAGE154',
 PHYS_PAGE='158',
 XY='(-4825,9600)',
 ROT='0',
 VER='2',
 PACK_TYPE='0402LF',
 CDS_LIB='pure_quanta',
 CDS_PART_NAME='Q_RES_0402LF-1K,1%,1/16W,EMPTYA',
 WATTAGE='1/16W',
 TOLERANCE='1%',
 MATERIAL='EMPTY',
 VALUE='1K',
 PRIM_FILE='./archive_libs/logical/q_res/chips/chips.prt';

PART_NAME
 R1124 'Q_RES_0402LF-1K,1%,1/16W,CHIP,A':;

SECTION_NUMBER 1
 '@S9S_MB_2U_LIB.S9S_MB_2U(SCH_1):PAGE154_I143@PURE_QUANTA.Q_RES(CHIPS)':
 C_PATH='@s9s_mb_2u_lib.s9s_mb_2u(sch_1):page154_i143@pure_quanta.q_res(chips)',
 P_PATH='@s9s_mb_2u_lib.s9s_mb_2u(sch_1):page158_i143@pure_quanta.q_res(chips)',
 PATH='I143',
 DRAWING='@S9S_MB_2U_LIB.S9S_MB_2U(SCH_1):PAGE154',
 PHYS_PAGE='158',
 XY='(-4825,9000)',
 ROT='0',
 VER='2',
 PACK_TYPE='0402LF',
 CDS_LIB='pure_quanta',
 CDS_PART_NAME='Q_RES_0402LF-1K,1%,1/16W,CHIP,A',
 WATTAGE='1/16W',
 TOLERANCE='1%',
 MATERIAL='CHIP',
 VALUE='1K',
 PRIM_FILE='./archive_libs/logical/q_res/chips/chips.prt';

PART_NAME
 R1126 'Q_RES_0402LF-1K,1%,1/16W,CHIP,A':;

SECTION_NUMBER 1
 '@S9S_MB_2U_LIB.S9S_MB_2U(SCH_1):PAGE154_I140@PURE_QUANTA.Q_RES(CHIPS)':
 C_PATH='@s9s_mb_2u_lib.s9s_mb_2u(sch_1):page154_i140@pure_quanta.q_res(chips)',
 P_PATH='@s9s_mb_2u_lib.s9s_mb_2u(sch_1):page158_i140@pure_quanta.q_res(chips)',
 PATH='I140',
 DRAWING='@S9S_MB_2U_LIB.S9S_MB_2U(SCH_1):PAGE154',
 PHYS_PAGE='158',
 XY='(-4575,9000)',
 ROT='0',
 VER='2',
 PACK_TYPE='0402LF',
 CDS_LIB='pure_quanta',
 CDS_PART_NAME='Q_RES_0402LF-1K,1%,1/16W,CHIP,A',
 WATTAGE='1/16W',
 TOLERANCE='1%',
 MATERIAL='CHIP',
 VALUE='1K',
 PRIM_FILE='./archive_libs/logical/q_res/chips/chips.prt';

PART_NAME
 R1127 'Q_RES_0402LF-1K,1%,1/16W,EMPTYA':;

SECTION_NUMBER 1
 '@S9S_MB_2U_LIB.S9S_MB_2U(SCH_1):PAGE154_I133@PURE_QUANTA.Q_RES(CHIPS)':
 C_PATH='@s9s_mb_2u_lib.s9s_mb_2u(sch_1):page154_i133@pure_quanta.q_res(chips)',
 P_PATH='@s9s_mb_2u_lib.s9s_mb_2u(sch_1):page158_i133@pure_quanta.q_res(chips)',
 PATH='I133',
 DRAWING='@S9S_MB_2U_LIB.S9S_MB_2U(SCH_1):PAGE154',
 PHYS_PAGE='158',
 XY='(-4325,9600)',
 ROT='0',
 VER='2',
 PACK_TYPE='0402LF',
 CDS_LIB='pure_quanta',
 CDS_PART_NAME='Q_RES_0402LF-1K,1%,1/16W,EMPTYA',
 WATTAGE='1/16W',
 TOLERANCE='1%',
 MATERIAL='EMPTY',
 VALUE='1K',
 PRIM_FILE='./archive_libs/logical/q_res/chips/chips.prt';

PART_NAME
 R1128 'Q_RES_0402LF-1K,1%,1/16W,CHIP,A':;

SECTION_NUMBER 1
 '@S9S_MB_2U_LIB.S9S_MB_2U(SCH_1):PAGE154_I137@PURE_QUANTA.Q_RES(CHIPS)':
 C_PATH='@s9s_mb_2u_lib.s9s_mb_2u(sch_1):page154_i137@pure_quanta.q_res(chips)',
 P_PATH='@s9s_mb_2u_lib.s9s_mb_2u(sch_1):page158_i137@pure_quanta.q_res(chips)',
 PATH='I137',
 DRAWING='@S9S_MB_2U_LIB.S9S_MB_2U(SCH_1):PAGE154',
 PHYS_PAGE='158',
 XY='(-4325,9000)',
 ROT='0',
 VER='2',
 PACK_TYPE='0402LF',
 CDS_LIB='pure_quanta',
 CDS_PART_NAME='Q_RES_0402LF-1K,1%,1/16W,CHIP,A',
 WATTAGE='1/16W',
 TOLERANCE='1%',
 MATERIAL='CHIP',
 VALUE='1K',
 PRIM_FILE='./archive_libs/logical/q_res/chips/chips.prt';

PART_NAME
 R1129 'Q_RES_0402LF-1K,1%,1/16W,CHIP,A':;

SECTION_NUMBER 1
 '@S9S_MB_2U_LIB.S9S_MB_2U(SCH_1):PAGE154_I172@PURE_QUANTA.Q_RES(CHIPS)':
 C_PATH='@s9s_mb_2u_lib.s9s_mb_2u(sch_1):page154_i172@pure_quanta.q_res(chips)',
 P_PATH='@s9s_mb_2u_lib.s9s_mb_2u(sch_1):page158_i172@pure_quanta.q_res(chips)',
 PATH='I172',
 DRAWING='@S9S_MB_2U_LIB.S9S_MB_2U(SCH_1):PAGE154',
 PHYS_PAGE='158',
 XY='(-4000,5450)',
 ROT='0',
 VER='2',
 PACK_TYPE='0402LF',
 CDS_LIB='pure_quanta',
 CDS_PART_NAME='Q_RES_0402LF-1K,1%,1/16W,CHIP,A',
 WATTAGE='1/16W',
 TOLERANCE='1%',
 MATERIAL='CHIP',
 VALUE='1K',
 PRIM_FILE='./archive_libs/logical/q_res/chips/chips.prt';

PART_NAME
 R1130 'Q_RES_0402LF-33.2,1%,1/16W,CHIA':;

SECTION_NUMBER 1
 '@S9S_MB_2U_LIB.S9S_MB_2U(SCH_1):PAGE154_I130@PURE_QUANTA.Q_RES(CHIPS)':
 C_PATH='@s9s_mb_2u_lib.s9s_mb_2u(sch_1):page154_i130@pure_quanta.q_res(chips)',
 P_PATH='@s9s_mb_2u_lib.s9s_mb_2u(sch_1):page158_i130@pure_quanta.q_res(chips)',
 PATH='I130',
 DRAWING='@S9S_MB_2U_LIB.S9S_MB_2U(SCH_1):PAGE154',
 PHYS_PAGE='158',
 XY='(-2800,8300)',
 ROT='0',
 VER='1',
 PACK_TYPE='0402LF',
 CDS_LIB='pure_quanta',
 CDS_PART_NAME='Q_RES_0402LF-33.2,1%,1/16W,CHIA',
 WATTAGE='1/16W',
 TOLERANCE='1%',
 MATERIAL='CHIP',
 VALUE='33.2',
 PRIM_FILE='./archive_libs/logical/q_res/chips/chips.prt';

PART_NAME
 R1131 'Q_RES_0402LF-33.2,1%,1/16W,CHIA':;

SECTION_NUMBER 1
 '@S9S_MB_2U_LIB.S9S_MB_2U(SCH_1):PAGE154_I131@PURE_QUANTA.Q_RES(CHIPS)':
 C_PATH='@s9s_mb_2u_lib.s9s_mb_2u(sch_1):page154_i131@pure_quanta.q_res(chips)',
 P_PATH='@s9s_mb_2u_lib.s9s_mb_2u(sch_1):page158_i131@pure_quanta.q_res(chips)',
 PATH='I131',
 DRAWING='@S9S_MB_2U_LIB.S9S_MB_2U(SCH_1):PAGE154',
 PHYS_PAGE='158',
 XY='(-2800,8250)',
 ROT='0',
 VER='1',
 PACK_TYPE='0402LF',
 CDS_LIB='pure_quanta',
 CDS_PART_NAME='Q_RES_0402LF-33.2,1%,1/16W,CHIA',
 WATTAGE='1/16W',
 TOLERANCE='1%',
 MATERIAL='CHIP',
 VALUE='33.2',
 PRIM_FILE='./archive_libs/logical/q_res/chips/chips.prt';

PART_NAME
 R1132 'Q_RES_0402LF-1K,1%,1/16W,EMPTYA':;

SECTION_NUMBER 1
 '@S9S_MB_2U_LIB.S9S_MB_2U(SCH_1):PAGE132_I95@PURE_QUANTA.Q_RES(CHIPS)':
 C_PATH='@s9s_mb_2u_lib.s9s_mb_2u(sch_1):page132_i95@pure_quanta.q_res(chips)',
 P_PATH='@s9s_mb_2u_lib.s9s_mb_2u(sch_1):page164_i95@pure_quanta.q_res(chips)',
 PATH='I95',
 DRAWING='@S9S_MB_2U_LIB.S9S_MB_2U(SCH_1):PAGE132',
 PHYS_PAGE='164',
 XY='(-1650,1675)',
 ROT='0',
 VER='2',
 PACK_TYPE='0402LF',
 LOCATION='R1132',
 CDS_LIB='pure_quanta',
 CDS_PART_NAME='Q_RES_0402LF-1K,1%,1/16W,EMPTYA',
 WATTAGE='1/16W',
 TOLERANCE='1%',
 MATERIAL='EMPTY',
 VALUE='1K',
 PRIM_FILE='./archive_libs/logical/q_res/chips/chips.prt';

PART_NAME
 R1138 'Q_RES_0402LF-10K,1%,1/16W,CHIPA':;

SECTION_NUMBER 1
 '@S9S_MB_2U_LIB.S9S_MB_2U(SCH_1):PAGE152_I61@PURE_QUANTA.Q_RES(CHIPS)':
 C_PATH='@s9s_mb_2u_lib.s9s_mb_2u(sch_1):page152_i61@pure_quanta.q_res(chips)',
 P_PATH='@s9s_mb_2u_lib.s9s_mb_2u(sch_1):page155_i61@pure_quanta.q_res(chips)',
 PATH='I61',
 DRAWING='@S9S_MB_2U_LIB.S9S_MB_2U(SCH_1):PAGE152',
 PHYS_PAGE='155',
 XY='(-10400,2575)',
 ROT='2',
 VER='2',
 PACK_TYPE='0402LF',
 CDS_LIB='pure_quanta',
 CDS_PART_NAME='Q_RES_0402LF-10K,1%,1/16W,CHIPA',
 WATTAGE='1/16W',
 TOLERANCE='1%',
 MATERIAL='CHIP',
 VALUE='10K',
 PRIM_FILE='./archive_libs/logical/q_res/chips/chips.prt';

PART_NAME
 R1139 'Q_RES_0402LF-0,5%,1/16W,CHIP,CA':;

SECTION_NUMBER 1
 '@S9S_MB_2U_LIB.S9S_MB_2U(SCH_1):PAGE152_I56@PURE_QUANTA.Q_RES(CHIPS)':
 C_PATH='@s9s_mb_2u_lib.s9s_mb_2u(sch_1):page152_i56@pure_quanta.q_res(chips)',
 P_PATH='@s9s_mb_2u_lib.s9s_mb_2u(sch_1):page155_i56@pure_quanta.q_res(chips)',
 PATH='I56',
 DRAWING='@S9S_MB_2U_LIB.S9S_MB_2U(SCH_1):PAGE152',
 PHYS_PAGE='155',
 XY='(-8325,2375)',
 ROT='0',
 VER='1',
 PACK_TYPE='0402LF',
 CDS_LIB='pure_quanta',
 CDS_PART_NAME='Q_RES_0402LF-0,5%,1/16W,CHIP,CA',
 WATTAGE='1/16W',
 TOLERANCE='5%',
 MATERIAL='CHIP',
 VALUE='0',
 PRIM_FILE='./archive_libs/logical/q_res/chips/chips.prt';

PART_NAME
 R1140 'Q_RES_0402LF-27.4,1%,1/16W,CHIA':;

SECTION_NUMBER 1
 '@S9S_MB_2U_LIB.S9S_MB_2U(SCH_1):PAGE152_I52@PURE_QUANTA.Q_RES(CHIPS)':
 C_PATH='@s9s_mb_2u_lib.s9s_mb_2u(sch_1):page152_i52@pure_quanta.q_res(chips)',
 P_PATH='@s9s_mb_2u_lib.s9s_mb_2u(sch_1):page155_i52@pure_quanta.q_res(chips)',
 PATH='I52',
 DRAWING='@S9S_MB_2U_LIB.S9S_MB_2U(SCH_1):PAGE152',
 PHYS_PAGE='155',
 XY='(-5725,2375)',
 ROT='0',
 VER='1',
 PACK_TYPE='0402LF',
 CDS_LIB='pure_quanta',
 CDS_PART_NAME='Q_RES_0402LF-27.4,1%,1/16W,CHIA',
 WATTAGE='1/16W',
 TOLERANCE='1%',
 MATERIAL='CHIP',
 VALUE='27.4',
 PRIM_FILE='./archive_libs/logical/q_res/chips/chips.prt';

PART_NAME
 R1141 'Q_RES_0402LF-27.4,1%,1/16W,CHIA':;

SECTION_NUMBER 1
 '@S9S_MB_2U_LIB.S9S_MB_2U(SCH_1):PAGE152_I53@PURE_QUANTA.Q_RES(CHIPS)':
 C_PATH='@s9s_mb_2u_lib.s9s_mb_2u(sch_1):page152_i53@pure_quanta.q_res(chips)',
 P_PATH='@s9s_mb_2u_lib.s9s_mb_2u(sch_1):page155_i53@pure_quanta.q_res(chips)',
 PATH='I53',
 DRAWING='@S9S_MB_2U_LIB.S9S_MB_2U(SCH_1):PAGE152',
 PHYS_PAGE='155',
 XY='(-5725,2325)',
 ROT='0',
 VER='1',
 PACK_TYPE='0402LF',
 CDS_LIB='pure_quanta',
 CDS_PART_NAME='Q_RES_0402LF-27.4,1%,1/16W,CHIA',
 WATTAGE='1/16W',
 TOLERANCE='1%',
 MATERIAL='CHIP',
 VALUE='27.4',
 PRIM_FILE='./archive_libs/logical/q_res/chips/chips.prt';

PART_NAME
 R1147 'Q_RES_0402LF-0,5%,1/16W,CHIP,CA':;

SECTION_NUMBER 1
 '@S9S_MB_2U_LIB.S9S_MB_2U(SCH_1):PAGE153_I47@PURE_QUANTA.Q_RES(CHIPS)':
 C_PATH='@s9s_mb_2u_lib.s9s_mb_2u(sch_1):page153_i47@pure_quanta.q_res(chips)',
 P_PATH='@s9s_mb_2u_lib.s9s_mb_2u(sch_1):page156_i47@pure_quanta.q_res(chips)',
 PATH='I47',
 DRAWING='@S9S_MB_2U_LIB.S9S_MB_2U(SCH_1):PAGE153',
 PHYS_PAGE='156',
 XY='(6775,9025)',
 ROT='0',
 VER='1',
 PACK_TYPE='0402LF',
 CDS_LIB='pure_quanta',
 CDS_PART_NAME='Q_RES_0402LF-0,5%,1/16W,CHIP,CA',
 WATTAGE='1/16W',
 TOLERANCE='5%',
 MATERIAL='CHIP',
 VALUE='0',
 PRIM_FILE='./archive_libs/logical/q_res/chips/chips.prt';

PART_NAME
 R1148 'Q_RES_0402LF-0,5%,1/16W,CHIP,CA':;

SECTION_NUMBER 1
 '@S9S_MB_2U_LIB.S9S_MB_2U(SCH_1):PAGE153_I46@PURE_QUANTA.Q_RES(CHIPS)':
 C_PATH='@s9s_mb_2u_lib.s9s_mb_2u(sch_1):page153_i46@pure_quanta.q_res(chips)',
 P_PATH='@s9s_mb_2u_lib.s9s_mb_2u(sch_1):page156_i46@pure_quanta.q_res(chips)',
 PATH='I46',
 DRAWING='@S9S_MB_2U_LIB.S9S_MB_2U(SCH_1):PAGE153',
 PHYS_PAGE='156',
 XY='(6750,8875)',
 ROT='0',
 VER='1',
 PACK_TYPE='0402LF',
 CDS_LIB='pure_quanta',
 CDS_PART_NAME='Q_RES_0402LF-0,5%,1/16W,CHIP,CA',
 WATTAGE='1/16W',
 TOLERANCE='5%',
 MATERIAL='CHIP',
 VALUE='0',
 PRIM_FILE='./archive_libs/logical/q_res/chips/chips.prt';

PART_NAME
 R1149 'Q_RES_0402LF-10K,1%,1/16W,CHIPA':;

SECTION_NUMBER 1
 '@S9S_MB_2U_LIB.S9S_MB_2U(SCH_1):PAGE153_I50@PURE_QUANTA.Q_RES(CHIPS)':
 C_PATH='@s9s_mb_2u_lib.s9s_mb_2u(sch_1):page153_i50@pure_quanta.q_res(chips)',
 P_PATH='@s9s_mb_2u_lib.s9s_mb_2u(sch_1):page156_i50@pure_quanta.q_res(chips)',
 PATH='I50',
 DRAWING='@S9S_MB_2U_LIB.S9S_MB_2U(SCH_1):PAGE153',
 PHYS_PAGE='156',
 XY='(8025,9300)',
 ROT='0',
 VER='2',
 PACK_TYPE='0402LF',
 CDS_LIB='pure_quanta',
 CDS_PART_NAME='Q_RES_0402LF-10K,1%,1/16W,CHIPA',
 WATTAGE='1/16W',
 TOLERANCE='1%',
 MATERIAL='CHIP',
 VALUE='10K',
 PRIM_FILE='./archive_libs/logical/q_res/chips/chips.prt';

PART_NAME
 R1150 'Q_RES_0402LF-10K,1%,1/16W,CHIPA':;

SECTION_NUMBER 1
 '@S9S_MB_2U_LIB.S9S_MB_2U(SCH_1):PAGE153_I74@PURE_QUANTA.Q_RES(CHIPS)':
 C_PATH='@s9s_mb_2u_lib.s9s_mb_2u(sch_1):page153_i74@pure_quanta.q_res(chips)',
 P_PATH='@s9s_mb_2u_lib.s9s_mb_2u(sch_1):page156_i74@pure_quanta.q_res(chips)',
 PATH='I74',
 DRAWING='@S9S_MB_2U_LIB.S9S_MB_2U(SCH_1):PAGE153',
 PHYS_PAGE='156',
 XY='(8250,9300)',
 ROT='0',
 VER='2',
 PACK_TYPE='0402LF',
 CDS_LIB='pure_quanta',
 CDS_PART_NAME='Q_RES_0402LF-10K,1%,1/16W,CHIPA',
 WATTAGE='1/16W',
 TOLERANCE='1%',
 MATERIAL='CHIP',
 VALUE='10K',
 PRIM_FILE='./archive_libs/logical/q_res/chips/chips.prt';

PART_NAME
 R1184 'Q_RES_0402LF-0,5%,1/16W,CHIP,CA':;

SECTION_NUMBER 1
 '@S9S_MB_2U_LIB.S9S_MB_2U(SCH_1):PAGE226_I14@PURE_QUANTA.Q_RES(CHIPS)':
 C_PATH='@s9s_mb_2u_lib.s9s_mb_2u(sch_1):page226_i14@pure_quanta.q_res(chips)',
 P_PATH='@s9s_mb_2u_lib.s9s_mb_2u(sch_1):page239_i14@pure_quanta.q_res(chips)',
 PATH='I14',
 DRAWING='@S9S_MB_2U_LIB.S9S_MB_2U(SCH_1):PAGE226',
 PHYS_PAGE='239',
 XY='(-9850,3200)',
 ROT='0',
 VER='1',
 PACK_TYPE='0402LF',
 CDS_LIB='pure_quanta',
 CDS_PART_NAME='Q_RES_0402LF-0,5%,1/16W,CHIP,CA',
 WATTAGE='1/16W',
 TOLERANCE='5%',
 MATERIAL='CHIP',
 VALUE='0',
 PRIM_FILE='./archive_libs/logical/q_res/chips/chips.prt';

PART_NAME
 R1194 'Q_RES_0402LF-4.75K,1%,1/16W,EMA':;

SECTION_NUMBER 1
 '@S9S_MB_2U_LIB.S9S_MB_2U(SCH_1):PAGE197_I277@PURE_QUANTA.Q_RES(CHIPS)':
 C_PATH='@s9s_mb_2u_lib.s9s_mb_2u(sch_1):page197_i277@pure_quanta.q_res(chips)',
 P_PATH='@s9s_mb_2u_lib.s9s_mb_2u(sch_1):page208_i277@pure_quanta.q_res(chips)',
 PATH='I277',
 DRAWING='@S9S_MB_2U_LIB.S9S_MB_2U(SCH_1):PAGE197',
 PHYS_PAGE='208',
 XY='(-5100,10725)',
 ROT='0',
 VER='2',
 PACK_TYPE='0402LF',
 CDS_LIB='pure_quanta',
 CDS_PART_NAME='Q_RES_0402LF-4.75K,1%,1/16W,EMA',
 WATTAGE='1/16W',
 TOLERANCE='1%',
 MATERIAL='EMPTY',
 VALUE='4.75K',
 PRIM_FILE='./archive_libs/logical/q_res/chips/chips.prt';

PART_NAME
 R1195 'Q_RES_0402LF-130,1%,1/16W,CHIPA':;

SECTION_NUMBER 1
 '@S9S_MB_2U_LIB.S9S_MB_2U(SCH_1):PAGE207_I278@PURE_QUANTA.Q_RES(CHIPS)':
 C_PATH='@s9s_mb_2u_lib.s9s_mb_2u(sch_1):page207_i278@pure_quanta.q_res(chips)',
 P_PATH='@s9s_mb_2u_lib.s9s_mb_2u(sch_1):page218_i278@pure_quanta.q_res(chips)',
 PATH='I278',
 DRAWING='@S9S_MB_2U_LIB.S9S_MB_2U(SCH_1):PAGE207',
 PHYS_PAGE='218',
 XY='(-4250,4700)',
 ROT='0',
 VER='1',
 PACK_TYPE='0402LF',
 LOCATION='R1195',
 CDS_LIB='pure_quanta',
 CDS_PART_NAME='Q_RES_0402LF-130,1%,1/16W,CHIPA',
 WATTAGE='1/16W',
 TOLERANCE='1%',
 MATERIAL='CHIP',
 VALUE='130',
 PRIM_FILE='./archive_libs/logical/q_res/chips/chips.prt';

PART_NAME
 R1196 'Q_RES_0402LF-4.75K,1%,1/16W,CHA':;

SECTION_NUMBER 1
 '@S9S_MB_2U_LIB.S9S_MB_2U(SCH_1):PAGE197_I281@PURE_QUANTA.Q_RES(CHIPS)':
 C_PATH='@s9s_mb_2u_lib.s9s_mb_2u(sch_1):page197_i281@pure_quanta.q_res(chips)',
 P_PATH='@s9s_mb_2u_lib.s9s_mb_2u(sch_1):page208_i281@pure_quanta.q_res(chips)',
 PATH='I281',
 DRAWING='@S9S_MB_2U_LIB.S9S_MB_2U(SCH_1):PAGE197',
 PHYS_PAGE='208',
 XY='(-5100,9800)',
 ROT='0',
 VER='2',
 PACK_TYPE='0402LF',
 CDS_LIB='pure_quanta',
 CDS_PART_NAME='Q_RES_0402LF-4.75K,1%,1/16W,CHA',
 WATTAGE='1/16W',
 TOLERANCE='1%',
 MATERIAL='CHIP',
 VALUE='4.75K',
 PRIM_FILE='./archive_libs/logical/q_res/chips/chips.prt';

PART_NAME
 R1197 'Q_RES_0402LF-1K,1%,1/16W,EMPTYA':;

SECTION_NUMBER 1
 '@S9S_MB_2U_LIB.S9S_MB_2U(SCH_1):PAGE174_I50@PURE_QUANTA.Q_RES(CHIPS)':
 C_PATH='@s9s_mb_2u_lib.s9s_mb_2u(sch_1):page174_i50@pure_quanta.q_res(chips)',
 P_PATH='@s9s_mb_2u_lib.s9s_mb_2u(sch_1):page182_i50@pure_quanta.q_res(chips)',
 PATH='I50',
 DRAWING='@S9S_MB_2U_LIB.S9S_MB_2U(SCH_1):PAGE174',
 PHYS_PAGE='182',
 XY='(-1125,2775)',
 ROT='0',
 VER='1',
 PACK_TYPE='0402LF',
 CDS_LIB='pure_quanta',
 CDS_PART_NAME='Q_RES_0402LF-1K,1%,1/16W,EMPTYA',
 WATTAGE='1/16W',
 TOLERANCE='1%',
 MATERIAL='EMPTY',
 VALUE='1K',
 PRIM_FILE='./archive_libs/logical/q_res/chips/chips.prt';

PART_NAME
 R1198 'Q_RES_0402LF-10K,1%,1/16W,CHIPA':;

SECTION_NUMBER 1
 '@S9S_MB_2U_LIB.S9S_MB_2U(SCH_1):PAGE174_I48@PURE_QUANTA.Q_RES(CHIPS)':
 C_PATH='@s9s_mb_2u_lib.s9s_mb_2u(sch_1):page174_i48@pure_quanta.q_res(chips)',
 P_PATH='@s9s_mb_2u_lib.s9s_mb_2u(sch_1):page182_i48@pure_quanta.q_res(chips)',
 PATH='I48',
 DRAWING='@S9S_MB_2U_LIB.S9S_MB_2U(SCH_1):PAGE174',
 PHYS_PAGE='182',
 XY='(-1850,2425)',
 ROT='0',
 VER='1',
 PACK_TYPE='0402LF',
 CDS_LIB='pure_quanta',
 CDS_PART_NAME='Q_RES_0402LF-10K,1%,1/16W,CHIPA',
 WATTAGE='1/16W',
 TOLERANCE='1%',
 MATERIAL='CHIP',
 VALUE='10K',
 PRIM_FILE='./archive_libs/logical/q_res/chips/chips.prt';

PART_NAME
 R1200 'Q_RES_0402LF-100,1%,1/16W,CHIPA':;

SECTION_NUMBER 1
 '@S9S_MB_2U_LIB.S9S_MB_2U(SCH_1):PAGE174_I60@PURE_QUANTA.Q_RES(CHIPS)':
 C_PATH='@s9s_mb_2u_lib.s9s_mb_2u(sch_1):page174_i60@pure_quanta.q_res(chips)',
 P_PATH='@s9s_mb_2u_lib.s9s_mb_2u(sch_1):page182_i60@pure_quanta.q_res(chips)',
 PATH='I60',
 DRAWING='@S9S_MB_2U_LIB.S9S_MB_2U(SCH_1):PAGE174',
 PHYS_PAGE='182',
 XY='(3850,350)',
 ROT='0',
 VER='1',
 PACK_TYPE='0402LF',
 CDS_LIB='pure_quanta',
 CDS_PART_NAME='Q_RES_0402LF-100,1%,1/16W,CHIPA',
 WATTAGE='1/16W',
 TOLERANCE='1%',
 MATERIAL='CHIP',
 VALUE='100',
 PRIM_FILE='./archive_libs/logical/q_res/chips/chips.prt';

PART_NAME
 R1201 'Q_RES_0402LF-49.9,1%,1/16W,CHIA':;

SECTION_NUMBER 1
 '@S9S_MB_2U_LIB.S9S_MB_2U(SCH_1):PAGE174_I58@PURE_QUANTA.Q_RES(CHIPS)':
 C_PATH='@s9s_mb_2u_lib.s9s_mb_2u(sch_1):page174_i58@pure_quanta.q_res(chips)',
 P_PATH='@s9s_mb_2u_lib.s9s_mb_2u(sch_1):page182_i58@pure_quanta.q_res(chips)',
 PATH='I58',
 DRAWING='@S9S_MB_2U_LIB.S9S_MB_2U(SCH_1):PAGE174',
 PHYS_PAGE='182',
 XY='(3850,100)',
 ROT='0',
 VER='1',
 PACK_TYPE='0402LF',
 CDS_LIB='pure_quanta',
 CDS_PART_NAME='Q_RES_0402LF-49.9,1%,1/16W,CHIA',
 WATTAGE='1/16W',
 TOLERANCE='1%',
 MATERIAL='CHIP',
 VALUE='49.9',
 PRIM_FILE='./archive_libs/logical/q_res/chips/chips.prt';

PART_NAME
 R1202 'Q_RES_0402LF-20K,1%,1/16W,CHIPA':;

SECTION_NUMBER 1
 '@S9S_MB_2U_LIB.S9S_MB_2U(SCH_1):PAGE177_I70@PURE_QUANTA.Q_RES(CHIPS)':
 C_PATH='@s9s_mb_2u_lib.s9s_mb_2u(sch_1):page177_i70@pure_quanta.q_res(chips)',
 P_PATH='@s9s_mb_2u_lib.s9s_mb_2u(sch_1):page185_i70@pure_quanta.q_res(chips)',
 PATH='I70',
 DRAWING='@S9S_MB_2U_LIB.S9S_MB_2U(SCH_1):PAGE177',
 PHYS_PAGE='185',
 XY='(-1400,1075)',
 ROT='0',
 VER='2',
 PACK_TYPE='0402LF',
 CDS_LIB='pure_quanta',
 CDS_PART_NAME='Q_RES_0402LF-20K,1%,1/16W,CHIPA',
 WATTAGE='1/16W',
 TOLERANCE='1%',
 MATERIAL='CHIP',
 VALUE='20K',
 PRIM_FILE='./archive_libs/logical/q_res/chips/chips.prt';

PART_NAME
 R1203 'Q_RES_0402LF-1K,1%,1/16W,CHIP,A':;

SECTION_NUMBER 1
 '@S9S_MB_2U_LIB.S9S_MB_2U(SCH_1):PAGE177_I62@PURE_QUANTA.Q_RES(CHIPS)':
 C_PATH='@s9s_mb_2u_lib.s9s_mb_2u(sch_1):page177_i62@pure_quanta.q_res(chips)',
 P_PATH='@s9s_mb_2u_lib.s9s_mb_2u(sch_1):page185_i62@pure_quanta.q_res(chips)',
 PATH='I62',
 DRAWING='@S9S_MB_2U_LIB.S9S_MB_2U(SCH_1):PAGE177',
 PHYS_PAGE='185',
 XY='(3625,350)',
 ROT='0',
 VER='1',
 PACK_TYPE='0402LF',
 CDS_LIB='pure_quanta',
 CDS_PART_NAME='Q_RES_0402LF-1K,1%,1/16W,CHIP,A',
 WATTAGE='1/16W',
 TOLERANCE='1%',
 MATERIAL='CHIP',
 VALUE='1K',
 PRIM_FILE='./archive_libs/logical/q_res/chips/chips.prt';

PART_NAME
 R1204 'Q_RES_0402LF-10K,1%,1/16W,EMPTA':;

SECTION_NUMBER 1
 '@S9S_MB_2U_LIB.S9S_MB_2U(SCH_1):PAGE197_I273@PURE_QUANTA.Q_RES(CHIPS)':
 C_PATH='@s9s_mb_2u_lib.s9s_mb_2u(sch_1):page197_i273@pure_quanta.q_res(chips)',
 P_PATH='@s9s_mb_2u_lib.s9s_mb_2u(sch_1):page208_i273@pure_quanta.q_res(chips)',
 PATH='I273',
 DRAWING='@S9S_MB_2U_LIB.S9S_MB_2U(SCH_1):PAGE197',
 PHYS_PAGE='208',
 XY='(-4675,10725)',
 ROT='0',
 VER='2',
 PACK_TYPE='0402LF',
 CDS_LIB='pure_quanta',
 CDS_PART_NAME='Q_RES_0402LF-10K,1%,1/16W,EMPTA',
 WATTAGE='1/16W',
 TOLERANCE='1%',
 MATERIAL='EMPTY',
 VALUE='10K',
 PRIM_FILE='./archive_libs/logical/q_res/chips/chips.prt';

PART_NAME
 R1205 'Q_RES_0402LF-33.2,1%,1/16W,CHIA':;

SECTION_NUMBER 1
 '@S9S_MB_2U_LIB.S9S_MB_2U(SCH_1):PAGE212_I7@PURE_QUANTA.Q_RES(CHIPS)':
 C_PATH='@s9s_mb_2u_lib.s9s_mb_2u(sch_1):page212_i7@pure_quanta.q_res(chips)',
 P_PATH='@s9s_mb_2u_lib.s9s_mb_2u(sch_1):page223_i7@pure_quanta.q_res(chips)',
 PATH='I7',
 DRAWING='@S9S_MB_2U_LIB.S9S_MB_2U(SCH_1):PAGE212',
 PHYS_PAGE='223',
 XY='(-2800,2925)',
 ROT='0',
 VER='1',
 PACK_TYPE='0402LF',
 CDS_LIB='pure_quanta',
 CDS_PART_NAME='Q_RES_0402LF-33.2,1%,1/16W,CHIA',
 WATTAGE='1/16W',
 TOLERANCE='1%',
 MATERIAL='CHIP',
 VALUE='33.2',
 PRIM_FILE='./archive_libs/logical/q_res/chips/chips.prt';

PART_NAME
 R1206 'Q_RES_0402LF-33.2,1%,1/16W,CHIA':;

SECTION_NUMBER 1
 '@S9S_MB_2U_LIB.S9S_MB_2U(SCH_1):PAGE212_I10@PURE_QUANTA.Q_RES(CHIPS)':
 C_PATH='@s9s_mb_2u_lib.s9s_mb_2u(sch_1):page212_i10@pure_quanta.q_res(chips)',
 P_PATH='@s9s_mb_2u_lib.s9s_mb_2u(sch_1):page223_i10@pure_quanta.q_res(chips)',
 PATH='I10',
 DRAWING='@S9S_MB_2U_LIB.S9S_MB_2U(SCH_1):PAGE212',
 PHYS_PAGE='223',
 XY='(-2800,2500)',
 ROT='0',
 VER='1',
 PACK_TYPE='0402LF',
 CDS_LIB='pure_quanta',
 CDS_PART_NAME='Q_RES_0402LF-33.2,1%,1/16W,CHIA',
 WATTAGE='1/16W',
 TOLERANCE='1%',
 MATERIAL='CHIP',
 VALUE='33.2',
 PRIM_FILE='./archive_libs/logical/q_res/chips/chips.prt';

PART_NAME
 R1207 'Q_RES_0402LF-33.2,1%,1/16W,CHIA':;

SECTION_NUMBER 1
 '@S9S_MB_2U_LIB.S9S_MB_2U(SCH_1):PAGE212_I15@PURE_QUANTA.Q_RES(CHIPS)':
 C_PATH='@s9s_mb_2u_lib.s9s_mb_2u(sch_1):page212_i15@pure_quanta.q_res(chips)',
 P_PATH='@s9s_mb_2u_lib.s9s_mb_2u(sch_1):page223_i15@pure_quanta.q_res(chips)',
 PATH='I15',
 DRAWING='@S9S_MB_2U_LIB.S9S_MB_2U(SCH_1):PAGE212',
 PHYS_PAGE='223',
 XY='(-2800,2275)',
 ROT='0',
 VER='1',
 PACK_TYPE='0402LF',
 CDS_LIB='pure_quanta',
 CDS_PART_NAME='Q_RES_0402LF-33.2,1%,1/16W,CHIA',
 WATTAGE='1/16W',
 TOLERANCE='1%',
 MATERIAL='CHIP',
 VALUE='33.2',
 PRIM_FILE='./archive_libs/logical/q_res/chips/chips.prt';

PART_NAME
 R1214 'Q_RES_0402LF-0,5%,1/16W,CHIP,CA':;

SECTION_NUMBER 1
 '@S9S_MB_2U_LIB.S9S_MB_2U(SCH_1):PAGE190_I33@PURE_QUANTA.Q_RES(CHIPS)':
 C_PATH='@s9s_mb_2u_lib.s9s_mb_2u(sch_1):page190_i33@pure_quanta.q_res(chips)',
 P_PATH='@s9s_mb_2u_lib.s9s_mb_2u(sch_1):page202_i33@pure_quanta.q_res(chips)',
 PATH='I33',
 DRAWING='@S9S_MB_2U_LIB.S9S_MB_2U(SCH_1):PAGE190',
 PHYS_PAGE='202',
 XY='(-625,3900)',
 ROT='0',
 VER='1',
 PACK_TYPE='0402LF',
 CDS_LIB='pure_quanta',
 CDS_PART_NAME='Q_RES_0402LF-0,5%,1/16W,CHIP,CA',
 WATTAGE='1/16W',
 TOLERANCE='5%',
 MATERIAL='CHIP',
 VALUE='0',
 PRIM_FILE='./archive_libs/logical/q_res/chips/chips.prt';

PART_NAME
 R1215 'Q_RES_0402LF-49.9,1%,1/16W,CHIA':;

SECTION_NUMBER 1
 '@S9S_MB_2U_LIB.S9S_MB_2U(SCH_1):PAGE190_I38@PURE_QUANTA.Q_RES(CHIPS)':
 C_PATH='@s9s_mb_2u_lib.s9s_mb_2u(sch_1):page190_i38@pure_quanta.q_res(chips)',
 P_PATH='@s9s_mb_2u_lib.s9s_mb_2u(sch_1):page202_i38@pure_quanta.q_res(chips)',
 PATH='I38',
 DRAWING='@S9S_MB_2U_LIB.S9S_MB_2U(SCH_1):PAGE190',
 PHYS_PAGE='202',
 XY='(2800,3800)',
 ROT='0',
 VER='1',
 PACK_TYPE='0402LF',
 CDS_LIB='pure_quanta',
 CDS_PART_NAME='Q_RES_0402LF-49.9,1%,1/16W,CHIA',
 WATTAGE='1/16W',
 TOLERANCE='1%',
 MATERIAL='CHIP',
 VALUE='49.9',
 PRIM_FILE='./archive_libs/logical/q_res/chips/chips.prt';

PART_NAME
 R1216 'Q_RES_0402LF-1.5K,1%,1/16W,CHIA':;

SECTION_NUMBER 1
 '@S9S_MB_2U_LIB.S9S_MB_2U(SCH_1):PAGE80_I1@PURE_QUANTA.Q_RES(CHIPS)':
 C_PATH='@s9s_mb_2u_lib.s9s_mb_2u(sch_1):page80_i1@pure_quanta.q_res(chips)',
 P_PATH='@s9s_mb_2u_lib.s9s_mb_2u(sch_1):page80_i1@pure_quanta.q_res(chips)',
 PATH='I1',
 DRAWING='@S9S_MB_2U_LIB.S9S_MB_2U(SCH_1):PAGE80',
 PHYS_PAGE='80',
 XY='(-2375,-1225)',
 ROT='0',
 VER='1',
 PACK_TYPE='0402LF',
 CDS_LIB='pure_quanta',
 CDS_PART_NAME='Q_RES_0402LF-1.5K,1%,1/16W,CHIA',
 WATTAGE='1/16W',
 TOLERANCE='1%',
 MATERIAL='CHIP',
 VALUE='1.5K',
 PRIM_FILE='./archive_libs/logical/q_res/chips/chips.prt';

PART_NAME
 R1217 'Q_RES_0402LF-1.5K,1%,1/16W,CHIA':;

SECTION_NUMBER 1
 '@S9S_MB_2U_LIB.S9S_MB_2U(SCH_1):PAGE80_I22@PURE_QUANTA.Q_RES(CHIPS)':
 C_PATH='@s9s_mb_2u_lib.s9s_mb_2u(sch_1):page80_i22@pure_quanta.q_res(chips)',
 P_PATH='@s9s_mb_2u_lib.s9s_mb_2u(sch_1):page80_i22@pure_quanta.q_res(chips)',
 PATH='I22',
 DRAWING='@S9S_MB_2U_LIB.S9S_MB_2U(SCH_1):PAGE80',
 PHYS_PAGE='80',
 XY='(775,-1225)',
 ROT='0',
 VER='1',
 PACK_TYPE='0402LF',
 CDS_LIB='pure_quanta',
 CDS_PART_NAME='Q_RES_0402LF-1.5K,1%,1/16W,CHIA',
 WATTAGE='1/16W',
 TOLERANCE='1%',
 MATERIAL='CHIP',
 VALUE='1.5K',
 PRIM_FILE='./archive_libs/logical/q_res/chips/chips.prt';

PART_NAME
 R1220 'Q_RES_0402LF-1K,1%,1/16W,EMPTYA':;

SECTION_NUMBER 1
 '@S9S_MB_2U_LIB.S9S_MB_2U(SCH_1):PAGE188_I63@PURE_QUANTA.Q_RES(CHIPS)':
 C_PATH='@s9s_mb_2u_lib.s9s_mb_2u(sch_1):page188_i63@pure_quanta.q_res(chips)',
 P_PATH='@s9s_mb_2u_lib.s9s_mb_2u(sch_1):page200_i63@pure_quanta.q_res(chips)',
 PATH='I63',
 DRAWING='@S9S_MB_2U_LIB.S9S_MB_2U(SCH_1):PAGE188',
 PHYS_PAGE='200',
 XY='(-2950,-450)',
 ROT='0',
 VER='2',
 PACK_TYPE='0402LF',
 CDS_LIB='pure_quanta',
 CDS_PART_NAME='Q_RES_0402LF-1K,1%,1/16W,EMPTYA',
 WATTAGE='1/16W',
 TOLERANCE='1%',
 MATERIAL='EMPTY',
 VALUE='1K',
 PRIM_FILE='./archive_libs/logical/q_res/chips/chips.prt';

PART_NAME
 R1221 'Q_RES_0402LF-1K,1%,1/16W,CHIP,A':;

SECTION_NUMBER 1
 '@S9S_MB_2U_LIB.S9S_MB_2U(SCH_1):PAGE188_I64@PURE_QUANTA.Q_RES(CHIPS)':
 C_PATH='@s9s_mb_2u_lib.s9s_mb_2u(sch_1):page188_i64@pure_quanta.q_res(chips)',
 P_PATH='@s9s_mb_2u_lib.s9s_mb_2u(sch_1):page200_i64@pure_quanta.q_res(chips)',
 PATH='I64',
 DRAWING='@S9S_MB_2U_LIB.S9S_MB_2U(SCH_1):PAGE188',
 PHYS_PAGE='200',
 XY='(-2950,-975)',
 ROT='0',
 VER='2',
 PACK_TYPE='0402LF',
 CDS_LIB='pure_quanta',
 CDS_PART_NAME='Q_RES_0402LF-1K,1%,1/16W,CHIP,A',
 WATTAGE='1/16W',
 TOLERANCE='1%',
 MATERIAL='CHIP',
 VALUE='1K',
 PRIM_FILE='./archive_libs/logical/q_res/chips/chips.prt';

PART_NAME
 R1226 'Q_RES_0402LF-10K,1%,1/16W,CHIPA':;

SECTION_NUMBER 1
 '@S9S_MB_2U_LIB.S9S_MB_2U(SCH_1):PAGE43_I52@PURE_QUANTA.Q_RES(CHIPS)':
 C_PATH='@s9s_mb_2u_lib.s9s_mb_2u(sch_1):page43_i52@pure_quanta.q_res(chips)',
 P_PATH='@s9s_mb_2u_lib.s9s_mb_2u(sch_1):page43_i52@pure_quanta.q_res(chips)',
 PATH='I52',
 DRAWING='@S9S_MB_2U_LIB.S9S_MB_2U(SCH_1):PAGE43',
 PHYS_PAGE='43',
 XY='(4875,50)',
 ROT='0',
 VER='1',
 PACK_TYPE='0402LF',
 CDS_LIB='pure_quanta',
 CDS_PART_NAME='Q_RES_0402LF-10K,1%,1/16W,CHIPA',
 WATTAGE='1/16W',
 TOLERANCE='1%',
 MATERIAL='CHIP',
 VALUE='10K',
 PRIM_FILE='./archive_libs/logical/q_res/chips/chips.prt';

PART_NAME
 R1227 'Q_RES_0402LF-10K,1%,1/16W,CHIPA':;

SECTION_NUMBER 1
 '@S9S_MB_2U_LIB.S9S_MB_2U(SCH_1):PAGE43_I56@PURE_QUANTA.Q_RES(CHIPS)':
 C_PATH='@s9s_mb_2u_lib.s9s_mb_2u(sch_1):page43_i56@pure_quanta.q_res(chips)',
 P_PATH='@s9s_mb_2u_lib.s9s_mb_2u(sch_1):page43_i56@pure_quanta.q_res(chips)',
 PATH='I56',
 DRAWING='@S9S_MB_2U_LIB.S9S_MB_2U(SCH_1):PAGE43',
 PHYS_PAGE='43',
 XY='(4875,-200)',
 ROT='0',
 VER='1',
 PACK_TYPE='0402LF',
 CDS_LIB='pure_quanta',
 CDS_PART_NAME='Q_RES_0402LF-10K,1%,1/16W,CHIPA',
 WATTAGE='1/16W',
 TOLERANCE='1%',
 MATERIAL='CHIP',
 VALUE='10K',
 PRIM_FILE='./archive_libs/logical/q_res/chips/chips.prt';

PART_NAME
 R1229 'Q_RES_0402LF-240,1%,1/16W,EMPTA':;

SECTION_NUMBER 1
 '@S9S_MB_2U_LIB.S9S_MB_2U(SCH_1):PAGE119_I169@PURE_QUANTA.Q_RES(CHIPS)':
 C_PATH='@s9s_mb_2u_lib.s9s_mb_2u(sch_1):page119_i169@pure_quanta.q_res(chips)',
 P_PATH='@s9s_mb_2u_lib.s9s_mb_2u(sch_1):page119_i169@pure_quanta.q_res(chips)',
 PATH='I169',
 DRAWING='@S9S_MB_2U_LIB.S9S_MB_2U(SCH_1):PAGE119',
 PHYS_PAGE='119',
 XY='(-2100,-650)',
 ROT='0',
 VER='1',
 PACK_TYPE='0402LF',
 CDS_LIB='pure_quanta',
 CDS_PART_NAME='Q_RES_0402LF-240,1%,1/16W,EMPTA',
 WATTAGE='1/16W',
 TOLERANCE='1%',
 MATERIAL='EMPTY',
 VALUE='240',
 PRIM_FILE='./archive_libs/logical/q_res/chips/chips.prt';

PART_NAME
 R1230 'Q_RES_0402LF-240,1%,1/16W,EMPTA':;

SECTION_NUMBER 1
 '@S9S_MB_2U_LIB.S9S_MB_2U(SCH_1):PAGE119_I170@PURE_QUANTA.Q_RES(CHIPS)':
 C_PATH='@s9s_mb_2u_lib.s9s_mb_2u(sch_1):page119_i170@pure_quanta.q_res(chips)',
 P_PATH='@s9s_mb_2u_lib.s9s_mb_2u(sch_1):page119_i170@pure_quanta.q_res(chips)',
 PATH='I170',
 DRAWING='@S9S_MB_2U_LIB.S9S_MB_2U(SCH_1):PAGE119',
 PHYS_PAGE='119',
 XY='(-2100,-775)',
 ROT='0',
 VER='1',
 PACK_TYPE='0402LF',
 CDS_LIB='pure_quanta',
 CDS_PART_NAME='Q_RES_0402LF-240,1%,1/16W,EMPTA',
 WATTAGE='1/16W',
 TOLERANCE='1%',
 MATERIAL='EMPTY',
 VALUE='240',
 PRIM_FILE='./archive_libs/logical/q_res/chips/chips.prt';

PART_NAME
 R1232 'Q_RES_0402LF-240,1%,1/16W,EMPTA':;

SECTION_NUMBER 1
 '@S9S_MB_2U_LIB.S9S_MB_2U(SCH_1):PAGE119_I156@PURE_QUANTA.Q_RES(CHIPS)':
 C_PATH='@s9s_mb_2u_lib.s9s_mb_2u(sch_1):page119_i156@pure_quanta.q_res(chips)',
 P_PATH='@s9s_mb_2u_lib.s9s_mb_2u(sch_1):page119_i156@pure_quanta.q_res(chips)',
 PATH='I156',
 DRAWING='@S9S_MB_2U_LIB.S9S_MB_2U(SCH_1):PAGE119',
 PHYS_PAGE='119',
 XY='(-2075,2450)',
 ROT='0',
 VER='1',
 PACK_TYPE='0402LF',
 CDS_LIB='pure_quanta',
 CDS_PART_NAME='Q_RES_0402LF-240,1%,1/16W,EMPTA',
 WATTAGE='1/16W',
 TOLERANCE='1%',
 MATERIAL='EMPTY',
 VALUE='240',
 PRIM_FILE='./archive_libs/logical/q_res/chips/chips.prt';

PART_NAME
 R1233 'Q_RES_0402LF-240,1%,1/16W,EMPTA':;

SECTION_NUMBER 1
 '@S9S_MB_2U_LIB.S9S_MB_2U(SCH_1):PAGE119_I158@PURE_QUANTA.Q_RES(CHIPS)':
 C_PATH='@s9s_mb_2u_lib.s9s_mb_2u(sch_1):page119_i158@pure_quanta.q_res(chips)',
 P_PATH='@s9s_mb_2u_lib.s9s_mb_2u(sch_1):page119_i158@pure_quanta.q_res(chips)',
 PATH='I158',
 DRAWING='@S9S_MB_2U_LIB.S9S_MB_2U(SCH_1):PAGE119',
 PHYS_PAGE='119',
 XY='(-2075,2325)',
 ROT='0',
 VER='1',
 PACK_TYPE='0402LF',
 CDS_LIB='pure_quanta',
 CDS_PART_NAME='Q_RES_0402LF-240,1%,1/16W,EMPTA',
 WATTAGE='1/16W',
 TOLERANCE='1%',
 MATERIAL='EMPTY',
 VALUE='240',
 PRIM_FILE='./archive_libs/logical/q_res/chips/chips.prt';

PART_NAME
 R1235 'Q_RES_0402LF-240,1%,1/16W,EMPTA':;

SECTION_NUMBER 1
 '@S9S_MB_2U_LIB.S9S_MB_2U(SCH_1):PAGE119_I176@PURE_QUANTA.Q_RES(CHIPS)':
 C_PATH='@s9s_mb_2u_lib.s9s_mb_2u(sch_1):page119_i176@pure_quanta.q_res(chips)',
 P_PATH='@s9s_mb_2u_lib.s9s_mb_2u(sch_1):page119_i176@pure_quanta.q_res(chips)',
 PATH='I176',
 DRAWING='@S9S_MB_2U_LIB.S9S_MB_2U(SCH_1):PAGE119',
 PHYS_PAGE='119',
 XY='(250,0)',
 ROT='0',
 VER='1',
 PACK_TYPE='0402LF',
 CDS_LIB='pure_quanta',
 CDS_PART_NAME='Q_RES_0402LF-240,1%,1/16W,EMPTA',
 WATTAGE='1/16W',
 TOLERANCE='1%',
 MATERIAL='EMPTY',
 VALUE='240',
 PRIM_FILE='./archive_libs/logical/q_res/chips/chips.prt';

PART_NAME
 R1236 'Q_RES_0402LF-240,1%,1/16W,EMPTA':;

SECTION_NUMBER 1
 '@S9S_MB_2U_LIB.S9S_MB_2U(SCH_1):PAGE119_I177@PURE_QUANTA.Q_RES(CHIPS)':
 C_PATH='@s9s_mb_2u_lib.s9s_mb_2u(sch_1):page119_i177@pure_quanta.q_res(chips)',
 P_PATH='@s9s_mb_2u_lib.s9s_mb_2u(sch_1):page119_i177@pure_quanta.q_res(chips)',
 PATH='I177',
 DRAWING='@S9S_MB_2U_LIB.S9S_MB_2U(SCH_1):PAGE119',
 PHYS_PAGE='119',
 XY='(250,-125)',
 ROT='0',
 VER='1',
 PACK_TYPE='0402LF',
 CDS_LIB='pure_quanta',
 CDS_PART_NAME='Q_RES_0402LF-240,1%,1/16W,EMPTA',
 WATTAGE='1/16W',
 TOLERANCE='1%',
 MATERIAL='EMPTY',
 VALUE='240',
 PRIM_FILE='./archive_libs/logical/q_res/chips/chips.prt';

PART_NAME
 R1237 'Q_RES_0402LF-240,1%,1/16W,EMPTA':;

SECTION_NUMBER 1
 '@S9S_MB_2U_LIB.S9S_MB_2U(SCH_1):PAGE119_I160@PURE_QUANTA.Q_RES(CHIPS)':
 C_PATH='@s9s_mb_2u_lib.s9s_mb_2u(sch_1):page119_i160@pure_quanta.q_res(chips)',
 P_PATH='@s9s_mb_2u_lib.s9s_mb_2u(sch_1):page119_i160@pure_quanta.q_res(chips)',
 PATH='I160',
 DRAWING='@S9S_MB_2U_LIB.S9S_MB_2U(SCH_1):PAGE119',
 PHYS_PAGE='119',
 XY='(275,3100)',
 ROT='0',
 VER='1',
 PACK_TYPE='0402LF',
 CDS_LIB='pure_quanta',
 CDS_PART_NAME='Q_RES_0402LF-240,1%,1/16W,EMPTA',
 WATTAGE='1/16W',
 TOLERANCE='1%',
 MATERIAL='EMPTY',
 VALUE='240',
 PRIM_FILE='./archive_libs/logical/q_res/chips/chips.prt';

PART_NAME
 R1238 'Q_RES_0402LF-240,1%,1/16W,EMPTA':;

SECTION_NUMBER 1
 '@S9S_MB_2U_LIB.S9S_MB_2U(SCH_1):PAGE119_I161@PURE_QUANTA.Q_RES(CHIPS)':
 C_PATH='@s9s_mb_2u_lib.s9s_mb_2u(sch_1):page119_i161@pure_quanta.q_res(chips)',
 P_PATH='@s9s_mb_2u_lib.s9s_mb_2u(sch_1):page119_i161@pure_quanta.q_res(chips)',
 PATH='I161',
 DRAWING='@S9S_MB_2U_LIB.S9S_MB_2U(SCH_1):PAGE119',
 PHYS_PAGE='119',
 XY='(275,2975)',
 ROT='0',
 VER='1',
 PACK_TYPE='0402LF',
 CDS_LIB='pure_quanta',
 CDS_PART_NAME='Q_RES_0402LF-240,1%,1/16W,EMPTA',
 WATTAGE='1/16W',
 TOLERANCE='1%',
 MATERIAL='EMPTY',
 VALUE='240',
 PRIM_FILE='./archive_libs/logical/q_res/chips/chips.prt';

PART_NAME
 R1239 'Q_RES_0402LF-240,1%,1/16W,EMPTA':;

SECTION_NUMBER 1
 '@S9S_MB_2U_LIB.S9S_MB_2U(SCH_1):PAGE119_I163@PURE_QUANTA.Q_RES(CHIPS)':
 C_PATH='@s9s_mb_2u_lib.s9s_mb_2u(sch_1):page119_i163@pure_quanta.q_res(chips)',
 P_PATH='@s9s_mb_2u_lib.s9s_mb_2u(sch_1):page119_i163@pure_quanta.q_res(chips)',
 PATH='I163',
 DRAWING='@S9S_MB_2U_LIB.S9S_MB_2U(SCH_1):PAGE119',
 PHYS_PAGE='119',
 XY='(275,2850)',
 ROT='0',
 VER='1',
 PACK_TYPE='0402LF',
 CDS_LIB='pure_quanta',
 CDS_PART_NAME='Q_RES_0402LF-240,1%,1/16W,EMPTA',
 WATTAGE='1/16W',
 TOLERANCE='1%',
 MATERIAL='EMPTY',
 VALUE='240',
 PRIM_FILE='./archive_libs/logical/q_res/chips/chips.prt';

PART_NAME
 R1240 'Q_RES_0402LF-0,5%,1/16W,CHIP,CA':;

SECTION_NUMBER 1
 '@S9S_MB_2U_LIB.S9S_MB_2U(SCH_1):PAGE117_I9@PURE_QUANTA.Q_RES(CHIPS)':
 C_PATH='@s9s_mb_2u_lib.s9s_mb_2u(sch_1):page117_i9@pure_quanta.q_res(chips)',
 P_PATH='@s9s_mb_2u_lib.s9s_mb_2u(sch_1):page117_i9@pure_quanta.q_res(chips)',
 PATH='I9',
 DRAWING='@S9S_MB_2U_LIB.S9S_MB_2U(SCH_1):PAGE117',
 PHYS_PAGE='117',
 XY='(-2175,3350)',
 ROT='0',
 VER='1',
 PACK_TYPE='0402LF',
 CDS_LIB='pure_quanta',
 CDS_PART_NAME='Q_RES_0402LF-0,5%,1/16W,CHIP,CA',
 WATTAGE='1/16W',
 TOLERANCE='5%',
 MATERIAL='CHIP',
 VALUE='0',
 PRIM_FILE='./archive_libs/logical/q_res/chips/chips.prt';

PART_NAME
 R1241 'Q_RES_0402LF-249,1%,1/16W,CHIPA':;

SECTION_NUMBER 1
 '@S9S_MB_2U_LIB.S9S_MB_2U(SCH_1):PAGE117_I17@PURE_QUANTA.Q_RES(CHIPS)':
 C_PATH='@s9s_mb_2u_lib.s9s_mb_2u(sch_1):page117_i17@pure_quanta.q_res(chips)',
 P_PATH='@s9s_mb_2u_lib.s9s_mb_2u(sch_1):page117_i17@pure_quanta.q_res(chips)',
 PATH='I17',
 DRAWING='@S9S_MB_2U_LIB.S9S_MB_2U(SCH_1):PAGE117',
 PHYS_PAGE='117',
 XY='(-3100,5100)',
 ROT='0',
 VER='2',
 PACK_TYPE='0402LF',
 CDS_LIB='pure_quanta',
 CDS_PART_NAME='Q_RES_0402LF-249,1%,1/16W,CHIPA',
 WATTAGE='1/16W',
 TOLERANCE='1%',
 MATERIAL='CHIP',
 VALUE='249',
 PRIM_FILE='./archive_libs/logical/q_res/chips/chips.prt';

PART_NAME
 R1242 'Q_RES_0402LF-301,1%,1/16W,CHIPA':;

SECTION_NUMBER 1
 '@S9S_MB_2U_LIB.S9S_MB_2U(SCH_1):PAGE117_I13@PURE_QUANTA.Q_RES(CHIPS)':
 C_PATH='@s9s_mb_2u_lib.s9s_mb_2u(sch_1):page117_i13@pure_quanta.q_res(chips)',
 P_PATH='@s9s_mb_2u_lib.s9s_mb_2u(sch_1):page117_i13@pure_quanta.q_res(chips)',
 PATH='I13',
 DRAWING='@S9S_MB_2U_LIB.S9S_MB_2U(SCH_1):PAGE117',
 PHYS_PAGE='117',
 XY='(-1875,3650)',
 ROT='0',
 VER='2',
 PACK_TYPE='0402LF',
 CDS_LIB='pure_quanta',
 CDS_PART_NAME='Q_RES_0402LF-301,1%,1/16W,CHIPA',
 WATTAGE='1/16W',
 TOLERANCE='1%',
 MATERIAL='CHIP',
 VALUE='301',
 PRIM_FILE='./archive_libs/logical/q_res/chips/chips.prt';

PART_NAME
 R1243 'Q_RES_0402LF-249,1%,1/16W,CHIPA':;

SECTION_NUMBER 1
 '@S9S_MB_2U_LIB.S9S_MB_2U(SCH_1):PAGE117_I19@PURE_QUANTA.Q_RES(CHIPS)':
 C_PATH='@s9s_mb_2u_lib.s9s_mb_2u(sch_1):page117_i19@pure_quanta.q_res(chips)',
 P_PATH='@s9s_mb_2u_lib.s9s_mb_2u(sch_1):page117_i19@pure_quanta.q_res(chips)',
 PATH='I19',
 DRAWING='@S9S_MB_2U_LIB.S9S_MB_2U(SCH_1):PAGE117',
 PHYS_PAGE='117',
 XY='(-2825,5100)',
 ROT='0',
 VER='2',
 PACK_TYPE='0402LF',
 CDS_LIB='pure_quanta',
 CDS_PART_NAME='Q_RES_0402LF-249,1%,1/16W,CHIPA',
 WATTAGE='1/16W',
 TOLERANCE='1%',
 MATERIAL='CHIP',
 VALUE='249',
 PRIM_FILE='./archive_libs/logical/q_res/chips/chips.prt';

PART_NAME
 R1244 'Q_RES_0402LF-301,1%,1/16W,CHIPA':;

SECTION_NUMBER 1
 '@S9S_MB_2U_LIB.S9S_MB_2U(SCH_1):PAGE117_I16@PURE_QUANTA.Q_RES(CHIPS)':
 C_PATH='@s9s_mb_2u_lib.s9s_mb_2u(sch_1):page117_i16@pure_quanta.q_res(chips)',
 P_PATH='@s9s_mb_2u_lib.s9s_mb_2u(sch_1):page117_i16@pure_quanta.q_res(chips)',
 PATH='I16',
 DRAWING='@S9S_MB_2U_LIB.S9S_MB_2U(SCH_1):PAGE117',
 PHYS_PAGE='117',
 XY='(-1075,3650)',
 ROT='0',
 VER='2',
 PACK_TYPE='0402LF',
 CDS_LIB='pure_quanta',
 CDS_PART_NAME='Q_RES_0402LF-301,1%,1/16W,CHIPA',
 WATTAGE='1/16W',
 TOLERANCE='1%',
 MATERIAL='CHIP',
 VALUE='301',
 PRIM_FILE='./archive_libs/logical/q_res/chips/chips.prt';

PART_NAME
 R1247 'Q_RES_0402LF-0,5%,1/16W,CHIP,CA':;

SECTION_NUMBER 1
 '@S9S_MB_2U_LIB.S9S_MB_2U(SCH_1):PAGE191_I14@PURE_QUANTA.Q_RES(CHIPS)':
 C_PATH='@s9s_mb_2u_lib.s9s_mb_2u(sch_1):page191_i14@pure_quanta.q_res(chips)',
 P_PATH='@s9s_mb_2u_lib.s9s_mb_2u(sch_1):page203_i14@pure_quanta.q_res(chips)',
 PATH='I14',
 DRAWING='@S9S_MB_2U_LIB.S9S_MB_2U(SCH_1):PAGE191',
 PHYS_PAGE='203',
 XY='(-1675,975)',
 ROT='0',
 VER='1',
 PACK_TYPE='0402LF',
 CDS_LIB='pure_quanta',
 CDS_PART_NAME='Q_RES_0402LF-0,5%,1/16W,CHIP,CA',
 WATTAGE='1/16W',
 TOLERANCE='5%',
 MATERIAL='CHIP',
 VALUE='0',
 PRIM_FILE='./archive_libs/logical/q_res/chips/chips.prt';

PART_NAME
 R1249 'Q_RES_0402LF-0,5%,1/16W,CHIP,CA':;

SECTION_NUMBER 1
 '@S9S_MB_2U_LIB.S9S_MB_2U(SCH_1):PAGE191_I2@PURE_QUANTA.Q_RES(CHIPS)':
 C_PATH='@s9s_mb_2u_lib.s9s_mb_2u(sch_1):page191_i2@pure_quanta.q_res(chips)',
 P_PATH='@s9s_mb_2u_lib.s9s_mb_2u(sch_1):page203_i2@pure_quanta.q_res(chips)',
 PATH='I2',
 DRAWING='@S9S_MB_2U_LIB.S9S_MB_2U(SCH_1):PAGE191',
 PHYS_PAGE='203',
 XY='(-1675,4150)',
 ROT='0',
 VER='1',
 PACK_TYPE='0402LF',
 CDS_LIB='pure_quanta',
 CDS_PART_NAME='Q_RES_0402LF-0,5%,1/16W,CHIP,CA',
 WATTAGE='1/16W',
 TOLERANCE='5%',
 MATERIAL='CHIP',
 VALUE='0',
 PRIM_FILE='./archive_libs/logical/q_res/chips/chips.prt';

PART_NAME
 R1253 'Q_RES_0402LF-1K,1%,1/16W,CHIP,A':;

SECTION_NUMBER 1
 '@S9S_MB_2U_LIB.S9S_MB_2U(SCH_1):PAGE192_I23@PURE_QUANTA.Q_RES(CHIPS)':
 C_PATH='@s9s_mb_2u_lib.s9s_mb_2u(sch_1):page192_i23@pure_quanta.q_res(chips)',
 P_PATH='@s9s_mb_2u_lib.s9s_mb_2u(sch_1):page204_i23@pure_quanta.q_res(chips)',
 PATH='I23',
 DRAWING='@S9S_MB_2U_LIB.S9S_MB_2U(SCH_1):PAGE192',
 PHYS_PAGE='204',
 XY='(-4950,3125)',
 ROT='0',
 VER='1',
 PACK_TYPE='0402LF',
 CDS_LIB='pure_quanta',
 CDS_PART_NAME='Q_RES_0402LF-1K,1%,1/16W,CHIP,A',
 WATTAGE='1/16W',
 TOLERANCE='1%',
 MATERIAL='CHIP',
 VALUE='1K',
 PRIM_FILE='./archive_libs/logical/q_res/chips/chips.prt';

PART_NAME
 R1254 'Q_RES_0402LF-10K,1%,1/16W,CHIPA':;

SECTION_NUMBER 1
 '@S9S_MB_2U_LIB.S9S_MB_2U(SCH_1):PAGE192_I24@PURE_QUANTA.Q_RES(CHIPS)':
 C_PATH='@s9s_mb_2u_lib.s9s_mb_2u(sch_1):page192_i24@pure_quanta.q_res(chips)',
 P_PATH='@s9s_mb_2u_lib.s9s_mb_2u(sch_1):page204_i24@pure_quanta.q_res(chips)',
 PATH='I24',
 DRAWING='@S9S_MB_2U_LIB.S9S_MB_2U(SCH_1):PAGE192',
 PHYS_PAGE='204',
 XY='(-4950,3000)',
 ROT='0',
 VER='1',
 PACK_TYPE='0402LF',
 CDS_LIB='pure_quanta',
 CDS_PART_NAME='Q_RES_0402LF-10K,1%,1/16W,CHIPA',
 WATTAGE='1/16W',
 TOLERANCE='1%',
 MATERIAL='CHIP',
 VALUE='10K',
 PRIM_FILE='./archive_libs/logical/q_res/chips/chips.prt';

PART_NAME
 R1255 'Q_RES_0402LF-1K,1%,1/16W,CHIP,A':;

SECTION_NUMBER 1
 '@S9S_MB_2U_LIB.S9S_MB_2U(SCH_1):PAGE192_I26@PURE_QUANTA.Q_RES(CHIPS)':
 C_PATH='@s9s_mb_2u_lib.s9s_mb_2u(sch_1):page192_i26@pure_quanta.q_res(chips)',
 P_PATH='@s9s_mb_2u_lib.s9s_mb_2u(sch_1):page204_i26@pure_quanta.q_res(chips)',
 PATH='I26',
 DRAWING='@S9S_MB_2U_LIB.S9S_MB_2U(SCH_1):PAGE192',
 PHYS_PAGE='204',
 XY='(-4950,2875)',
 ROT='0',
 VER='1',
 PACK_TYPE='0402LF',
 CDS_LIB='pure_quanta',
 CDS_PART_NAME='Q_RES_0402LF-1K,1%,1/16W,CHIP,A',
 WATTAGE='1/16W',
 TOLERANCE='1%',
 MATERIAL='CHIP',
 VALUE='1K',
 PRIM_FILE='./archive_libs/logical/q_res/chips/chips.prt';

PART_NAME
 R1257 'Q_RES_0402LF-10K,1%,1/16W,CHIPA':;

SECTION_NUMBER 1
 '@S9S_MB_2U_LIB.S9S_MB_2U(SCH_1):PAGE192_I4@PURE_QUANTA.Q_RES(CHIPS)':
 C_PATH='@s9s_mb_2u_lib.s9s_mb_2u(sch_1):page192_i4@pure_quanta.q_res(chips)',
 P_PATH='@s9s_mb_2u_lib.s9s_mb_2u(sch_1):page204_i4@pure_quanta.q_res(chips)',
 PATH='I4',
 DRAWING='@S9S_MB_2U_LIB.S9S_MB_2U(SCH_1):PAGE192',
 PHYS_PAGE='204',
 XY='(1150,3025)',
 ROT='0',
 VER='1',
 PACK_TYPE='0402LF',
 CDS_LIB='pure_quanta',
 CDS_PART_NAME='Q_RES_0402LF-10K,1%,1/16W,CHIPA',
 WATTAGE='1/16W',
 TOLERANCE='1%',
 MATERIAL='CHIP',
 VALUE='10K',
 PRIM_FILE='./archive_libs/logical/q_res/chips/chips.prt';

PART_NAME
 R1259 'Q_RES_0402LF-10K,1%,1/16W,CHIPA':;

SECTION_NUMBER 1
 '@S9S_MB_2U_LIB.S9S_MB_2U(SCH_1):PAGE192_I8@PURE_QUANTA.Q_RES(CHIPS)':
 C_PATH='@s9s_mb_2u_lib.s9s_mb_2u(sch_1):page192_i8@pure_quanta.q_res(chips)',
 P_PATH='@s9s_mb_2u_lib.s9s_mb_2u(sch_1):page204_i8@pure_quanta.q_res(chips)',
 PATH='I8',
 DRAWING='@S9S_MB_2U_LIB.S9S_MB_2U(SCH_1):PAGE192',
 PHYS_PAGE='204',
 XY='(1150,2750)',
 ROT='0',
 VER='1',
 PACK_TYPE='0402LF',
 CDS_LIB='pure_quanta',
 CDS_PART_NAME='Q_RES_0402LF-10K,1%,1/16W,CHIPA',
 WATTAGE='1/16W',
 TOLERANCE='1%',
 MATERIAL='CHIP',
 VALUE='10K',
 PRIM_FILE='./archive_libs/logical/q_res/chips/chips.prt';

PART_NAME
 R1260 'Q_RES_0402LF-10K,1%,1/16W,EMPTA':;

SECTION_NUMBER 1
 '@S9S_MB_2U_LIB.S9S_MB_2U(SCH_1):PAGE192_I17@PURE_QUANTA.Q_RES(CHIPS)':
 C_PATH='@s9s_mb_2u_lib.s9s_mb_2u(sch_1):page192_i17@pure_quanta.q_res(chips)',
 P_PATH='@s9s_mb_2u_lib.s9s_mb_2u(sch_1):page204_i17@pure_quanta.q_res(chips)',
 PATH='I17',
 DRAWING='@S9S_MB_2U_LIB.S9S_MB_2U(SCH_1):PAGE192',
 PHYS_PAGE='204',
 XY='(1200,1300)',
 ROT='0',
 VER='1',
 PACK_TYPE='0402LF',
 CDS_LIB='pure_quanta',
 CDS_PART_NAME='Q_RES_0402LF-10K,1%,1/16W,EMPTA',
 WATTAGE='1/16W',
 TOLERANCE='1%',
 MATERIAL='EMPTY',
 VALUE='10K',
 PRIM_FILE='./archive_libs/logical/q_res/chips/chips.prt';

PART_NAME
 R1262 'Q_RES_0402LF-10K,1%,1/16W,EMPTA':;

SECTION_NUMBER 1
 '@S9S_MB_2U_LIB.S9S_MB_2U(SCH_1):PAGE192_I11@PURE_QUANTA.Q_RES(CHIPS)':
 C_PATH='@s9s_mb_2u_lib.s9s_mb_2u(sch_1):page192_i11@pure_quanta.q_res(chips)',
 P_PATH='@s9s_mb_2u_lib.s9s_mb_2u(sch_1):page204_i11@pure_quanta.q_res(chips)',
 PATH='I11',
 DRAWING='@S9S_MB_2U_LIB.S9S_MB_2U(SCH_1):PAGE192',
 PHYS_PAGE='204',
 XY='(1200,1050)',
 ROT='0',
 VER='1',
 PACK_TYPE='0402LF',
 CDS_LIB='pure_quanta',
 CDS_PART_NAME='Q_RES_0402LF-10K,1%,1/16W,EMPTA',
 WATTAGE='1/16W',
 TOLERANCE='1%',
 MATERIAL='EMPTY',
 VALUE='10K',
 PRIM_FILE='./archive_libs/logical/q_res/chips/chips.prt';

PART_NAME
 R1263 'Q_RES_0402LF-33.2,1%,1/16W,CHIA':;

SECTION_NUMBER 1
 '@S9S_MB_2U_LIB.S9S_MB_2U(SCH_1):PAGE191_I29@PURE_QUANTA.Q_RES(CHIPS)':
 C_PATH='@s9s_mb_2u_lib.s9s_mb_2u(sch_1):page191_i29@pure_quanta.q_res(chips)',
 P_PATH='@s9s_mb_2u_lib.s9s_mb_2u(sch_1):page203_i29@pure_quanta.q_res(chips)',
 PATH='I29',
 DRAWING='@S9S_MB_2U_LIB.S9S_MB_2U(SCH_1):PAGE191',
 PHYS_PAGE='203',
 XY='(-1750,3125)',
 ROT='0',
 VER='1',
 PACK_TYPE='0402LF',
 CDS_LIB='pure_quanta',
 CDS_PART_NAME='Q_RES_0402LF-33.2,1%,1/16W,CHIA',
 WATTAGE='1/16W',
 TOLERANCE='1%',
 MATERIAL='CHIP',
 VALUE='33.2',
 PRIM_FILE='./archive_libs/logical/q_res/chips/chips.prt';

PART_NAME
 R1266 'Q_RES_0402LF-75,1%,1/16W,CHIP,A':;

SECTION_NUMBER 1
 '@S9S_MB_2U_LIB.S9S_MB_2U(SCH_1):PAGE191_I38@PURE_QUANTA.Q_RES(CHIPS)':
 C_PATH='@s9s_mb_2u_lib.s9s_mb_2u(sch_1):page191_i38@pure_quanta.q_res(chips)',
 P_PATH='@s9s_mb_2u_lib.s9s_mb_2u(sch_1):page203_i38@pure_quanta.q_res(chips)',
 PATH='I38',
 DRAWING='@S9S_MB_2U_LIB.S9S_MB_2U(SCH_1):PAGE191',
 PHYS_PAGE='203',
 XY='(175,4400)',
 ROT='0',
 VER='2',
 PACK_TYPE='0402LF',
 LOCATION='R1266',
 CDS_LIB='pure_quanta',
 CDS_PART_NAME='Q_RES_0402LF-75,1%,1/16W,CHIP,A',
 WATTAGE='1/16W',
 TOLERANCE='1%',
 MATERIAL='CHIP',
 VALUE='75',
 PRIM_FILE='./archive_libs/logical/q_res/chips/chips.prt';

PART_NAME
 R1267 'Q_RES_0402LF-1K,1%,1/16W,CHIP,A':;

SECTION_NUMBER 1
 '@S9S_MB_2U_LIB.S9S_MB_2U(SCH_1):PAGE197_I276@PURE_QUANTA.Q_RES(CHIPS)':
 C_PATH='@s9s_mb_2u_lib.s9s_mb_2u(sch_1):page197_i276@pure_quanta.q_res(chips)',
 P_PATH='@s9s_mb_2u_lib.s9s_mb_2u(sch_1):page208_i276@pure_quanta.q_res(chips)',
 PATH='I276',
 DRAWING='@S9S_MB_2U_LIB.S9S_MB_2U(SCH_1):PAGE197',
 PHYS_PAGE='208',
 XY='(-4675,9800)',
 ROT='0',
 VER='2',
 PACK_TYPE='0402LF',
 CDS_LIB='pure_quanta',
 CDS_PART_NAME='Q_RES_0402LF-1K,1%,1/16W,CHIP,A',
 WATTAGE='1/16W',
 TOLERANCE='1%',
 MATERIAL='CHIP',
 VALUE='1K',
 PRIM_FILE='./archive_libs/logical/q_res/chips/chips.prt';

PART_NAME
 R1268 'Q_RES_0402LF-33.2,1%,1/16W,CHIA':;

SECTION_NUMBER 1
 '@S9S_MB_2U_LIB.S9S_MB_2U(SCH_1):PAGE175_I222@PURE_QUANTA.Q_RES(CHIPS)':
 C_PATH='@s9s_mb_2u_lib.s9s_mb_2u(sch_1):page175_i222@pure_quanta.q_res(chips)',
 P_PATH='@s9s_mb_2u_lib.s9s_mb_2u(sch_1):page183_i222@pure_quanta.q_res(chips)',
 PATH='I222',
 DRAWING='@S9S_MB_2U_LIB.S9S_MB_2U(SCH_1):PAGE175',
 PHYS_PAGE='183',
 XY='(-1850,225)',
 ROT='0',
 VER='1',
 PACK_TYPE='0402LF',
 CDS_LIB='pure_quanta',
 CDS_PART_NAME='Q_RES_0402LF-33.2,1%,1/16W,CHIA',
 WATTAGE='1/16W',
 TOLERANCE='1%',
 MATERIAL='CHIP',
 VALUE='33.2',
 PRIM_FILE='./archive_libs/logical/q_res/chips/chips.prt';

PART_NAME
 R1269 'Q_RES_0402LF-4.75K,1%,1/16W,CHA':;

SECTION_NUMBER 1
 '@S9S_MB_2U_LIB.S9S_MB_2U(SCH_1):PAGE175_I225@PURE_QUANTA.Q_RES(CHIPS)':
 C_PATH='@s9s_mb_2u_lib.s9s_mb_2u(sch_1):page175_i225@pure_quanta.q_res(chips)',
 P_PATH='@s9s_mb_2u_lib.s9s_mb_2u(sch_1):page183_i225@pure_quanta.q_res(chips)',
 PATH='I225',
 DRAWING='@S9S_MB_2U_LIB.S9S_MB_2U(SCH_1):PAGE175',
 PHYS_PAGE='183',
 XY='(-1100,75)',
 ROT='0',
 VER='1',
 PACK_TYPE='0402LF',
 CDS_LIB='pure_quanta',
 CDS_PART_NAME='Q_RES_0402LF-4.75K,1%,1/16W,CHA',
 WATTAGE='1/16W',
 TOLERANCE='1%',
 MATERIAL='CHIP',
 VALUE='4.75K',
 PRIM_FILE='./archive_libs/logical/q_res/chips/chips.prt';

PART_NAME
 R1270 'Q_RES_0402LF-240,1%,1/16W,EMPTA':;

SECTION_NUMBER 1
 '@S9S_MB_2U_LIB.S9S_MB_2U(SCH_1):PAGE44_I55@PURE_QUANTA.Q_RES(CHIPS)':
 C_PATH='@s9s_mb_2u_lib.s9s_mb_2u(sch_1):page44_i55@pure_quanta.q_res(chips)',
 P_PATH='@s9s_mb_2u_lib.s9s_mb_2u(sch_1):page44_i55@pure_quanta.q_res(chips)',
 PATH='I55',
 DRAWING='@S9S_MB_2U_LIB.S9S_MB_2U(SCH_1):PAGE44',
 PHYS_PAGE='44',
 XY='(-1575,5275)',
 ROT='0',
 VER='2',
 PACK_TYPE='0402LF',
 CDS_LIB='pure_quanta',
 CDS_PART_NAME='Q_RES_0402LF-240,1%,1/16W,EMPTA',
 WATTAGE='1/16W',
 TOLERANCE='1%',
 MATERIAL='EMPTY',
 VALUE='240',
 PRIM_FILE='./archive_libs/logical/q_res/chips/chips.prt';

PART_NAME
 R1271 'Q_RES_0402LF-2.21K,1%,1/16W,EMA':;

SECTION_NUMBER 1
 '@S9S_MB_2U_LIB.S9S_MB_2U(SCH_1):PAGE183_I5@PURE_QUANTA.Q_RES(CHIPS)':
 C_PATH='@s9s_mb_2u_lib.s9s_mb_2u(sch_1):page183_i5@pure_quanta.q_res(chips)',
 P_PATH='@s9s_mb_2u_lib.s9s_mb_2u(sch_1):page194_i5@pure_quanta.q_res(chips)',
 PATH='I5',
 DRAWING='@S9S_MB_2U_LIB.S9S_MB_2U(SCH_1):PAGE183',
 PHYS_PAGE='194',
 XY='(-2100,-200)',
 ROT='0',
 VER='2',
 PACK_TYPE='0402LF',
 CDS_LIB='pure_quanta',
 CDS_PART_NAME='Q_RES_0402LF-2.21K,1%,1/16W,EMA',
 WATTAGE='1/16W',
 TOLERANCE='1%',
 MATERIAL='EMPTY',
 VALUE='2.21K',
 PRIM_FILE='./archive_libs/logical/q_res/chips/chips.prt';

PART_NAME
 R1273 'Q_RES_0402LF-22,1%,1/16W,CHIP,A':;

SECTION_NUMBER 1
 '@S9S_MB_2U_LIB.S9S_MB_2U(SCH_1):PAGE198_I44@PURE_QUANTA.Q_RES(CHIPS)':
 C_PATH='@s9s_mb_2u_lib.s9s_mb_2u(sch_1):page198_i44@pure_quanta.q_res(chips)',
 P_PATH='@s9s_mb_2u_lib.s9s_mb_2u(sch_1):page209_i44@pure_quanta.q_res(chips)',
 PATH='I44',
 DRAWING='@S9S_MB_2U_LIB.S9S_MB_2U(SCH_1):PAGE198',
 PHYS_PAGE='209',
 XY='(-6025,200)',
 ROT='0',
 VER='1',
 PACK_TYPE='0402LF',
 CDS_LIB='pure_quanta',
 CDS_PART_NAME='Q_RES_0402LF-22,1%,1/16W,CHIP,A',
 WATTAGE='1/16W',
 TOLERANCE='1%',
 MATERIAL='CHIP',
 VALUE='22',
 PRIM_FILE='./archive_libs/logical/q_res/chips/chips.prt';

PART_NAME
 R1274 'Q_RES_0402LF-22,1%,1/16W,CHIP,A':;

SECTION_NUMBER 1
 '@S9S_MB_2U_LIB.S9S_MB_2U(SCH_1):PAGE198_I43@PURE_QUANTA.Q_RES(CHIPS)':
 C_PATH='@s9s_mb_2u_lib.s9s_mb_2u(sch_1):page198_i43@pure_quanta.q_res(chips)',
 P_PATH='@s9s_mb_2u_lib.s9s_mb_2u(sch_1):page209_i43@pure_quanta.q_res(chips)',
 PATH='I43',
 DRAWING='@S9S_MB_2U_LIB.S9S_MB_2U(SCH_1):PAGE198',
 PHYS_PAGE='209',
 XY='(-6025,50)',
 ROT='0',
 VER='1',
 PACK_TYPE='0402LF',
 CDS_LIB='pure_quanta',
 CDS_PART_NAME='Q_RES_0402LF-22,1%,1/16W,CHIP,A',
 WATTAGE='1/16W',
 TOLERANCE='1%',
 MATERIAL='CHIP',
 VALUE='22',
 PRIM_FILE='./archive_libs/logical/q_res/chips/chips.prt';

PART_NAME
 R1275 'Q_RES_0402LF-22,1%,1/16W,CHIP,A':;

SECTION_NUMBER 1
 '@S9S_MB_2U_LIB.S9S_MB_2U(SCH_1):PAGE198_I24@PURE_QUANTA.Q_RES(CHIPS)':
 C_PATH='@s9s_mb_2u_lib.s9s_mb_2u(sch_1):page198_i24@pure_quanta.q_res(chips)',
 P_PATH='@s9s_mb_2u_lib.s9s_mb_2u(sch_1):page209_i24@pure_quanta.q_res(chips)',
 PATH='I24',
 DRAWING='@S9S_MB_2U_LIB.S9S_MB_2U(SCH_1):PAGE198',
 PHYS_PAGE='209',
 XY='(-6025,-200)',
 ROT='0',
 VER='1',
 PACK_TYPE='0402LF',
 CDS_LIB='pure_quanta',
 CDS_PART_NAME='Q_RES_0402LF-22,1%,1/16W,CHIP,A',
 WATTAGE='1/16W',
 TOLERANCE='1%',
 MATERIAL='CHIP',
 VALUE='22',
 PRIM_FILE='./archive_libs/logical/q_res/chips/chips.prt';

PART_NAME
 R1276 'Q_RES_0402LF-22,1%,1/16W,CHIP,A':;

SECTION_NUMBER 1
 '@S9S_MB_2U_LIB.S9S_MB_2U(SCH_1):PAGE198_I23@PURE_QUANTA.Q_RES(CHIPS)':
 C_PATH='@s9s_mb_2u_lib.s9s_mb_2u(sch_1):page198_i23@pure_quanta.q_res(chips)',
 P_PATH='@s9s_mb_2u_lib.s9s_mb_2u(sch_1):page209_i23@pure_quanta.q_res(chips)',
 PATH='I23',
 DRAWING='@S9S_MB_2U_LIB.S9S_MB_2U(SCH_1):PAGE198',
 PHYS_PAGE='209',
 XY='(-6025,-350)',
 ROT='0',
 VER='1',
 PACK_TYPE='0402LF',
 CDS_LIB='pure_quanta',
 CDS_PART_NAME='Q_RES_0402LF-22,1%,1/16W,CHIP,A',
 WATTAGE='1/16W',
 TOLERANCE='1%',
 MATERIAL='CHIP',
 VALUE='22',
 PRIM_FILE='./archive_libs/logical/q_res/chips/chips.prt';

PART_NAME
 R1289 'Q_RES_0402LF-100K,1%,1/16W,CHIA':;

SECTION_NUMBER 1
 '@S9S_MB_2U_LIB.S9S_MB_2U(SCH_1):PAGE151_I21@PURE_QUANTA.Q_RES(CHIPS)':
 C_PATH='@s9s_mb_2u_lib.s9s_mb_2u(sch_1):page151_i21@pure_quanta.q_res(chips)',
 P_PATH='@s9s_mb_2u_lib.s9s_mb_2u(sch_1):page154_i21@pure_quanta.q_res(chips)',
 PATH='I21',
 DRAWING='@S9S_MB_2U_LIB.S9S_MB_2U(SCH_1):PAGE151',
 PHYS_PAGE='154',
 XY='(-1475,3525)',
 ROT='0',
 VER='2',
 PACK_TYPE='0402LF',
 CDS_LIB='pure_quanta',
 CDS_PART_NAME='Q_RES_0402LF-100K,1%,1/16W,CHIA',
 WATTAGE='1/16W',
 TOLERANCE='1%',
 MATERIAL='CHIP',
 VALUE='100K',
 PRIM_FILE='./archive_libs/logical/q_res/chips/chips.prt';

PART_NAME
 R1290 'Q_RES_0402LF-22,1%,1/16W,EMPTYA':;

SECTION_NUMBER 1
 '@S9S_MB_2U_LIB.S9S_MB_2U(SCH_1):PAGE151_I81@PURE_QUANTA.Q_RES(CHIPS)':
 C_PATH='@s9s_mb_2u_lib.s9s_mb_2u(sch_1):page151_i81@pure_quanta.q_res(chips)',
 P_PATH='@s9s_mb_2u_lib.s9s_mb_2u(sch_1):page154_i81@pure_quanta.q_res(chips)',
 PATH='I81',
 DRAWING='@S9S_MB_2U_LIB.S9S_MB_2U(SCH_1):PAGE151',
 PHYS_PAGE='154',
 XY='(1650,6625)',
 ROT='0',
 VER='1',
 PACK_TYPE='0402LF',
 CDS_LIB='pure_quanta',
 CDS_PART_NAME='Q_RES_0402LF-22,1%,1/16W,EMPTYA',
 WATTAGE='1/16W',
 TOLERANCE='1%',
 MATERIAL='EMPTY',
 VALUE='22',
 PRIM_FILE='./archive_libs/logical/q_res/chips/chips.prt';

PART_NAME
 R1291 'Q_RES_0402LF-22,1%,1/16W,CHIP,A':;

SECTION_NUMBER 1
 '@S9S_MB_2U_LIB.S9S_MB_2U(SCH_1):PAGE151_I69@PURE_QUANTA.Q_RES(CHIPS)':
 C_PATH='@s9s_mb_2u_lib.s9s_mb_2u(sch_1):page151_i69@pure_quanta.q_res(chips)',
 P_PATH='@s9s_mb_2u_lib.s9s_mb_2u(sch_1):page154_i69@pure_quanta.q_res(chips)',
 PATH='I69',
 DRAWING='@S9S_MB_2U_LIB.S9S_MB_2U(SCH_1):PAGE151',
 PHYS_PAGE='154',
 XY='(50,6475)',
 ROT='0',
 VER='1',
 PACK_TYPE='0402LF',
 CDS_LIB='pure_quanta',
 CDS_PART_NAME='Q_RES_0402LF-22,1%,1/16W,CHIP,A',
 WATTAGE='1/16W',
 TOLERANCE='1%',
 MATERIAL='CHIP',
 VALUE='22',
 PRIM_FILE='./archive_libs/logical/q_res/chips/chips.prt';

PART_NAME
 R1292 'Q_RES_0402LF-22,1%,1/16W,CHIP,A':;

SECTION_NUMBER 1
 '@S9S_MB_2U_LIB.S9S_MB_2U(SCH_1):PAGE151_I68@PURE_QUANTA.Q_RES(CHIPS)':
 C_PATH='@s9s_mb_2u_lib.s9s_mb_2u(sch_1):page151_i68@pure_quanta.q_res(chips)',
 P_PATH='@s9s_mb_2u_lib.s9s_mb_2u(sch_1):page154_i68@pure_quanta.q_res(chips)',
 PATH='I68',
 DRAWING='@S9S_MB_2U_LIB.S9S_MB_2U(SCH_1):PAGE151',
 PHYS_PAGE='154',
 XY='(50,6325)',
 ROT='0',
 VER='1',
 PACK_TYPE='0402LF',
 CDS_LIB='pure_quanta',
 CDS_PART_NAME='Q_RES_0402LF-22,1%,1/16W,CHIP,A',
 WATTAGE='1/16W',
 TOLERANCE='1%',
 MATERIAL='CHIP',
 VALUE='22',
 PRIM_FILE='./archive_libs/logical/q_res/chips/chips.prt';

PART_NAME
 R1293 'Q_RES_0402LF-22,1%,1/16W,CHIP,A':;

SECTION_NUMBER 1
 '@S9S_MB_2U_LIB.S9S_MB_2U(SCH_1):PAGE151_I67@PURE_QUANTA.Q_RES(CHIPS)':
 C_PATH='@s9s_mb_2u_lib.s9s_mb_2u(sch_1):page151_i67@pure_quanta.q_res(chips)',
 P_PATH='@s9s_mb_2u_lib.s9s_mb_2u(sch_1):page154_i67@pure_quanta.q_res(chips)',
 PATH='I67',
 DRAWING='@S9S_MB_2U_LIB.S9S_MB_2U(SCH_1):PAGE151',
 PHYS_PAGE='154',
 XY='(50,6175)',
 ROT='0',
 VER='1',
 PACK_TYPE='0402LF',
 CDS_LIB='pure_quanta',
 CDS_PART_NAME='Q_RES_0402LF-22,1%,1/16W,CHIP,A',
 WATTAGE='1/16W',
 TOLERANCE='1%',
 MATERIAL='CHIP',
 VALUE='22',
 PRIM_FILE='./archive_libs/logical/q_res/chips/chips.prt';

PART_NAME
 R1294 'Q_RES_0402LF-0,5%,1/16W,CHIP,CA':;

SECTION_NUMBER 1
 '@S9S_MB_2U_LIB.S9S_MB_2U(SCH_1):PAGE151_I66@PURE_QUANTA.Q_RES(CHIPS)':
 C_PATH='@s9s_mb_2u_lib.s9s_mb_2u(sch_1):page151_i66@pure_quanta.q_res(chips)',
 P_PATH='@s9s_mb_2u_lib.s9s_mb_2u(sch_1):page154_i66@pure_quanta.q_res(chips)',
 PATH='I66',
 DRAWING='@S9S_MB_2U_LIB.S9S_MB_2U(SCH_1):PAGE151',
 PHYS_PAGE='154',
 XY='(50,5050)',
 ROT='0',
 VER='1',
 PACK_TYPE='0402LF',
 CDS_LIB='pure_quanta',
 CDS_PART_NAME='Q_RES_0402LF-0,5%,1/16W,CHIP,CA',
 WATTAGE='1/16W',
 TOLERANCE='5%',
 MATERIAL='CHIP',
 VALUE='0',
 PRIM_FILE='./archive_libs/logical/q_res/chips/chips.prt';

PART_NAME
 R1295 'Q_RES_0402LF-0,5%,1/16W,CHIP,CA':;

SECTION_NUMBER 1
 '@S9S_MB_2U_LIB.S9S_MB_2U(SCH_1):PAGE151_I65@PURE_QUANTA.Q_RES(CHIPS)':
 C_PATH='@s9s_mb_2u_lib.s9s_mb_2u(sch_1):page151_i65@pure_quanta.q_res(chips)',
 P_PATH='@s9s_mb_2u_lib.s9s_mb_2u(sch_1):page154_i65@pure_quanta.q_res(chips)',
 PATH='I65',
 DRAWING='@S9S_MB_2U_LIB.S9S_MB_2U(SCH_1):PAGE151',
 PHYS_PAGE='154',
 XY='(50,4900)',
 ROT='0',
 VER='1',
 PACK_TYPE='0402LF',
 CDS_LIB='pure_quanta',
 CDS_PART_NAME='Q_RES_0402LF-0,5%,1/16W,CHIP,CA',
 WATTAGE='1/16W',
 TOLERANCE='5%',
 MATERIAL='CHIP',
 VALUE='0',
 PRIM_FILE='./archive_libs/logical/q_res/chips/chips.prt';

PART_NAME
 R1296 'Q_RES_0402LF-0,5%,1/16W,CHIP,CA':;

SECTION_NUMBER 1
 '@S9S_MB_2U_LIB.S9S_MB_2U(SCH_1):PAGE151_I61@PURE_QUANTA.Q_RES(CHIPS)':
 C_PATH='@s9s_mb_2u_lib.s9s_mb_2u(sch_1):page151_i61@pure_quanta.q_res(chips)',
 P_PATH='@s9s_mb_2u_lib.s9s_mb_2u(sch_1):page154_i61@pure_quanta.q_res(chips)',
 PATH='I61',
 DRAWING='@S9S_MB_2U_LIB.S9S_MB_2U(SCH_1):PAGE151',
 PHYS_PAGE='154',
 XY='(50,4750)',
 ROT='0',
 VER='1',
 PACK_TYPE='0402LF',
 CDS_LIB='pure_quanta',
 CDS_PART_NAME='Q_RES_0402LF-0,5%,1/16W,CHIP,CA',
 WATTAGE='1/16W',
 TOLERANCE='5%',
 MATERIAL='CHIP',
 VALUE='0',
 PRIM_FILE='./archive_libs/logical/q_res/chips/chips.prt';

PART_NAME
 R1297 'Q_RES_0402LF-0,5%,1/16W,CHIP,CA':;

SECTION_NUMBER 1
 '@S9S_MB_2U_LIB.S9S_MB_2U(SCH_1):PAGE185_I32@PURE_QUANTA.Q_RES(CHIPS)':
 C_PATH='@s9s_mb_2u_lib.s9s_mb_2u(sch_1):page185_i32@pure_quanta.q_res(chips)',
 P_PATH='@s9s_mb_2u_lib.s9s_mb_2u(sch_1):page197_i32@pure_quanta.q_res(chips)',
 PATH='I32',
 DRAWING='@S9S_MB_2U_LIB.S9S_MB_2U(SCH_1):PAGE185',
 PHYS_PAGE='197',
 XY='(-7050,4625)',
 ROT='0',
 VER='1',
 PACK_TYPE='0402LF',
 CDS_LIB='pure_quanta',
 CDS_PART_NAME='Q_RES_0402LF-0,5%,1/16W,CHIP,CA',
 WATTAGE='1/16W',
 TOLERANCE='5%',
 MATERIAL='CHIP',
 VALUE='0',
 PRIM_FILE='./archive_libs/logical/q_res/chips/chips.prt';

PART_NAME
 R1298 'Q_RES_0402LF-1K,1%,1/16W,EMPTYA':;

SECTION_NUMBER 1
 '@S9S_MB_2U_LIB.S9S_MB_2U(SCH_1):PAGE188_I22@PURE_QUANTA.Q_RES(CHIPS)':
 C_PATH='@s9s_mb_2u_lib.s9s_mb_2u(sch_1):page188_i22@pure_quanta.q_res(chips)',
 P_PATH='@s9s_mb_2u_lib.s9s_mb_2u(sch_1):page200_i22@pure_quanta.q_res(chips)',
 PATH='I22',
 DRAWING='@S9S_MB_2U_LIB.S9S_MB_2U(SCH_1):PAGE188',
 PHYS_PAGE='200',
 XY='(-2925,3550)',
 ROT='0',
 VER='2',
 PACK_TYPE='0402LF',
 CDS_LIB='pure_quanta',
 CDS_PART_NAME='Q_RES_0402LF-1K,1%,1/16W,EMPTYA',
 WATTAGE='1/16W',
 TOLERANCE='1%',
 MATERIAL='EMPTY',
 VALUE='1K',
 PRIM_FILE='./archive_libs/logical/q_res/chips/chips.prt';

PART_NAME
 R1299 'Q_RES_0402LF-10K,1%,1/16W,CHIPA':;

SECTION_NUMBER 1
 '@S9S_MB_2U_LIB.S9S_MB_2U(SCH_1):PAGE188_I21@PURE_QUANTA.Q_RES(CHIPS)':
 C_PATH='@s9s_mb_2u_lib.s9s_mb_2u(sch_1):page188_i21@pure_quanta.q_res(chips)',
 P_PATH='@s9s_mb_2u_lib.s9s_mb_2u(sch_1):page200_i21@pure_quanta.q_res(chips)',
 PATH='I21',
 DRAWING='@S9S_MB_2U_LIB.S9S_MB_2U(SCH_1):PAGE188',
 PHYS_PAGE='200',
 XY='(-2925,3025)',
 ROT='0',
 VER='2',
 PACK_TYPE='0402LF',
 CDS_LIB='pure_quanta',
 CDS_PART_NAME='Q_RES_0402LF-10K,1%,1/16W,CHIPA',
 WATTAGE='1/16W',
 TOLERANCE='1%',
 MATERIAL='CHIP',
 VALUE='10K',
 PRIM_FILE='./archive_libs/logical/q_res/chips/chips.prt';

PART_NAME
 R1300 'Q_RES_0402LF-33.2,1%,1/16W,CHIA':;

SECTION_NUMBER 1
 '@S9S_MB_2U_LIB.S9S_MB_2U(SCH_1):PAGE193_I5@PURE_QUANTA.Q_RES(CHIPS)':
 C_PATH='@s9s_mb_2u_lib.s9s_mb_2u(sch_1):page193_i5@pure_quanta.q_res(chips)',
 P_PATH='@s9s_mb_2u_lib.s9s_mb_2u(sch_1):page205_i5@pure_quanta.q_res(chips)',
 PATH='I5',
 DRAWING='@S9S_MB_2U_LIB.S9S_MB_2U(SCH_1):PAGE193',
 PHYS_PAGE='205',
 XY='(-5725,-825)',
 ROT='0',
 VER='1',
 PACK_TYPE='0402LF',
 CDS_LIB='pure_quanta',
 CDS_PART_NAME='Q_RES_0402LF-33.2,1%,1/16W,CHIA',
 WATTAGE='1/16W',
 TOLERANCE='1%',
 MATERIAL='CHIP',
 VALUE='33.2',
 PRIM_FILE='./archive_libs/logical/q_res/chips/chips.prt';

PART_NAME
 R1302 'Q_RES_0402LF-2K,1%,1/16W,EMPTYA':;

SECTION_NUMBER 1
 '@S9S_MB_2U_LIB.S9S_MB_2U(SCH_1):PAGE208_I12@PURE_QUANTA.Q_RES(CHIPS)':
 C_PATH='@s9s_mb_2u_lib.s9s_mb_2u(sch_1):page208_i12@pure_quanta.q_res(chips)',
 P_PATH='@s9s_mb_2u_lib.s9s_mb_2u(sch_1):page219_i12@pure_quanta.q_res(chips)',
 PATH='I12',
 DRAWING='@S9S_MB_2U_LIB.S9S_MB_2U(SCH_1):PAGE208',
 PHYS_PAGE='219',
 XY='(-300,2675)',
 ROT='0',
 VER='1',
 PACK_TYPE='0402LF',
 CDS_LIB='pure_quanta',
 CDS_PART_NAME='Q_RES_0402LF-2K,1%,1/16W,EMPTYA',
 WATTAGE='1/16W',
 TOLERANCE='1%',
 MATERIAL='EMPTY',
 VALUE='2K',
 PRIM_FILE='./archive_libs/logical/q_res/chips/chips.prt';

PART_NAME
 R1305 'Q_RES_0402LF-10K,1%,1/16W,EMPTA':;

SECTION_NUMBER 1
 '@S9S_MB_2U_LIB.S9S_MB_2U(SCH_1):PAGE197_I272@PURE_QUANTA.Q_RES(CHIPS)':
 C_PATH='@s9s_mb_2u_lib.s9s_mb_2u(sch_1):page197_i272@pure_quanta.q_res(chips)',
 P_PATH='@s9s_mb_2u_lib.s9s_mb_2u(sch_1):page208_i272@pure_quanta.q_res(chips)',
 PATH='I272',
 DRAWING='@S9S_MB_2U_LIB.S9S_MB_2U(SCH_1):PAGE197',
 PHYS_PAGE='208',
 XY='(-4400,10725)',
 ROT='0',
 VER='2',
 PACK_TYPE='0402LF',
 CDS_LIB='pure_quanta',
 CDS_PART_NAME='Q_RES_0402LF-10K,1%,1/16W,EMPTA',
 WATTAGE='1/16W',
 TOLERANCE='1%',
 MATERIAL='EMPTY',
 VALUE='10K',
 PRIM_FILE='./archive_libs/logical/q_res/chips/chips.prt';

PART_NAME
 R1306 'Q_RES_0402LF-33.2,1%,1/16W,CHIA':;

SECTION_NUMBER 1
 '@S9S_MB_2U_LIB.S9S_MB_2U(SCH_1):PAGE193_I13@PURE_QUANTA.Q_RES(CHIPS)':
 C_PATH='@s9s_mb_2u_lib.s9s_mb_2u(sch_1):page193_i13@pure_quanta.q_res(chips)',
 P_PATH='@s9s_mb_2u_lib.s9s_mb_2u(sch_1):page205_i13@pure_quanta.q_res(chips)',
 PATH='I13',
 DRAWING='@S9S_MB_2U_LIB.S9S_MB_2U(SCH_1):PAGE193',
 PHYS_PAGE='205',
 XY='(-5700,625)',
 ROT='0',
 VER='1',
 PACK_TYPE='0402LF',
 CDS_LIB='pure_quanta',
 CDS_PART_NAME='Q_RES_0402LF-33.2,1%,1/16W,CHIA',
 WATTAGE='1/16W',
 TOLERANCE='1%',
 MATERIAL='CHIP',
 VALUE='33.2',
 PRIM_FILE='./archive_libs/logical/q_res/chips/chips.prt';

PART_NAME
 R1307 'Q_RES_0402LF-33.2,1%,1/16W,CHIA':;

SECTION_NUMBER 1
 '@S9S_MB_2U_LIB.S9S_MB_2U(SCH_1):PAGE193_I3@PURE_QUANTA.Q_RES(CHIPS)':
 C_PATH='@s9s_mb_2u_lib.s9s_mb_2u(sch_1):page193_i3@pure_quanta.q_res(chips)',
 P_PATH='@s9s_mb_2u_lib.s9s_mb_2u(sch_1):page205_i3@pure_quanta.q_res(chips)',
 PATH='I3',
 DRAWING='@S9S_MB_2U_LIB.S9S_MB_2U(SCH_1):PAGE193',
 PHYS_PAGE='205',
 XY='(-5700,350)',
 ROT='0',
 VER='1',
 PACK_TYPE='0402LF',
 CDS_LIB='pure_quanta',
 CDS_PART_NAME='Q_RES_0402LF-33.2,1%,1/16W,CHIA',
 WATTAGE='1/16W',
 TOLERANCE='1%',
 MATERIAL='CHIP',
 VALUE='33.2',
 PRIM_FILE='./archive_libs/logical/q_res/chips/chips.prt';

PART_NAME
 R1308 'Q_RES_0402LF-10K,1%,1/16W,EMPTA':;

SECTION_NUMBER 1
 '@S9S_MB_2U_LIB.S9S_MB_2U(SCH_1):PAGE209_I23@PURE_QUANTA.Q_RES(CHIPS)':
 C_PATH='@s9s_mb_2u_lib.s9s_mb_2u(sch_1):page209_i23@pure_quanta.q_res(chips)',
 P_PATH='@s9s_mb_2u_lib.s9s_mb_2u(sch_1):page220_i23@pure_quanta.q_res(chips)',
 PATH='I23',
 DRAWING='@S9S_MB_2U_LIB.S9S_MB_2U(SCH_1):PAGE209',
 PHYS_PAGE='220',
 XY='(1775,-1625)',
 ROT='0',
 VER='1',
 PACK_TYPE='0402LF',
 CDS_LIB='pure_quanta',
 CDS_PART_NAME='Q_RES_0402LF-10K,1%,1/16W,EMPTA',
 WATTAGE='1/16W',
 TOLERANCE='1%',
 MATERIAL='EMPTY',
 VALUE='10K',
 PRIM_FILE='./archive_libs/logical/q_res/chips/chips.prt';

PART_NAME
 R1309 'Q_RES_0402LF-33.2,1%,1/16W,CHIA':;

SECTION_NUMBER 1
 '@S9S_MB_2U_LIB.S9S_MB_2U(SCH_1):PAGE193_I10@PURE_QUANTA.Q_RES(CHIPS)':
 C_PATH='@s9s_mb_2u_lib.s9s_mb_2u(sch_1):page193_i10@pure_quanta.q_res(chips)',
 P_PATH='@s9s_mb_2u_lib.s9s_mb_2u(sch_1):page205_i10@pure_quanta.q_res(chips)',
 PATH='I10',
 DRAWING='@S9S_MB_2U_LIB.S9S_MB_2U(SCH_1):PAGE193',
 PHYS_PAGE='205',
 XY='(-5700,75)',
 ROT='0',
 VER='1',
 PACK_TYPE='0402LF',
 CDS_LIB='pure_quanta',
 CDS_PART_NAME='Q_RES_0402LF-33.2,1%,1/16W,CHIA',
 WATTAGE='1/16W',
 TOLERANCE='1%',
 MATERIAL='CHIP',
 VALUE='33.2',
 PRIM_FILE='./archive_libs/logical/q_res/chips/chips.prt';

PART_NAME
 R1310 'Q_RES_0402LF-33.2,1%,1/16W,CHIA':;

SECTION_NUMBER 1
 '@S9S_MB_2U_LIB.S9S_MB_2U(SCH_1):PAGE193_I20@PURE_QUANTA.Q_RES(CHIPS)':
 C_PATH='@s9s_mb_2u_lib.s9s_mb_2u(sch_1):page193_i20@pure_quanta.q_res(chips)',
 P_PATH='@s9s_mb_2u_lib.s9s_mb_2u(sch_1):page205_i20@pure_quanta.q_res(chips)',
 PATH='I20',
 DRAWING='@S9S_MB_2U_LIB.S9S_MB_2U(SCH_1):PAGE193',
 PHYS_PAGE='205',
 XY='(-5700,-225)',
 ROT='0',
 VER='1',
 PACK_TYPE='0402LF',
 CDS_LIB='pure_quanta',
 CDS_PART_NAME='Q_RES_0402LF-33.2,1%,1/16W,CHIA',
 WATTAGE='1/16W',
 TOLERANCE='1%',
 MATERIAL='CHIP',
 VALUE='33.2',
 PRIM_FILE='./archive_libs/logical/q_res/chips/chips.prt';

PART_NAME
 R1311 'Q_RES_0402LF-10K,1%,1/16W,CHIPA':;

SECTION_NUMBER 1
 '@S9S_MB_2U_LIB.S9S_MB_2U(SCH_1):PAGE188_I31@PURE_QUANTA.Q_RES(CHIPS)':
 C_PATH='@s9s_mb_2u_lib.s9s_mb_2u(sch_1):page188_i31@pure_quanta.q_res(chips)',
 P_PATH='@s9s_mb_2u_lib.s9s_mb_2u(sch_1):page200_i31@pure_quanta.q_res(chips)',
 PATH='I31',
 DRAWING='@S9S_MB_2U_LIB.S9S_MB_2U(SCH_1):PAGE188',
 PHYS_PAGE='200',
 XY='(-150,3025)',
 ROT='0',
 VER='2',
 PACK_TYPE='0402LF',
 CDS_LIB='pure_quanta',
 CDS_PART_NAME='Q_RES_0402LF-10K,1%,1/16W,CHIPA',
 WATTAGE='1/16W',
 TOLERANCE='1%',
 MATERIAL='CHIP',
 VALUE='10K',
 PRIM_FILE='./archive_libs/logical/q_res/chips/chips.prt';

PART_NAME
 R1312 'Q_RES_0402LF-10K,1%,1/16W,EMPTA':;

SECTION_NUMBER 1
 '@S9S_MB_2U_LIB.S9S_MB_2U(SCH_1):PAGE209_I22@PURE_QUANTA.Q_RES(CHIPS)':
 C_PATH='@s9s_mb_2u_lib.s9s_mb_2u(sch_1):page209_i22@pure_quanta.q_res(chips)',
 P_PATH='@s9s_mb_2u_lib.s9s_mb_2u(sch_1):page220_i22@pure_quanta.q_res(chips)',
 PATH='I22',
 DRAWING='@S9S_MB_2U_LIB.S9S_MB_2U(SCH_1):PAGE209',
 PHYS_PAGE='220',
 XY='(1775,-1725)',
 ROT='0',
 VER='1',
 PACK_TYPE='0402LF',
 CDS_LIB='pure_quanta',
 CDS_PART_NAME='Q_RES_0402LF-10K,1%,1/16W,EMPTA',
 WATTAGE='1/16W',
 TOLERANCE='1%',
 MATERIAL='EMPTY',
 VALUE='10K',
 PRIM_FILE='./archive_libs/logical/q_res/chips/chips.prt';

PART_NAME
 R1313 'Q_RES_0402LF-33.2,1%,1/16W,CHIA':;

SECTION_NUMBER 1
 '@S9S_MB_2U_LIB.S9S_MB_2U(SCH_1):PAGE193_I21@PURE_QUANTA.Q_RES(CHIPS)':
 C_PATH='@s9s_mb_2u_lib.s9s_mb_2u(sch_1):page193_i21@pure_quanta.q_res(chips)',
 P_PATH='@s9s_mb_2u_lib.s9s_mb_2u(sch_1):page205_i21@pure_quanta.q_res(chips)',
 PATH='I21',
 DRAWING='@S9S_MB_2U_LIB.S9S_MB_2U(SCH_1):PAGE193',
 PHYS_PAGE='205',
 XY='(-5700,-525)',
 ROT='0',
 VER='1',
 PACK_TYPE='0402LF',
 CDS_LIB='pure_quanta',
 CDS_PART_NAME='Q_RES_0402LF-33.2,1%,1/16W,CHIA',
 WATTAGE='1/16W',
 TOLERANCE='1%',
 MATERIAL='CHIP',
 VALUE='33.2',
 PRIM_FILE='./archive_libs/logical/q_res/chips/chips.prt';

PART_NAME
 R1316 'Q_RES_0603LF-200K,0.1%,1/10W,EA':;

SECTION_NUMBER 1
 '@S9S_MB_2U_LIB.S9S_MB_2U(SCH_1):PAGE171_I92@PURE_QUANTA.Q_RES(CHIPS)':
 C_PATH='@s9s_mb_2u_lib.s9s_mb_2u(sch_1):page171_i92@pure_quanta.q_res(chips)',
 P_PATH='@s9s_mb_2u_lib.s9s_mb_2u(sch_1):page179_i92@pure_quanta.q_res(chips)',
 PATH='I92',
 DRAWING='@S9S_MB_2U_LIB.S9S_MB_2U(SCH_1):PAGE171',
 PHYS_PAGE='179',
 XY='(-875,275)',
 ROT='0',
 VER='1',
 PACK_TYPE='0603LF',
 CDS_LIB='pure_quanta',
 CDS_PART_NAME='Q_RES_0603LF-200K,0.1%,1/10W,EA',
 WATTAGE='1/10W',
 TOLERANCE='0.1%',
 MATERIAL='EMPTY',
 VALUE='200K',
 PRIM_FILE='./archive_libs/logical/q_res/chips/chips.prt';

PART_NAME
 R1317 'Q_RES_0402LF-1K,1%,1/16W,CHIP,A':;

SECTION_NUMBER 1
 '@S9S_MB_2U_LIB.S9S_MB_2U(SCH_1):PAGE189_I88@PURE_QUANTA.Q_RES(CHIPS)':
 C_PATH='@s9s_mb_2u_lib.s9s_mb_2u(sch_1):page189_i88@pure_quanta.q_res(chips)',
 P_PATH='@s9s_mb_2u_lib.s9s_mb_2u(sch_1):page201_i88@pure_quanta.q_res(chips)',
 PATH='I88',
 DRAWING='@S9S_MB_2U_LIB.S9S_MB_2U(SCH_1):PAGE189',
 PHYS_PAGE='201',
 XY='(-350,3650)',
 ROT='0',
 VER='1',
 PACK_TYPE='0402LF',
 CDS_LIB='pure_quanta',
 CDS_PART_NAME='Q_RES_0402LF-1K,1%,1/16W,CHIP,A',
 WATTAGE='1/16W',
 TOLERANCE='1%',
 MATERIAL='CHIP',
 VALUE='1K',
 PRIM_FILE='./archive_libs/logical/q_res/chips/chips.prt';

PART_NAME
 R1318 'Q_RES_0402LF-0,5%,1/16W,CHIP,CA':;

SECTION_NUMBER 1
 '@S9S_MB_2U_LIB.S9S_MB_2U(SCH_1):PAGE212_I130@PURE_QUANTA.Q_RES(CHIPS)':
 C_PATH='@s9s_mb_2u_lib.s9s_mb_2u(sch_1):page212_i130@pure_quanta.q_res(chips)',
 P_PATH='@s9s_mb_2u_lib.s9s_mb_2u(sch_1):page223_i130@pure_quanta.q_res(chips)',
 PATH='I130',
 DRAWING='@S9S_MB_2U_LIB.S9S_MB_2U(SCH_1):PAGE212',
 PHYS_PAGE='223',
 XY='(1925,3775)',
 ROT='0',
 VER='1',
 PACK_TYPE='0402LF',
 LOCATION='R1318',
 CDS_LIB='pure_quanta',
 CDS_PART_NAME='Q_RES_0402LF-0,5%,1/16W,CHIP,CA',
 WATTAGE='1/16W',
 TOLERANCE='5%',
 MATERIAL='CHIP',
 VALUE='0',
 PRIM_FILE='./archive_libs/logical/q_res/chips/chips.prt';

PART_NAME
 R1319 'Q_RES_0402LF-2K,1%,1/16W,EMPTYA':;

SECTION_NUMBER 1
 '@S9S_MB_2U_LIB.S9S_MB_2U(SCH_1):PAGE228_I2@PURE_QUANTA.Q_RES(CHIPS)':
 C_PATH='@s9s_mb_2u_lib.s9s_mb_2u(sch_1):page228_i2@pure_quanta.q_res(chips)',
 P_PATH='@s9s_mb_2u_lib.s9s_mb_2u(sch_1):page241_i2@pure_quanta.q_res(chips)',
 PATH='I2',
 DRAWING='@S9S_MB_2U_LIB.S9S_MB_2U(SCH_1):PAGE228',
 PHYS_PAGE='241',
 XY='(5000,6075)',
 ROT='0',
 VER='1',
 PACK_TYPE='0402LF',
 CDS_LIB='pure_quanta',
 CDS_PART_NAME='Q_RES_0402LF-2K,1%,1/16W,EMPTYA',
 WATTAGE='1/16W',
 TOLERANCE='1%',
 MATERIAL='EMPTY',
 VALUE='2K',
 PRIM_FILE='./archive_libs/logical/q_res/chips/chips.prt';

PART_NAME
 R1320 'Q_RES_0402LF-1K,1%,1/16W,CHIP,A':;

SECTION_NUMBER 1
 '@S9S_MB_2U_LIB.S9S_MB_2U(SCH_1):PAGE189_I89@PURE_QUANTA.Q_RES(CHIPS)':
 C_PATH='@s9s_mb_2u_lib.s9s_mb_2u(sch_1):page189_i89@pure_quanta.q_res(chips)',
 P_PATH='@s9s_mb_2u_lib.s9s_mb_2u(sch_1):page201_i89@pure_quanta.q_res(chips)',
 PATH='I89',
 DRAWING='@S9S_MB_2U_LIB.S9S_MB_2U(SCH_1):PAGE189',
 PHYS_PAGE='201',
 XY='(-350,3600)',
 ROT='0',
 VER='1',
 PACK_TYPE='0402LF',
 CDS_LIB='pure_quanta',
 CDS_PART_NAME='Q_RES_0402LF-1K,1%,1/16W,CHIP,A',
 WATTAGE='1/16W',
 TOLERANCE='1%',
 MATERIAL='CHIP',
 VALUE='1K',
 PRIM_FILE='./archive_libs/logical/q_res/chips/chips.prt';

PART_NAME
 R1324 'Q_RES_0402LF-1K,1%,1/16W,CHIP,A':;

SECTION_NUMBER 1
 '@S9S_MB_2U_LIB.S9S_MB_2U(SCH_1):PAGE189_I87@PURE_QUANTA.Q_RES(CHIPS)':
 C_PATH='@s9s_mb_2u_lib.s9s_mb_2u(sch_1):page189_i87@pure_quanta.q_res(chips)',
 P_PATH='@s9s_mb_2u_lib.s9s_mb_2u(sch_1):page201_i87@pure_quanta.q_res(chips)',
 PATH='I87',
 DRAWING='@S9S_MB_2U_LIB.S9S_MB_2U(SCH_1):PAGE189',
 PHYS_PAGE='201',
 XY='(-350,3550)',
 ROT='0',
 VER='1',
 PACK_TYPE='0402LF',
 CDS_LIB='pure_quanta',
 CDS_PART_NAME='Q_RES_0402LF-1K,1%,1/16W,CHIP,A',
 WATTAGE='1/16W',
 TOLERANCE='1%',
 MATERIAL='CHIP',
 VALUE='1K',
 PRIM_FILE='./archive_libs/logical/q_res/chips/chips.prt';

PART_NAME
 R1325 'Q_RES_0402LF-1K,1%,1/16W,CHIP,A':;

SECTION_NUMBER 1
 '@S9S_MB_2U_LIB.S9S_MB_2U(SCH_1):PAGE189_I93@PURE_QUANTA.Q_RES(CHIPS)':
 C_PATH='@s9s_mb_2u_lib.s9s_mb_2u(sch_1):page189_i93@pure_quanta.q_res(chips)',
 P_PATH='@s9s_mb_2u_lib.s9s_mb_2u(sch_1):page201_i93@pure_quanta.q_res(chips)',
 PATH='I93',
 DRAWING='@S9S_MB_2U_LIB.S9S_MB_2U(SCH_1):PAGE189',
 PHYS_PAGE='201',
 XY='(-350,3500)',
 ROT='0',
 VER='1',
 PACK_TYPE='0402LF',
 CDS_LIB='pure_quanta',
 CDS_PART_NAME='Q_RES_0402LF-1K,1%,1/16W,CHIP,A',
 WATTAGE='1/16W',
 TOLERANCE='1%',
 MATERIAL='CHIP',
 VALUE='1K',
 PRIM_FILE='./archive_libs/logical/q_res/chips/chips.prt';

PART_NAME
 R1326 'Q_RES_0402LF-2K,1%,1/16W,EMPTYA':;

SECTION_NUMBER 1
 '@S9S_MB_2U_LIB.S9S_MB_2U(SCH_1):PAGE208_I11@PURE_QUANTA.Q_RES(CHIPS)':
 C_PATH='@s9s_mb_2u_lib.s9s_mb_2u(sch_1):page208_i11@pure_quanta.q_res(chips)',
 P_PATH='@s9s_mb_2u_lib.s9s_mb_2u(sch_1):page219_i11@pure_quanta.q_res(chips)',
 PATH='I11',
 DRAWING='@S9S_MB_2U_LIB.S9S_MB_2U(SCH_1):PAGE208',
 PHYS_PAGE='219',
 XY='(-300,2525)',
 ROT='0',
 VER='1',
 PACK_TYPE='0402LF',
 CDS_LIB='pure_quanta',
 CDS_PART_NAME='Q_RES_0402LF-2K,1%,1/16W,EMPTYA',
 WATTAGE='1/16W',
 TOLERANCE='1%',
 MATERIAL='EMPTY',
 VALUE='2K',
 PRIM_FILE='./archive_libs/logical/q_res/chips/chips.prt';

PART_NAME
 R1327 'Q_RES_0402LF-2K,1%,1/16W,EMPTYA':;

SECTION_NUMBER 1
 '@S9S_MB_2U_LIB.S9S_MB_2U(SCH_1):PAGE208_I14@PURE_QUANTA.Q_RES(CHIPS)':
 C_PATH='@s9s_mb_2u_lib.s9s_mb_2u(sch_1):page208_i14@pure_quanta.q_res(chips)',
 P_PATH='@s9s_mb_2u_lib.s9s_mb_2u(sch_1):page219_i14@pure_quanta.q_res(chips)',
 PATH='I14',
 DRAWING='@S9S_MB_2U_LIB.S9S_MB_2U(SCH_1):PAGE208',
 PHYS_PAGE='219',
 XY='(-300,2375)',
 ROT='0',
 VER='1',
 PACK_TYPE='0402LF',
 CDS_LIB='pure_quanta',
 CDS_PART_NAME='Q_RES_0402LF-2K,1%,1/16W,EMPTYA',
 WATTAGE='1/16W',
 TOLERANCE='1%',
 MATERIAL='EMPTY',
 VALUE='2K',
 PRIM_FILE='./archive_libs/logical/q_res/chips/chips.prt';

PART_NAME
 R1328 'Q_RES_0402LF-2K,1%,1/16W,EMPTYA':;

SECTION_NUMBER 1
 '@S9S_MB_2U_LIB.S9S_MB_2U(SCH_1):PAGE208_I13@PURE_QUANTA.Q_RES(CHIPS)':
 C_PATH='@s9s_mb_2u_lib.s9s_mb_2u(sch_1):page208_i13@pure_quanta.q_res(chips)',
 P_PATH='@s9s_mb_2u_lib.s9s_mb_2u(sch_1):page219_i13@pure_quanta.q_res(chips)',
 PATH='I13',
 DRAWING='@S9S_MB_2U_LIB.S9S_MB_2U(SCH_1):PAGE208',
 PHYS_PAGE='219',
 XY='(-300,2225)',
 ROT='0',
 VER='1',
 PACK_TYPE='0402LF',
 CDS_LIB='pure_quanta',
 CDS_PART_NAME='Q_RES_0402LF-2K,1%,1/16W,EMPTYA',
 WATTAGE='1/16W',
 TOLERANCE='1%',
 MATERIAL='EMPTY',
 VALUE='2K',
 PRIM_FILE='./archive_libs/logical/q_res/chips/chips.prt';

PART_NAME
 R1329 'Q_RES_0402LF-2K,1%,1/16W,EMPTYA':;

SECTION_NUMBER 1
 '@S9S_MB_2U_LIB.S9S_MB_2U(SCH_1):PAGE208_I15@PURE_QUANTA.Q_RES(CHIPS)':
 C_PATH='@s9s_mb_2u_lib.s9s_mb_2u(sch_1):page208_i15@pure_quanta.q_res(chips)',
 P_PATH='@s9s_mb_2u_lib.s9s_mb_2u(sch_1):page219_i15@pure_quanta.q_res(chips)',
 PATH='I15',
 DRAWING='@S9S_MB_2U_LIB.S9S_MB_2U(SCH_1):PAGE208',
 PHYS_PAGE='219',
 XY='(-300,2075)',
 ROT='0',
 VER='1',
 PACK_TYPE='0402LF',
 CDS_LIB='pure_quanta',
 CDS_PART_NAME='Q_RES_0402LF-2K,1%,1/16W,EMPTYA',
 WATTAGE='1/16W',
 TOLERANCE='1%',
 MATERIAL='EMPTY',
 VALUE='2K',
 PRIM_FILE='./archive_libs/logical/q_res/chips/chips.prt';

PART_NAME
 R1330 'Q_RES_0402LF-2K,1%,1/16W,EMPTYA':;

SECTION_NUMBER 1
 '@S9S_MB_2U_LIB.S9S_MB_2U(SCH_1):PAGE208_I16@PURE_QUANTA.Q_RES(CHIPS)':
 C_PATH='@s9s_mb_2u_lib.s9s_mb_2u(sch_1):page208_i16@pure_quanta.q_res(chips)',
 P_PATH='@s9s_mb_2u_lib.s9s_mb_2u(sch_1):page219_i16@pure_quanta.q_res(chips)',
 PATH='I16',
 DRAWING='@S9S_MB_2U_LIB.S9S_MB_2U(SCH_1):PAGE208',
 PHYS_PAGE='219',
 XY='(-300,1925)',
 ROT='0',
 VER='1',
 PACK_TYPE='0402LF',
 CDS_LIB='pure_quanta',
 CDS_PART_NAME='Q_RES_0402LF-2K,1%,1/16W,EMPTYA',
 WATTAGE='1/16W',
 TOLERANCE='1%',
 MATERIAL='EMPTY',
 VALUE='2K',
 PRIM_FILE='./archive_libs/logical/q_res/chips/chips.prt';

PART_NAME
 R1331 'Q_RES_0402LF-4.7K,5%,1/16W,EMPA':;

SECTION_NUMBER 1
 '@S9S_MB_2U_LIB.S9S_MB_2U(SCH_1):PAGE231_I95@PURE_QUANTA.Q_RES(CHIPS)':
 C_PATH='@s9s_mb_2u_lib.s9s_mb_2u(sch_1):page231_i95@pure_quanta.q_res(chips)',
 P_PATH='@s9s_mb_2u_lib.s9s_mb_2u(sch_1):page243_i95@pure_quanta.q_res(chips)',
 PATH='I95',
 DRAWING='@S9S_MB_2U_LIB.S9S_MB_2U(SCH_1):PAGE231',
 PHYS_PAGE='243',
 XY='(-1675,2525)',
 ROT='2',
 VER='2',
 PACK_TYPE='0402LF',
 CDS_LIB='pure_quanta',
 CDS_PART_NAME='Q_RES_0402LF-4.7K,5%,1/16W,EMPA',
 WATTAGE='1/16W',
 TOLERANCE='5%',
 MATERIAL='EMPTY',
 VALUE='4.7K',
 PRIM_FILE='./archive_libs/logical/q_res/chips/chips.prt';

PART_NAME
 R1332 'Q_RES_0402LF-4.7K,5%,1/16W,EMPA':;

SECTION_NUMBER 1
 '@S9S_MB_2U_LIB.S9S_MB_2U(SCH_1):PAGE231_I93@PURE_QUANTA.Q_RES(CHIPS)':
 C_PATH='@s9s_mb_2u_lib.s9s_mb_2u(sch_1):page231_i93@pure_quanta.q_res(chips)',
 P_PATH='@s9s_mb_2u_lib.s9s_mb_2u(sch_1):page243_i93@pure_quanta.q_res(chips)',
 PATH='I93',
 DRAWING='@S9S_MB_2U_LIB.S9S_MB_2U(SCH_1):PAGE231',
 PHYS_PAGE='243',
 XY='(-1575,2525)',
 ROT='0',
 VER='2',
 PACK_TYPE='0402LF',
 CDS_LIB='pure_quanta',
 CDS_PART_NAME='Q_RES_0402LF-4.7K,5%,1/16W,EMPA',
 WATTAGE='1/16W',
 TOLERANCE='5%',
 MATERIAL='EMPTY',
 VALUE='4.7K',
 PRIM_FILE='./archive_libs/logical/q_res/chips/chips.prt';

PART_NAME
 R1333 'Q_RES_0402LF-1K,1%,1/16W,CHIP,A':;

SECTION_NUMBER 1
 '@S9S_MB_2U_LIB.S9S_MB_2U(SCH_1):PAGE189_I123@PURE_QUANTA.Q_RES(CHIPS)':
 C_PATH='@s9s_mb_2u_lib.s9s_mb_2u(sch_1):page189_i123@pure_quanta.q_res(chips)',
 P_PATH='@s9s_mb_2u_lib.s9s_mb_2u(sch_1):page201_i123@pure_quanta.q_res(chips)',
 PATH='I123',
 DRAWING='@S9S_MB_2U_LIB.S9S_MB_2U(SCH_1):PAGE189',
 PHYS_PAGE='201',
 XY='(-550,1550)',
 ROT='0',
 VER='1',
 PACK_TYPE='0402LF',
 CDS_LIB='pure_quanta',
 CDS_PART_NAME='Q_RES_0402LF-1K,1%,1/16W,CHIP,A',
 WATTAGE='1/16W',
 TOLERANCE='1%',
 MATERIAL='CHIP',
 VALUE='1K',
 PRIM_FILE='./archive_libs/logical/q_res/chips/chips.prt';

PART_NAME
 R1335 'Q_RES_0402LF-1K,1%,1/16W,CHIP,A':;

SECTION_NUMBER 1
 '@S9S_MB_2U_LIB.S9S_MB_2U(SCH_1):PAGE189_I133@PURE_QUANTA.Q_RES(CHIPS)':
 C_PATH='@s9s_mb_2u_lib.s9s_mb_2u(sch_1):page189_i133@pure_quanta.q_res(chips)',
 P_PATH='@s9s_mb_2u_lib.s9s_mb_2u(sch_1):page201_i133@pure_quanta.q_res(chips)',
 PATH='I133',
 DRAWING='@S9S_MB_2U_LIB.S9S_MB_2U(SCH_1):PAGE189',
 PHYS_PAGE='201',
 XY='(-350,3400)',
 ROT='0',
 VER='1',
 PACK_TYPE='0402LF',
 CDS_LIB='pure_quanta',
 CDS_PART_NAME='Q_RES_0402LF-1K,1%,1/16W,CHIP,A',
 WATTAGE='1/16W',
 TOLERANCE='1%',
 MATERIAL='CHIP',
 VALUE='1K',
 PRIM_FILE='./archive_libs/logical/q_res/chips/chips.prt';

PART_NAME
 R1336 'Q_RES_0402LF-2.2K,5%,1/16W,EMPA':;

SECTION_NUMBER 1
 '@S9S_MB_2U_LIB.S9S_MB_2U(SCH_1):PAGE228_I177@PURE_QUANTA.Q_RES(CHIPS)':
 C_PATH='@s9s_mb_2u_lib.s9s_mb_2u(sch_1):page228_i177@pure_quanta.q_res(chips)',
 P_PATH='@s9s_mb_2u_lib.s9s_mb_2u(sch_1):page241_i177@pure_quanta.q_res(chips)',
 PATH='I177',
 DRAWING='@S9S_MB_2U_LIB.S9S_MB_2U(SCH_1):PAGE228',
 PHYS_PAGE='241',
 XY='(5000,4375)',
 ROT='0',
 VER='1',
 PACK_TYPE='0402LF',
 CDS_LIB='pure_quanta',
 CDS_PART_NAME='Q_RES_0402LF-2.2K,5%,1/16W,EMPA',
 WATTAGE='1/16W',
 TOLERANCE='5%',
 MATERIAL='EMPTY',
 VALUE='2.2K',
 PRIM_FILE='./archive_libs/logical/q_res/chips/chips.prt';

PART_NAME
 R1338 'Q_RES_0402LF-10K,1%,1/16W,CHIPA':;

SECTION_NUMBER 1
 '@S9S_MB_2U_LIB.S9S_MB_2U(SCH_1):PAGE189_I107@PURE_QUANTA.Q_RES(CHIPS)':
 C_PATH='@s9s_mb_2u_lib.s9s_mb_2u(sch_1):page189_i107@pure_quanta.q_res(chips)',
 P_PATH='@s9s_mb_2u_lib.s9s_mb_2u(sch_1):page201_i107@pure_quanta.q_res(chips)',
 PATH='I107',
 DRAWING='@S9S_MB_2U_LIB.S9S_MB_2U(SCH_1):PAGE189',
 PHYS_PAGE='201',
 XY='(2800,3025)',
 ROT='0',
 VER='2',
 PACK_TYPE='0402LF',
 CDS_LIB='pure_quanta',
 CDS_PART_NAME='Q_RES_0402LF-10K,1%,1/16W,CHIPA',
 WATTAGE='1/16W',
 TOLERANCE='1%',
 MATERIAL='CHIP',
 VALUE='10K',
 PRIM_FILE='./archive_libs/logical/q_res/chips/chips.prt';

PART_NAME
 R1339 'Q_RES_0402LF-10K,1%,1/16W,CHIPA':;

SECTION_NUMBER 1
 '@S9S_MB_2U_LIB.S9S_MB_2U(SCH_1):PAGE189_I100@PURE_QUANTA.Q_RES(CHIPS)':
 C_PATH='@s9s_mb_2u_lib.s9s_mb_2u(sch_1):page189_i100@pure_quanta.q_res(chips)',
 P_PATH='@s9s_mb_2u_lib.s9s_mb_2u(sch_1):page201_i100@pure_quanta.q_res(chips)',
 PATH='I100',
 DRAWING='@S9S_MB_2U_LIB.S9S_MB_2U(SCH_1):PAGE189',
 PHYS_PAGE='201',
 XY='(3575,3950)',
 ROT='0',
 VER='2',
 PACK_TYPE='0402LF',
 CDS_LIB='pure_quanta',
 CDS_PART_NAME='Q_RES_0402LF-10K,1%,1/16W,CHIPA',
 WATTAGE='1/16W',
 TOLERANCE='1%',
 MATERIAL='CHIP',
 VALUE='10K',
 PRIM_FILE='./archive_libs/logical/q_res/chips/chips.prt';

PART_NAME
 R1340 'Q_RES_0402LF-20K,1%,1/16W,CHIPA':;

SECTION_NUMBER 1
 '@S9S_MB_2U_LIB.S9S_MB_2U(SCH_1):PAGE189_I127@PURE_QUANTA.Q_RES(CHIPS)':
 C_PATH='@s9s_mb_2u_lib.s9s_mb_2u(sch_1):page189_i127@pure_quanta.q_res(chips)',
 P_PATH='@s9s_mb_2u_lib.s9s_mb_2u(sch_1):page201_i127@pure_quanta.q_res(chips)',
 PATH='I127',
 DRAWING='@S9S_MB_2U_LIB.S9S_MB_2U(SCH_1):PAGE189',
 PHYS_PAGE='201',
 XY='(2900,2050)',
 ROT='0',
 VER='2',
 PACK_TYPE='0402LF',
 CDS_LIB='pure_quanta',
 CDS_PART_NAME='Q_RES_0402LF-20K,1%,1/16W,CHIPA',
 WATTAGE='1/16W',
 TOLERANCE='1%',
 MATERIAL='CHIP',
 VALUE='20K',
 PRIM_FILE='./archive_libs/logical/q_res/chips/chips.prt';

PART_NAME
 R1341 'Q_RES_0402LF-10K,1%,1/16W,CHIPA':;

SECTION_NUMBER 1
 '@S9S_MB_2U_LIB.S9S_MB_2U(SCH_1):PAGE189_I106@PURE_QUANTA.Q_RES(CHIPS)':
 C_PATH='@s9s_mb_2u_lib.s9s_mb_2u(sch_1):page189_i106@pure_quanta.q_res(chips)',
 P_PATH='@s9s_mb_2u_lib.s9s_mb_2u(sch_1):page201_i106@pure_quanta.q_res(chips)',
 PATH='I106',
 DRAWING='@S9S_MB_2U_LIB.S9S_MB_2U(SCH_1):PAGE189',
 PHYS_PAGE='201',
 XY='(3025,3025)',
 ROT='0',
 VER='2',
 PACK_TYPE='0402LF',
 CDS_LIB='pure_quanta',
 CDS_PART_NAME='Q_RES_0402LF-10K,1%,1/16W,CHIPA',
 WATTAGE='1/16W',
 TOLERANCE='1%',
 MATERIAL='CHIP',
 VALUE='10K',
 PRIM_FILE='./archive_libs/logical/q_res/chips/chips.prt';

PART_NAME
 R1342 'Q_RES_0402LF-10K,1%,1/16W,CHIPA':;

SECTION_NUMBER 1
 '@S9S_MB_2U_LIB.S9S_MB_2U(SCH_1):PAGE189_I114@PURE_QUANTA.Q_RES(CHIPS)':
 C_PATH='@s9s_mb_2u_lib.s9s_mb_2u(sch_1):page189_i114@pure_quanta.q_res(chips)',
 P_PATH='@s9s_mb_2u_lib.s9s_mb_2u(sch_1):page201_i114@pure_quanta.q_res(chips)',
 PATH='I114',
 DRAWING='@S9S_MB_2U_LIB.S9S_MB_2U(SCH_1):PAGE189',
 PHYS_PAGE='201',
 XY='(4250,3950)',
 ROT='0',
 VER='2',
 PACK_TYPE='0402LF',
 CDS_LIB='pure_quanta',
 CDS_PART_NAME='Q_RES_0402LF-10K,1%,1/16W,CHIPA',
 WATTAGE='1/16W',
 TOLERANCE='1%',
 MATERIAL='CHIP',
 VALUE='10K',
 PRIM_FILE='./archive_libs/logical/q_res/chips/chips.prt';

PART_NAME
 R1343 'Q_RES_0402LF-10K,1%,1/16W,CHIPA':;

SECTION_NUMBER 1
 '@S9S_MB_2U_LIB.S9S_MB_2U(SCH_1):PAGE189_I113@PURE_QUANTA.Q_RES(CHIPS)':
 C_PATH='@s9s_mb_2u_lib.s9s_mb_2u(sch_1):page189_i113@pure_quanta.q_res(chips)',
 P_PATH='@s9s_mb_2u_lib.s9s_mb_2u(sch_1):page201_i113@pure_quanta.q_res(chips)',
 PATH='I113',
 DRAWING='@S9S_MB_2U_LIB.S9S_MB_2U(SCH_1):PAGE189',
 PHYS_PAGE='201',
 XY='(4000,3950)',
 ROT='0',
 VER='2',
 PACK_TYPE='0402LF',
 CDS_LIB='pure_quanta',
 CDS_PART_NAME='Q_RES_0402LF-10K,1%,1/16W,CHIPA',
 WATTAGE='1/16W',
 TOLERANCE='1%',
 MATERIAL='CHIP',
 VALUE='10K',
 PRIM_FILE='./archive_libs/logical/q_res/chips/chips.prt';

PART_NAME
 R1345 'Q_RES_0402LF-0,5%,1/16W,CHIP,CA':;

SECTION_NUMBER 1
 '@S9S_MB_2U_LIB.S9S_MB_2U(SCH_1):PAGE226_I13@PURE_QUANTA.Q_RES(CHIPS)':
 C_PATH='@s9s_mb_2u_lib.s9s_mb_2u(sch_1):page226_i13@pure_quanta.q_res(chips)',
 P_PATH='@s9s_mb_2u_lib.s9s_mb_2u(sch_1):page239_i13@pure_quanta.q_res(chips)',
 PATH='I13',
 DRAWING='@S9S_MB_2U_LIB.S9S_MB_2U(SCH_1):PAGE226',
 PHYS_PAGE='239',
 XY='(-9850,3150)',
 ROT='0',
 VER='1',
 PACK_TYPE='0402LF',
 CDS_LIB='pure_quanta',
 CDS_PART_NAME='Q_RES_0402LF-0,5%,1/16W,CHIP,CA',
 WATTAGE='1/16W',
 TOLERANCE='5%',
 MATERIAL='CHIP',
 VALUE='0',
 PRIM_FILE='./archive_libs/logical/q_res/chips/chips.prt';

PART_NAME
 R1346 'Q_RES_0402LF-100,1%,1/16W,CHIPA':;

SECTION_NUMBER 1
 '@S9S_MB_2U_LIB.S9S_MB_2U(SCH_1):PAGE226_I34@PURE_QUANTA.Q_RES(CHIPS)':
 C_PATH='@s9s_mb_2u_lib.s9s_mb_2u(sch_1):page226_i34@pure_quanta.q_res(chips)',
 P_PATH='@s9s_mb_2u_lib.s9s_mb_2u(sch_1):page239_i34@pure_quanta.q_res(chips)',
 PATH='I34',
 DRAWING='@S9S_MB_2U_LIB.S9S_MB_2U(SCH_1):PAGE226',
 PHYS_PAGE='239',
 XY='(-9450,1825)',
 ROT='0',
 VER='1',
 PACK_TYPE='0402LF',
 CDS_LIB='pure_quanta',
 CDS_PART_NAME='Q_RES_0402LF-100,1%,1/16W,CHIPA',
 WATTAGE='1/16W',
 TOLERANCE='1%',
 MATERIAL='CHIP',
 VALUE='100',
 PRIM_FILE='./archive_libs/logical/q_res/chips/chips.prt';

PART_NAME
 R1347 'Q_RES_0402LF-1K,1%,1/16W,CHIP,A':;

SECTION_NUMBER 1
 '@S9S_MB_2U_LIB.S9S_MB_2U(SCH_1):PAGE226_I10@PURE_QUANTA.Q_RES(CHIPS)':
 C_PATH='@s9s_mb_2u_lib.s9s_mb_2u(sch_1):page226_i10@pure_quanta.q_res(chips)',
 P_PATH='@s9s_mb_2u_lib.s9s_mb_2u(sch_1):page239_i10@pure_quanta.q_res(chips)',
 PATH='I10',
 DRAWING='@S9S_MB_2U_LIB.S9S_MB_2U(SCH_1):PAGE226',
 PHYS_PAGE='239',
 XY='(-9400,3400)',
 ROT='0',
 VER='1',
 PACK_TYPE='0402LF',
 CDS_LIB='pure_quanta',
 CDS_PART_NAME='Q_RES_0402LF-1K,1%,1/16W,CHIP,A',
 WATTAGE='1/16W',
 TOLERANCE='1%',
 MATERIAL='CHIP',
 VALUE='1K',
 PRIM_FILE='./archive_libs/logical/q_res/chips/chips.prt';

PART_NAME
 R1348 'Q_RES_0402LF-0,5%,1/16W,CHIP,CA':;

SECTION_NUMBER 1
 '@S9S_MB_2U_LIB.S9S_MB_2U(SCH_1):PAGE137_I88@PURE_QUANTA.Q_RES(CHIPS)':
 C_PATH='@s9s_mb_2u_lib.s9s_mb_2u(sch_1):page137_i88@pure_quanta.q_res(chips)',
 P_PATH='@s9s_mb_2u_lib.s9s_mb_2u(sch_1):page134_i88@pure_quanta.q_res(chips)',
 PATH='I88',
 DRAWING='@S9S_MB_2U_LIB.S9S_MB_2U(SCH_1):PAGE137',
 PHYS_PAGE='134',
 XY='(-4350,-2550)',
 ROT='0',
 VER='1',
 PACK_TYPE='0402LF',
 CDS_LIB='pure_quanta',
 CDS_PART_NAME='Q_RES_0402LF-0,5%,1/16W,CHIP,CA',
 WATTAGE='1/16W',
 TOLERANCE='5%',
 MATERIAL='CHIP',
 VALUE='0',
 PRIM_FILE='./archive_libs/logical/q_res/chips/chips.prt';

PART_NAME
 R1349 'Q_RES_0402LF-0,5%,1/16W,CHIP,CA':;

SECTION_NUMBER 1
 '@S9S_MB_2U_LIB.S9S_MB_2U(SCH_1):PAGE137_I87@PURE_QUANTA.Q_RES(CHIPS)':
 C_PATH='@s9s_mb_2u_lib.s9s_mb_2u(sch_1):page137_i87@pure_quanta.q_res(chips)',
 P_PATH='@s9s_mb_2u_lib.s9s_mb_2u(sch_1):page134_i87@pure_quanta.q_res(chips)',
 PATH='I87',
 DRAWING='@S9S_MB_2U_LIB.S9S_MB_2U(SCH_1):PAGE137',
 PHYS_PAGE='134',
 XY='(-4350,-2400)',
 ROT='0',
 VER='1',
 PACK_TYPE='0402LF',
 CDS_LIB='pure_quanta',
 CDS_PART_NAME='Q_RES_0402LF-0,5%,1/16W,CHIP,CA',
 WATTAGE='1/16W',
 TOLERANCE='5%',
 MATERIAL='CHIP',
 VALUE='0',
 PRIM_FILE='./archive_libs/logical/q_res/chips/chips.prt';

PART_NAME
 R1350 'Q_RES_0402LF-100K,1%,1/16W,CHIA':;

SECTION_NUMBER 1
 '@S9S_MB_2U_LIB.S9S_MB_2U(SCH_1):PAGE151_I73@PURE_QUANTA.Q_RES(CHIPS)':
 C_PATH='@s9s_mb_2u_lib.s9s_mb_2u(sch_1):page151_i73@pure_quanta.q_res(chips)',
 P_PATH='@s9s_mb_2u_lib.s9s_mb_2u(sch_1):page154_i73@pure_quanta.q_res(chips)',
 PATH='I73',
 DRAWING='@S9S_MB_2U_LIB.S9S_MB_2U(SCH_1):PAGE151',
 PHYS_PAGE='154',
 XY='(1625,4200)',
 ROT='0',
 VER='1',
 PACK_TYPE='0402LF',
 CDS_LIB='pure_quanta',
 CDS_PART_NAME='Q_RES_0402LF-100K,1%,1/16W,CHIA',
 WATTAGE='1/16W',
 TOLERANCE='1%',
 MATERIAL='CHIP',
 VALUE='100K',
 PRIM_FILE='./archive_libs/logical/q_res/chips/chips.prt';

PART_NAME
 R1351 'Q_RES_0402LF-100K,1%,1/16W,CHIA':;

SECTION_NUMBER 1
 '@S9S_MB_2U_LIB.S9S_MB_2U(SCH_1):PAGE151_I72@PURE_QUANTA.Q_RES(CHIPS)':
 C_PATH='@s9s_mb_2u_lib.s9s_mb_2u(sch_1):page151_i72@pure_quanta.q_res(chips)',
 P_PATH='@s9s_mb_2u_lib.s9s_mb_2u(sch_1):page154_i72@pure_quanta.q_res(chips)',
 PATH='I72',
 DRAWING='@S9S_MB_2U_LIB.S9S_MB_2U(SCH_1):PAGE151',
 PHYS_PAGE='154',
 XY='(1625,4050)',
 ROT='0',
 VER='1',
 PACK_TYPE='0402LF',
 CDS_LIB='pure_quanta',
 CDS_PART_NAME='Q_RES_0402LF-100K,1%,1/16W,CHIA',
 WATTAGE='1/16W',
 TOLERANCE='1%',
 MATERIAL='CHIP',
 VALUE='100K',
 PRIM_FILE='./archive_libs/logical/q_res/chips/chips.prt';

PART_NAME
 R1352 'Q_RES_0402LF-100K,1%,1/16W,CHIA':;

SECTION_NUMBER 1
 '@S9S_MB_2U_LIB.S9S_MB_2U(SCH_1):PAGE151_I71@PURE_QUANTA.Q_RES(CHIPS)':
 C_PATH='@s9s_mb_2u_lib.s9s_mb_2u(sch_1):page151_i71@pure_quanta.q_res(chips)',
 P_PATH='@s9s_mb_2u_lib.s9s_mb_2u(sch_1):page154_i71@pure_quanta.q_res(chips)',
 PATH='I71',
 DRAWING='@S9S_MB_2U_LIB.S9S_MB_2U(SCH_1):PAGE151',
 PHYS_PAGE='154',
 XY='(1625,3900)',
 ROT='0',
 VER='1',
 PACK_TYPE='0402LF',
 CDS_LIB='pure_quanta',
 CDS_PART_NAME='Q_RES_0402LF-100K,1%,1/16W,CHIA',
 WATTAGE='1/16W',
 TOLERANCE='1%',
 MATERIAL='CHIP',
 VALUE='100K',
 PRIM_FILE='./archive_libs/logical/q_res/chips/chips.prt';

PART_NAME
 R1353 'Q_RES_0402LF-100K,1%,1/16W,CHIA':;

SECTION_NUMBER 1
 '@S9S_MB_2U_LIB.S9S_MB_2U(SCH_1):PAGE151_I56@PURE_QUANTA.Q_RES(CHIPS)':
 C_PATH='@s9s_mb_2u_lib.s9s_mb_2u(sch_1):page151_i56@pure_quanta.q_res(chips)',
 P_PATH='@s9s_mb_2u_lib.s9s_mb_2u(sch_1):page154_i56@pure_quanta.q_res(chips)',
 PATH='I56',
 DRAWING='@S9S_MB_2U_LIB.S9S_MB_2U(SCH_1):PAGE151',
 PHYS_PAGE='154',
 XY='(1625,3750)',
 ROT='0',
 VER='1',
 PACK_TYPE='0402LF',
 CDS_LIB='pure_quanta',
 CDS_PART_NAME='Q_RES_0402LF-100K,1%,1/16W,CHIA',
 WATTAGE='1/16W',
 TOLERANCE='1%',
 MATERIAL='CHIP',
 VALUE='100K',
 PRIM_FILE='./archive_libs/logical/q_res/chips/chips.prt';

PART_NAME
 R1354 'Q_RES_0402LF-100K,1%,1/16W,CHIA':;

SECTION_NUMBER 1
 '@S9S_MB_2U_LIB.S9S_MB_2U(SCH_1):PAGE151_I55@PURE_QUANTA.Q_RES(CHIPS)':
 C_PATH='@s9s_mb_2u_lib.s9s_mb_2u(sch_1):page151_i55@pure_quanta.q_res(chips)',
 P_PATH='@s9s_mb_2u_lib.s9s_mb_2u(sch_1):page154_i55@pure_quanta.q_res(chips)',
 PATH='I55',
 DRAWING='@S9S_MB_2U_LIB.S9S_MB_2U(SCH_1):PAGE151',
 PHYS_PAGE='154',
 XY='(1625,3600)',
 ROT='0',
 VER='1',
 PACK_TYPE='0402LF',
 CDS_LIB='pure_quanta',
 CDS_PART_NAME='Q_RES_0402LF-100K,1%,1/16W,CHIA',
 WATTAGE='1/16W',
 TOLERANCE='1%',
 MATERIAL='CHIP',
 VALUE='100K',
 PRIM_FILE='./archive_libs/logical/q_res/chips/chips.prt';

PART_NAME
 R1355 'Q_RES_0402LF-100K,1%,1/16W,CHIA':;

SECTION_NUMBER 1
 '@S9S_MB_2U_LIB.S9S_MB_2U(SCH_1):PAGE151_I54@PURE_QUANTA.Q_RES(CHIPS)':
 C_PATH='@s9s_mb_2u_lib.s9s_mb_2u(sch_1):page151_i54@pure_quanta.q_res(chips)',
 P_PATH='@s9s_mb_2u_lib.s9s_mb_2u(sch_1):page154_i54@pure_quanta.q_res(chips)',
 PATH='I54',
 DRAWING='@S9S_MB_2U_LIB.S9S_MB_2U(SCH_1):PAGE151',
 PHYS_PAGE='154',
 XY='(1625,3450)',
 ROT='0',
 VER='1',
 PACK_TYPE='0402LF',
 CDS_LIB='pure_quanta',
 CDS_PART_NAME='Q_RES_0402LF-100K,1%,1/16W,CHIA',
 WATTAGE='1/16W',
 TOLERANCE='1%',
 MATERIAL='CHIP',
 VALUE='100K',
 PRIM_FILE='./archive_libs/logical/q_res/chips/chips.prt';

PART_NAME
 R1356 'Q_RES_0402LF-1K,1%,1/16W,CHIP,A':;

SECTION_NUMBER 1
 '@S9S_MB_2U_LIB.S9S_MB_2U(SCH_1):PAGE151_I53@PURE_QUANTA.Q_RES(CHIPS)':
 C_PATH='@s9s_mb_2u_lib.s9s_mb_2u(sch_1):page151_i53@pure_quanta.q_res(chips)',
 P_PATH='@s9s_mb_2u_lib.s9s_mb_2u(sch_1):page154_i53@pure_quanta.q_res(chips)',
 PATH='I53',
 DRAWING='@S9S_MB_2U_LIB.S9S_MB_2U(SCH_1):PAGE151',
 PHYS_PAGE='154',
 XY='(1625,3275)',
 ROT='0',
 VER='1',
 PACK_TYPE='0402LF',
 CDS_LIB='pure_quanta',
 CDS_PART_NAME='Q_RES_0402LF-1K,1%,1/16W,CHIP,A',
 WATTAGE='1/16W',
 TOLERANCE='1%',
 MATERIAL='CHIP',
 VALUE='1K',
 PRIM_FILE='./archive_libs/logical/q_res/chips/chips.prt';

PART_NAME
 R1365 'Q_RES_0402LF-1K,1%,1/16W,CHIP,A':;

SECTION_NUMBER 1
 '@S9S_MB_2U_LIB.S9S_MB_2U(SCH_1):PAGE137_I116@PURE_QUANTA.Q_RES(CHIPS)':
 C_PATH='@s9s_mb_2u_lib.s9s_mb_2u(sch_1):page137_i116@pure_quanta.q_res(chips)',
 P_PATH='@s9s_mb_2u_lib.s9s_mb_2u(sch_1):page134_i116@pure_quanta.q_res(chips)',
 PATH='I116',
 DRAWING='@S9S_MB_2U_LIB.S9S_MB_2U(SCH_1):PAGE137',
 PHYS_PAGE='134',
 XY='(-9725,-2800)',
 ROT='0',
 VER='2',
 PACK_TYPE='0402LF',
 CDS_LIB='pure_quanta',
 CDS_PART_NAME='Q_RES_0402LF-1K,1%,1/16W,CHIP,A',
 WATTAGE='1/16W',
 TOLERANCE='1%',
 MATERIAL='CHIP',
 VALUE='1K',
 PRIM_FILE='./archive_libs/logical/q_res/chips/chips.prt';

PART_NAME
 R1366 'Q_RES_0402LF-100,1%,1/16W,CHIPA':;

SECTION_NUMBER 1
 '@S9S_MB_2U_LIB.S9S_MB_2U(SCH_1):PAGE226_I64@PURE_QUANTA.Q_RES(CHIPS)':
 C_PATH='@s9s_mb_2u_lib.s9s_mb_2u(sch_1):page226_i64@pure_quanta.q_res(chips)',
 P_PATH='@s9s_mb_2u_lib.s9s_mb_2u(sch_1):page239_i64@pure_quanta.q_res(chips)',
 PATH='I64',
 DRAWING='@S9S_MB_2U_LIB.S9S_MB_2U(SCH_1):PAGE226',
 PHYS_PAGE='239',
 XY='(-13075,1625)',
 ROT='0',
 VER='1',
 PACK_TYPE='0402LF',
 CDS_LIB='pure_quanta',
 CDS_PART_NAME='Q_RES_0402LF-100,1%,1/16W,CHIPA',
 WATTAGE='1/16W',
 TOLERANCE='1%',
 MATERIAL='CHIP',
 VALUE='100',
 PRIM_FILE='./archive_libs/logical/q_res/chips/chips.prt';

PART_NAME
 R1367 'Q_RES_0402LF-100,1%,1/16W,CHIPA':;

SECTION_NUMBER 1
 '@S9S_MB_2U_LIB.S9S_MB_2U(SCH_1):PAGE226_I65@PURE_QUANTA.Q_RES(CHIPS)':
 C_PATH='@s9s_mb_2u_lib.s9s_mb_2u(sch_1):page226_i65@pure_quanta.q_res(chips)',
 P_PATH='@s9s_mb_2u_lib.s9s_mb_2u(sch_1):page239_i65@pure_quanta.q_res(chips)',
 PATH='I65',
 DRAWING='@S9S_MB_2U_LIB.S9S_MB_2U(SCH_1):PAGE226',
 PHYS_PAGE='239',
 XY='(-13075,1525)',
 ROT='0',
 VER='1',
 PACK_TYPE='0402LF',
 CDS_LIB='pure_quanta',
 CDS_PART_NAME='Q_RES_0402LF-100,1%,1/16W,CHIPA',
 WATTAGE='1/16W',
 TOLERANCE='1%',
 MATERIAL='CHIP',
 VALUE='100',
 PRIM_FILE='./archive_libs/logical/q_res/chips/chips.prt';

PART_NAME
 R1368 'Q_RES_0402LF-1K,1%,1/16W,CHIP,A':;

SECTION_NUMBER 1
 '@S9S_MB_2U_LIB.S9S_MB_2U(SCH_1):PAGE226_I48@PURE_QUANTA.Q_RES(CHIPS)':
 C_PATH='@s9s_mb_2u_lib.s9s_mb_2u(sch_1):page226_i48@pure_quanta.q_res(chips)',
 P_PATH='@s9s_mb_2u_lib.s9s_mb_2u(sch_1):page239_i48@pure_quanta.q_res(chips)',
 PATH='I48',
 DRAWING='@S9S_MB_2U_LIB.S9S_MB_2U(SCH_1):PAGE226',
 PHYS_PAGE='239',
 XY='(-12650,1250)',
 ROT='0',
 VER='2',
 PACK_TYPE='0402LF',
 CDS_LIB='pure_quanta',
 CDS_PART_NAME='Q_RES_0402LF-1K,1%,1/16W,CHIP,A',
 WATTAGE='1/16W',
 TOLERANCE='1%',
 MATERIAL='CHIP',
 VALUE='1K',
 PRIM_FILE='./archive_libs/logical/q_res/chips/chips.prt';

PART_NAME
 R1369 'Q_RES_0402LF-1K,1%,1/16W,CHIP,A':;

SECTION_NUMBER 1
 '@S9S_MB_2U_LIB.S9S_MB_2U(SCH_1):PAGE226_I47@PURE_QUANTA.Q_RES(CHIPS)':
 C_PATH='@s9s_mb_2u_lib.s9s_mb_2u(sch_1):page226_i47@pure_quanta.q_res(chips)',
 P_PATH='@s9s_mb_2u_lib.s9s_mb_2u(sch_1):page239_i47@pure_quanta.q_res(chips)',
 PATH='I47',
 DRAWING='@S9S_MB_2U_LIB.S9S_MB_2U(SCH_1):PAGE226',
 PHYS_PAGE='239',
 XY='(-12425,1250)',
 ROT='0',
 VER='2',
 PACK_TYPE='0402LF',
 CDS_LIB='pure_quanta',
 CDS_PART_NAME='Q_RES_0402LF-1K,1%,1/16W,CHIP,A',
 WATTAGE='1/16W',
 TOLERANCE='1%',
 MATERIAL='CHIP',
 VALUE='1K',
 PRIM_FILE='./archive_libs/logical/q_res/chips/chips.prt';

PART_NAME
 R1370 'Q_RES_0402LF-100,1%,1/16W,CHIPA':;

SECTION_NUMBER 1
 '@S9S_MB_2U_LIB.S9S_MB_2U(SCH_1):PAGE137_I98@PURE_QUANTA.Q_RES(CHIPS)':
 C_PATH='@s9s_mb_2u_lib.s9s_mb_2u(sch_1):page137_i98@pure_quanta.q_res(chips)',
 P_PATH='@s9s_mb_2u_lib.s9s_mb_2u(sch_1):page134_i98@pure_quanta.q_res(chips)',
 PATH='I98',
 DRAWING='@S9S_MB_2U_LIB.S9S_MB_2U(SCH_1):PAGE137',
 PHYS_PAGE='134',
 XY='(-8175,-1250)',
 ROT='2',
 VER='2',
 PACK_TYPE='0402LF',
 CDS_LIB='pure_quanta',
 CDS_PART_NAME='Q_RES_0402LF-100,1%,1/16W,CHIPA',
 WATTAGE='1/16W',
 TOLERANCE='1%',
 MATERIAL='CHIP',
 VALUE='100',
 PRIM_FILE='./archive_libs/logical/q_res/chips/chips.prt';

PART_NAME
 R1371 'Q_RES_0402LF-130,1%,1/16W,CHIPA':;

SECTION_NUMBER 1
 '@S9S_MB_2U_LIB.S9S_MB_2U(SCH_1):PAGE304_I49@PURE_QUANTA.Q_RES(CHIPS)':
 C_PATH='@s9s_mb_2u_lib.s9s_mb_2u(sch_1):page304_i49@pure_quanta.q_res(chips)',
 P_PATH='@s9s_mb_2u_lib.s9s_mb_2u(sch_1):page256_i49@pure_quanta.q_res(chips)',
 PATH='I49',
 DRAWING='@S9S_MB_2U_LIB.S9S_MB_2U(SCH_1):PAGE304',
 PHYS_PAGE='256',
 XY='(-400,4450)',
 ROT='0',
 VER='1',
 PACK_TYPE='0402LF',
 LOCATION='R1371',
 CDS_LIB='pure_quanta',
 CDS_PART_NAME='Q_RES_0402LF-130,1%,1/16W,CHIPA',
 WATTAGE='1/16W',
 TOLERANCE='1%',
 MATERIAL='CHIP',
 VALUE='130',
 PRIM_FILE='./archive_libs/logical/q_res/chips/chips.prt';

PART_NAME
 R1374 'Q_RES_0402LF-1K,1%,1/16W,CHIP,A':;

SECTION_NUMBER 1
 '@S9S_MB_2U_LIB.S9S_MB_2U(SCH_1):PAGE137_I103@PURE_QUANTA.Q_RES(CHIPS)':
 C_PATH='@s9s_mb_2u_lib.s9s_mb_2u(sch_1):page137_i103@pure_quanta.q_res(chips)',
 P_PATH='@s9s_mb_2u_lib.s9s_mb_2u(sch_1):page134_i103@pure_quanta.q_res(chips)',
 PATH='I103',
 DRAWING='@S9S_MB_2U_LIB.S9S_MB_2U(SCH_1):PAGE137',
 PHYS_PAGE='134',
 XY='(-7400,-2950)',
 ROT='0',
 VER='2',
 PACK_TYPE='0402LF',
 CDS_LIB='pure_quanta',
 CDS_PART_NAME='Q_RES_0402LF-1K,1%,1/16W,CHIP,A',
 WATTAGE='1/16W',
 TOLERANCE='1%',
 MATERIAL='CHIP',
 VALUE='1K',
 PRIM_FILE='./archive_libs/logical/q_res/chips/chips.prt';

PART_NAME
 R1375 'Q_RES_0402LF-10K,1%,1/16W,CHIPA':;

SECTION_NUMBER 1
 '@S9S_MB_2U_LIB.S9S_MB_2U(SCH_1):PAGE137_I97@PURE_QUANTA.Q_RES(CHIPS)':
 C_PATH='@s9s_mb_2u_lib.s9s_mb_2u(sch_1):page137_i97@pure_quanta.q_res(chips)',
 P_PATH='@s9s_mb_2u_lib.s9s_mb_2u(sch_1):page134_i97@pure_quanta.q_res(chips)',
 PATH='I97',
 DRAWING='@S9S_MB_2U_LIB.S9S_MB_2U(SCH_1):PAGE137',
 PHYS_PAGE='134',
 XY='(-7225,-2075)',
 ROT='2',
 VER='2',
 PACK_TYPE='0402LF',
 CDS_LIB='pure_quanta',
 CDS_PART_NAME='Q_RES_0402LF-10K,1%,1/16W,CHIPA',
 WATTAGE='1/16W',
 TOLERANCE='1%',
 MATERIAL='CHIP',
 VALUE='10K',
 PRIM_FILE='./archive_libs/logical/q_res/chips/chips.prt';

PART_NAME
 R1380 'Q_RES_0402LF-1K,1%,1/16W,CHIP,A':;

SECTION_NUMBER 1
 '@S9S_MB_2U_LIB.S9S_MB_2U(SCH_1):PAGE226_I31@PURE_QUANTA.Q_RES(CHIPS)':
 C_PATH='@s9s_mb_2u_lib.s9s_mb_2u(sch_1):page226_i31@pure_quanta.q_res(chips)',
 P_PATH='@s9s_mb_2u_lib.s9s_mb_2u(sch_1):page239_i31@pure_quanta.q_res(chips)',
 PATH='I31',
 DRAWING='@S9S_MB_2U_LIB.S9S_MB_2U(SCH_1):PAGE226',
 PHYS_PAGE='239',
 XY='(-8325,2000)',
 ROT='0',
 VER='2',
 PACK_TYPE='0402LF',
 CDS_LIB='pure_quanta',
 CDS_PART_NAME='Q_RES_0402LF-1K,1%,1/16W,CHIP,A',
 WATTAGE='1/16W',
 TOLERANCE='1%',
 MATERIAL='CHIP',
 VALUE='1K',
 PRIM_FILE='./archive_libs/logical/q_res/chips/chips.prt';

PART_NAME
 R1381 'Q_RES_0402LF-1K,1%,1/16W,CHIP,A':;

SECTION_NUMBER 1
 '@S9S_MB_2U_LIB.S9S_MB_2U(SCH_1):PAGE226_I7@PURE_QUANTA.Q_RES(CHIPS)':
 C_PATH='@s9s_mb_2u_lib.s9s_mb_2u(sch_1):page226_i7@pure_quanta.q_res(chips)',
 P_PATH='@s9s_mb_2u_lib.s9s_mb_2u(sch_1):page239_i7@pure_quanta.q_res(chips)',
 PATH='I7',
 DRAWING='@S9S_MB_2U_LIB.S9S_MB_2U(SCH_1):PAGE226',
 PHYS_PAGE='239',
 XY='(-7925,3575)',
 ROT='0',
 VER='2',
 PACK_TYPE='0402LF',
 CDS_LIB='pure_quanta',
 CDS_PART_NAME='Q_RES_0402LF-1K,1%,1/16W,CHIP,A',
 WATTAGE='1/16W',
 TOLERANCE='1%',
 MATERIAL='CHIP',
 VALUE='1K',
 PRIM_FILE='./archive_libs/logical/q_res/chips/chips.prt';

PART_NAME
 R1382 'Q_RES_0402LF-1K,1%,1/16W,CHIP,A':;

SECTION_NUMBER 1
 '@S9S_MB_2U_LIB.S9S_MB_2U(SCH_1):PAGE226_I20@PURE_QUANTA.Q_RES(CHIPS)':
 C_PATH='@s9s_mb_2u_lib.s9s_mb_2u(sch_1):page226_i20@pure_quanta.q_res(chips)',
 P_PATH='@s9s_mb_2u_lib.s9s_mb_2u(sch_1):page239_i20@pure_quanta.q_res(chips)',
 PATH='I20',
 DRAWING='@S9S_MB_2U_LIB.S9S_MB_2U(SCH_1):PAGE226',
 PHYS_PAGE='239',
 XY='(-8100,2000)',
 ROT='0',
 VER='2',
 PACK_TYPE='0402LF',
 CDS_LIB='pure_quanta',
 CDS_PART_NAME='Q_RES_0402LF-1K,1%,1/16W,CHIP,A',
 WATTAGE='1/16W',
 TOLERANCE='1%',
 MATERIAL='CHIP',
 VALUE='1K',
 PRIM_FILE='./archive_libs/logical/q_res/chips/chips.prt';

PART_NAME
 R1383 'Q_RES_0402LF-1K,1%,1/16W,CHIP,A':;

SECTION_NUMBER 1
 '@S9S_MB_2U_LIB.S9S_MB_2U(SCH_1):PAGE226_I1@PURE_QUANTA.Q_RES(CHIPS)':
 C_PATH='@s9s_mb_2u_lib.s9s_mb_2u(sch_1):page226_i1@pure_quanta.q_res(chips)',
 P_PATH='@s9s_mb_2u_lib.s9s_mb_2u(sch_1):page239_i1@pure_quanta.q_res(chips)',
 PATH='I1',
 DRAWING='@S9S_MB_2U_LIB.S9S_MB_2U(SCH_1):PAGE226',
 PHYS_PAGE='239',
 XY='(-7700,3575)',
 ROT='0',
 VER='2',
 PACK_TYPE='0402LF',
 CDS_LIB='pure_quanta',
 CDS_PART_NAME='Q_RES_0402LF-1K,1%,1/16W,CHIP,A',
 WATTAGE='1/16W',
 TOLERANCE='1%',
 MATERIAL='CHIP',
 VALUE='1K',
 PRIM_FILE='./archive_libs/logical/q_res/chips/chips.prt';

PART_NAME
 R1384 'Q_RES_0402LF-2K,1%,1/16W,EMPTYA':;

SECTION_NUMBER 1
 '@S9S_MB_2U_LIB.S9S_MB_2U(SCH_1):PAGE228_I4@PURE_QUANTA.Q_RES(CHIPS)':
 C_PATH='@s9s_mb_2u_lib.s9s_mb_2u(sch_1):page228_i4@pure_quanta.q_res(chips)',
 P_PATH='@s9s_mb_2u_lib.s9s_mb_2u(sch_1):page241_i4@pure_quanta.q_res(chips)',
 PATH='I4',
 DRAWING='@S9S_MB_2U_LIB.S9S_MB_2U(SCH_1):PAGE228',
 PHYS_PAGE='241',
 XY='(5000,5825)',
 ROT='0',
 VER='1',
 PACK_TYPE='0402LF',
 CDS_LIB='pure_quanta',
 CDS_PART_NAME='Q_RES_0402LF-2K,1%,1/16W,EMPTYA',
 WATTAGE='1/16W',
 TOLERANCE='1%',
 MATERIAL='EMPTY',
 VALUE='2K',
 PRIM_FILE='./archive_libs/logical/q_res/chips/chips.prt';

PART_NAME
 R1385 'Q_RES_0402LF-2K,1%,1/16W,EMPTYA':;

SECTION_NUMBER 1
 '@S9S_MB_2U_LIB.S9S_MB_2U(SCH_1):PAGE228_I5@PURE_QUANTA.Q_RES(CHIPS)':
 C_PATH='@s9s_mb_2u_lib.s9s_mb_2u(sch_1):page228_i5@pure_quanta.q_res(chips)',
 P_PATH='@s9s_mb_2u_lib.s9s_mb_2u(sch_1):page241_i5@pure_quanta.q_res(chips)',
 PATH='I5',
 DRAWING='@S9S_MB_2U_LIB.S9S_MB_2U(SCH_1):PAGE228',
 PHYS_PAGE='241',
 XY='(5000,5775)',
 ROT='0',
 VER='1',
 PACK_TYPE='0402LF',
 CDS_LIB='pure_quanta',
 CDS_PART_NAME='Q_RES_0402LF-2K,1%,1/16W,EMPTYA',
 WATTAGE='1/16W',
 TOLERANCE='1%',
 MATERIAL='EMPTY',
 VALUE='2K',
 PRIM_FILE='./archive_libs/logical/q_res/chips/chips.prt';

PART_NAME
 R1386 'Q_RES_0402LF-2K,1%,1/16W,EMPTYA':;

SECTION_NUMBER 1
 '@S9S_MB_2U_LIB.S9S_MB_2U(SCH_1):PAGE228_I6@PURE_QUANTA.Q_RES(CHIPS)':
 C_PATH='@s9s_mb_2u_lib.s9s_mb_2u(sch_1):page228_i6@pure_quanta.q_res(chips)',
 P_PATH='@s9s_mb_2u_lib.s9s_mb_2u(sch_1):page241_i6@pure_quanta.q_res(chips)',
 PATH='I6',
 DRAWING='@S9S_MB_2U_LIB.S9S_MB_2U(SCH_1):PAGE228',
 PHYS_PAGE='241',
 XY='(5000,5575)',
 ROT='0',
 VER='1',
 PACK_TYPE='0402LF',
 CDS_LIB='pure_quanta',
 CDS_PART_NAME='Q_RES_0402LF-2K,1%,1/16W,EMPTYA',
 WATTAGE='1/16W',
 TOLERANCE='1%',
 MATERIAL='EMPTY',
 VALUE='2K',
 PRIM_FILE='./archive_libs/logical/q_res/chips/chips.prt';

PART_NAME
 R1387 'Q_RES_0402LF-2K,1%,1/16W,EMPTYA':;

SECTION_NUMBER 1
 '@S9S_MB_2U_LIB.S9S_MB_2U(SCH_1):PAGE228_I7@PURE_QUANTA.Q_RES(CHIPS)':
 C_PATH='@s9s_mb_2u_lib.s9s_mb_2u(sch_1):page228_i7@pure_quanta.q_res(chips)',
 P_PATH='@s9s_mb_2u_lib.s9s_mb_2u(sch_1):page241_i7@pure_quanta.q_res(chips)',
 PATH='I7',
 DRAWING='@S9S_MB_2U_LIB.S9S_MB_2U(SCH_1):PAGE228',
 PHYS_PAGE='241',
 XY='(5000,5525)',
 ROT='0',
 VER='1',
 PACK_TYPE='0402LF',
 CDS_LIB='pure_quanta',
 CDS_PART_NAME='Q_RES_0402LF-2K,1%,1/16W,EMPTYA',
 WATTAGE='1/16W',
 TOLERANCE='1%',
 MATERIAL='EMPTY',
 VALUE='2K',
 PRIM_FILE='./archive_libs/logical/q_res/chips/chips.prt';

PART_NAME
 R1388 'Q_RES_0402LF-2K,1%,1/16W,EMPTYA':;

SECTION_NUMBER 1
 '@S9S_MB_2U_LIB.S9S_MB_2U(SCH_1):PAGE208_I17@PURE_QUANTA.Q_RES(CHIPS)':
 C_PATH='@s9s_mb_2u_lib.s9s_mb_2u(sch_1):page208_i17@pure_quanta.q_res(chips)',
 P_PATH='@s9s_mb_2u_lib.s9s_mb_2u(sch_1):page219_i17@pure_quanta.q_res(chips)',
 PATH='I17',
 DRAWING='@S9S_MB_2U_LIB.S9S_MB_2U(SCH_1):PAGE208',
 PHYS_PAGE='219',
 XY='(-300,1775)',
 ROT='0',
 VER='1',
 PACK_TYPE='0402LF',
 CDS_LIB='pure_quanta',
 CDS_PART_NAME='Q_RES_0402LF-2K,1%,1/16W,EMPTYA',
 WATTAGE='1/16W',
 TOLERANCE='1%',
 MATERIAL='EMPTY',
 VALUE='2K',
 PRIM_FILE='./archive_libs/logical/q_res/chips/chips.prt';

PART_NAME
 R1389 'Q_RES_0402LF-0,5%,1/16W,CHIP,CA':;

SECTION_NUMBER 1
 '@S9S_MB_2U_LIB.S9S_MB_2U(SCH_1):PAGE248_I27@PURE_QUANTA.Q_RES(CHIPS)':
 C_PATH='@s9s_mb_2u_lib.s9s_mb_2u(sch_1):page248_i27@pure_quanta.q_res(chips)',
 P_PATH='@s9s_mb_2u_lib.s9s_mb_2u(sch_1):page262_i27@pure_quanta.q_res(chips)',
 PATH='I27',
 DRAWING='@S9S_MB_2U_LIB.S9S_MB_2U(SCH_1):PAGE248',
 PHYS_PAGE='262',
 XY='(-2950,-350)',
 ROT='0',
 VER='1',
 PACK_TYPE='0402LF',
 LOCATION='R1389',
 CDS_LIB='pure_quanta',
 CDS_PART_NAME='Q_RES_0402LF-0,5%,1/16W,CHIP,CA',
 WATTAGE='1/16W',
 TOLERANCE='5%',
 MATERIAL='CHIP',
 VALUE='0',
 PRIM_FILE='./archive_libs/logical/q_res/chips/chips.prt';

PART_NAME
 R1390 'Q_RES_0402LF-1K,1%,1/16W,EMPTYA':;

SECTION_NUMBER 1
 '@S9S_MB_2U_LIB.S9S_MB_2U(SCH_1):PAGE197_I275@PURE_QUANTA.Q_RES(CHIPS)':
 C_PATH='@s9s_mb_2u_lib.s9s_mb_2u(sch_1):page197_i275@pure_quanta.q_res(chips)',
 P_PATH='@s9s_mb_2u_lib.s9s_mb_2u(sch_1):page208_i275@pure_quanta.q_res(chips)',
 PATH='I275',
 DRAWING='@S9S_MB_2U_LIB.S9S_MB_2U(SCH_1):PAGE197',
 PHYS_PAGE='208',
 XY='(-4400,9800)',
 ROT='0',
 VER='2',
 PACK_TYPE='0402LF',
 CDS_LIB='pure_quanta',
 CDS_PART_NAME='Q_RES_0402LF-1K,1%,1/16W,EMPTYA',
 WATTAGE='1/16W',
 TOLERANCE='1%',
 MATERIAL='EMPTY',
 VALUE='1K',
 PRIM_FILE='./archive_libs/logical/q_res/chips/chips.prt';

PART_NAME
 R1391 'Q_RES_0402LF-240,1%,1/16W,EMPTA':;

SECTION_NUMBER 1
 '@S9S_MB_2U_LIB.S9S_MB_2U(SCH_1):PAGE120_I61@PURE_QUANTA.Q_RES(CHIPS)':
 C_PATH='@s9s_mb_2u_lib.s9s_mb_2u(sch_1):page120_i61@pure_quanta.q_res(chips)',
 P_PATH='@s9s_mb_2u_lib.s9s_mb_2u(sch_1):page120_i61@pure_quanta.q_res(chips)',
 PATH='I61',
 DRAWING='@S9S_MB_2U_LIB.S9S_MB_2U(SCH_1):PAGE120',
 PHYS_PAGE='120',
 XY='(700,3200)',
 ROT='0',
 VER='1',
 PACK_TYPE='0402LF',
 CDS_LIB='pure_quanta',
 CDS_PART_NAME='Q_RES_0402LF-240,1%,1/16W,EMPTA',
 WATTAGE='1/16W',
 TOLERANCE='1%',
 MATERIAL='EMPTY',
 VALUE='240',
 PRIM_FILE='./archive_libs/logical/q_res/chips/chips.prt';

PART_NAME
 R1392 'Q_RES_0402LF-240,1%,1/16W,EMPTA':;

SECTION_NUMBER 1
 '@S9S_MB_2U_LIB.S9S_MB_2U(SCH_1):PAGE120_I62@PURE_QUANTA.Q_RES(CHIPS)':
 C_PATH='@s9s_mb_2u_lib.s9s_mb_2u(sch_1):page120_i62@pure_quanta.q_res(chips)',
 P_PATH='@s9s_mb_2u_lib.s9s_mb_2u(sch_1):page120_i62@pure_quanta.q_res(chips)',
 PATH='I62',
 DRAWING='@S9S_MB_2U_LIB.S9S_MB_2U(SCH_1):PAGE120',
 PHYS_PAGE='120',
 XY='(700,3075)',
 ROT='0',
 VER='1',
 PACK_TYPE='0402LF',
 CDS_LIB='pure_quanta',
 CDS_PART_NAME='Q_RES_0402LF-240,1%,1/16W,EMPTA',
 WATTAGE='1/16W',
 TOLERANCE='1%',
 MATERIAL='EMPTY',
 VALUE='240',
 PRIM_FILE='./archive_libs/logical/q_res/chips/chips.prt';

PART_NAME
 R1393 'Q_RES_0402LF-240,1%,1/16W,EMPTA':;

SECTION_NUMBER 1
 '@S9S_MB_2U_LIB.S9S_MB_2U(SCH_1):PAGE120_I66@PURE_QUANTA.Q_RES(CHIPS)':
 C_PATH='@s9s_mb_2u_lib.s9s_mb_2u(sch_1):page120_i66@pure_quanta.q_res(chips)',
 P_PATH='@s9s_mb_2u_lib.s9s_mb_2u(sch_1):page120_i66@pure_quanta.q_res(chips)',
 PATH='I66',
 DRAWING='@S9S_MB_2U_LIB.S9S_MB_2U(SCH_1):PAGE120',
 PHYS_PAGE='120',
 XY='(700,750)',
 ROT='0',
 VER='1',
 PACK_TYPE='0402LF',
 CDS_LIB='pure_quanta',
 CDS_PART_NAME='Q_RES_0402LF-240,1%,1/16W,EMPTA',
 WATTAGE='1/16W',
 TOLERANCE='1%',
 MATERIAL='EMPTY',
 VALUE='240',
 PRIM_FILE='./archive_libs/logical/q_res/chips/chips.prt';

PART_NAME
 R1394 'Q_RES_0402LF-240,1%,1/16W,EMPTA':;

SECTION_NUMBER 1
 '@S9S_MB_2U_LIB.S9S_MB_2U(SCH_1):PAGE120_I67@PURE_QUANTA.Q_RES(CHIPS)':
 C_PATH='@s9s_mb_2u_lib.s9s_mb_2u(sch_1):page120_i67@pure_quanta.q_res(chips)',
 P_PATH='@s9s_mb_2u_lib.s9s_mb_2u(sch_1):page120_i67@pure_quanta.q_res(chips)',
 PATH='I67',
 DRAWING='@S9S_MB_2U_LIB.S9S_MB_2U(SCH_1):PAGE120',
 PHYS_PAGE='120',
 XY='(700,625)',
 ROT='0',
 VER='1',
 PACK_TYPE='0402LF',
 CDS_LIB='pure_quanta',
 CDS_PART_NAME='Q_RES_0402LF-240,1%,1/16W,EMPTA',
 WATTAGE='1/16W',
 TOLERANCE='1%',
 MATERIAL='EMPTY',
 VALUE='240',
 PRIM_FILE='./archive_libs/logical/q_res/chips/chips.prt';

PART_NAME
 R1395 'Q_RES_0402LF-33.2,1%,1/16W,CHIA':;

SECTION_NUMBER 1
 '@S9S_MB_2U_LIB.S9S_MB_2U(SCH_1):PAGE177_I102@PURE_QUANTA.Q_RES(CHIPS)':
 C_PATH='@s9s_mb_2u_lib.s9s_mb_2u(sch_1):page177_i102@pure_quanta.q_res(chips)',
 P_PATH='@s9s_mb_2u_lib.s9s_mb_2u(sch_1):page185_i102@pure_quanta.q_res(chips)',
 PATH='I102',
 DRAWING='@S9S_MB_2U_LIB.S9S_MB_2U(SCH_1):PAGE177',
 PHYS_PAGE='185',
 XY='(4225,-900)',
 ROT='0',
 VER='1',
 PACK_TYPE='0402LF',
 CDS_LIB='pure_quanta',
 CDS_PART_NAME='Q_RES_0402LF-33.2,1%,1/16W,CHIA',
 WATTAGE='1/16W',
 TOLERANCE='1%',
 MATERIAL='CHIP',
 VALUE='33.2',
 PRIM_FILE='./archive_libs/logical/q_res/chips/chips.prt';

PART_NAME
 R1396 'Q_RES_0402LF-10K,1%,1/16W,CHIPA':;

SECTION_NUMBER 1
 '@S9S_MB_2U_LIB.S9S_MB_2U(SCH_1):PAGE182_I167@PURE_QUANTA.Q_RES(CHIPS)':
 C_PATH='@s9s_mb_2u_lib.s9s_mb_2u(sch_1):page182_i167@pure_quanta.q_res(chips)',
 P_PATH='@s9s_mb_2u_lib.s9s_mb_2u(sch_1):page190_i167@pure_quanta.q_res(chips)',
 PATH='I167',
 DRAWING='@S9S_MB_2U_LIB.S9S_MB_2U(SCH_1):PAGE182',
 PHYS_PAGE='190',
 XY='(10600,3275)',
 ROT='0',
 VER='1',
 PACK_TYPE='0402LF',
 CDS_LIB='pure_quanta',
 CDS_PART_NAME='Q_RES_0402LF-10K,1%,1/16W,CHIPA',
 WATTAGE='1/16W',
 TOLERANCE='1%',
 MATERIAL='CHIP',
 VALUE='10K',
 PRIM_FILE='./archive_libs/logical/q_res/chips/chips.prt';

PART_NAME
 R1398 'Q_RES_0402LF-2K,1%,1/16W,EMPTYA':;

SECTION_NUMBER 1
 '@S9S_MB_2U_LIB.S9S_MB_2U(SCH_1):PAGE208_I22@PURE_QUANTA.Q_RES(CHIPS)':
 C_PATH='@s9s_mb_2u_lib.s9s_mb_2u(sch_1):page208_i22@pure_quanta.q_res(chips)',
 P_PATH='@s9s_mb_2u_lib.s9s_mb_2u(sch_1):page219_i22@pure_quanta.q_res(chips)',
 PATH='I22',
 DRAWING='@S9S_MB_2U_LIB.S9S_MB_2U(SCH_1):PAGE208',
 PHYS_PAGE='219',
 XY='(-300,800)',
 ROT='0',
 VER='1',
 PACK_TYPE='0402LF',
 CDS_LIB='pure_quanta',
 CDS_PART_NAME='Q_RES_0402LF-2K,1%,1/16W,EMPTYA',
 WATTAGE='1/16W',
 TOLERANCE='1%',
 MATERIAL='EMPTY',
 VALUE='2K',
 PRIM_FILE='./archive_libs/logical/q_res/chips/chips.prt';

PART_NAME
 R1399 'Q_RES_0402LF-10K,1%,1/16W,CHIPA':;

SECTION_NUMBER 1
 '@S9S_MB_2U_LIB.S9S_MB_2U(SCH_1):PAGE209_I17@PURE_QUANTA.Q_RES(CHIPS)':
 C_PATH='@s9s_mb_2u_lib.s9s_mb_2u(sch_1):page209_i17@pure_quanta.q_res(chips)',
 P_PATH='@s9s_mb_2u_lib.s9s_mb_2u(sch_1):page220_i17@pure_quanta.q_res(chips)',
 PATH='I17',
 DRAWING='@S9S_MB_2U_LIB.S9S_MB_2U(SCH_1):PAGE209',
 PHYS_PAGE='220',
 XY='(-1850,1175)',
 ROT='0',
 VER='1',
 PACK_TYPE='0402LF',
 CDS_LIB='pure_quanta',
 CDS_PART_NAME='Q_RES_0402LF-10K,1%,1/16W,CHIPA',
 WATTAGE='1/16W',
 TOLERANCE='1%',
 MATERIAL='CHIP',
 VALUE='10K',
 PRIM_FILE='./archive_libs/logical/q_res/chips/chips.prt';

PART_NAME
 R1401 'Q_RES_0402LF-10K,1%,1/16W,CHIPA':;

SECTION_NUMBER 1
 '@S9S_MB_2U_LIB.S9S_MB_2U(SCH_1):PAGE209_I16@PURE_QUANTA.Q_RES(CHIPS)':
 C_PATH='@s9s_mb_2u_lib.s9s_mb_2u(sch_1):page209_i16@pure_quanta.q_res(chips)',
 P_PATH='@s9s_mb_2u_lib.s9s_mb_2u(sch_1):page220_i16@pure_quanta.q_res(chips)',
 PATH='I16',
 DRAWING='@S9S_MB_2U_LIB.S9S_MB_2U(SCH_1):PAGE209',
 PHYS_PAGE='220',
 XY='(-1850,875)',
 ROT='0',
 VER='1',
 PACK_TYPE='0402LF',
 CDS_LIB='pure_quanta',
 CDS_PART_NAME='Q_RES_0402LF-10K,1%,1/16W,CHIPA',
 WATTAGE='1/16W',
 TOLERANCE='1%',
 MATERIAL='CHIP',
 VALUE='10K',
 PRIM_FILE='./archive_libs/logical/q_res/chips/chips.prt';

PART_NAME
 R1402 'Q_RES_0402LF-2K,1%,1/16W,CHIP,A':;

SECTION_NUMBER 1
 '@S9S_MB_2U_LIB.S9S_MB_2U(SCH_1):PAGE208_I23@PURE_QUANTA.Q_RES(CHIPS)':
 C_PATH='@s9s_mb_2u_lib.s9s_mb_2u(sch_1):page208_i23@pure_quanta.q_res(chips)',
 P_PATH='@s9s_mb_2u_lib.s9s_mb_2u(sch_1):page219_i23@pure_quanta.q_res(chips)',
 PATH='I23',
 DRAWING='@S9S_MB_2U_LIB.S9S_MB_2U(SCH_1):PAGE208',
 PHYS_PAGE='219',
 XY='(-300,650)',
 ROT='0',
 VER='1',
 PACK_TYPE='0402LF',
 CDS_LIB='pure_quanta',
 CDS_PART_NAME='Q_RES_0402LF-2K,1%,1/16W,CHIP,A',
 WATTAGE='1/16W',
 TOLERANCE='1%',
 MATERIAL='CHIP',
 VALUE='2K',
 PRIM_FILE='./archive_libs/logical/q_res/chips/chips.prt';

PART_NAME
 R1403 'Q_RES_0402LF-2K,1%,1/16W,CHIP,A':;

SECTION_NUMBER 1
 '@S9S_MB_2U_LIB.S9S_MB_2U(SCH_1):PAGE208_I24@PURE_QUANTA.Q_RES(CHIPS)':
 C_PATH='@s9s_mb_2u_lib.s9s_mb_2u(sch_1):page208_i24@pure_quanta.q_res(chips)',
 P_PATH='@s9s_mb_2u_lib.s9s_mb_2u(sch_1):page219_i24@pure_quanta.q_res(chips)',
 PATH='I24',
 DRAWING='@S9S_MB_2U_LIB.S9S_MB_2U(SCH_1):PAGE208',
 PHYS_PAGE='219',
 XY='(-300,500)',
 ROT='0',
 VER='1',
 PACK_TYPE='0402LF',
 CDS_LIB='pure_quanta',
 CDS_PART_NAME='Q_RES_0402LF-2K,1%,1/16W,CHIP,A',
 WATTAGE='1/16W',
 TOLERANCE='1%',
 MATERIAL='CHIP',
 VALUE='2K',
 PRIM_FILE='./archive_libs/logical/q_res/chips/chips.prt';

PART_NAME
 R1404 'Q_RES_0402LF-2K,1%,1/16W,CHIP,A':;

SECTION_NUMBER 1
 '@S9S_MB_2U_LIB.S9S_MB_2U(SCH_1):PAGE208_I25@PURE_QUANTA.Q_RES(CHIPS)':
 C_PATH='@s9s_mb_2u_lib.s9s_mb_2u(sch_1):page208_i25@pure_quanta.q_res(chips)',
 P_PATH='@s9s_mb_2u_lib.s9s_mb_2u(sch_1):page219_i25@pure_quanta.q_res(chips)',
 PATH='I25',
 DRAWING='@S9S_MB_2U_LIB.S9S_MB_2U(SCH_1):PAGE208',
 PHYS_PAGE='219',
 XY='(-300,350)',
 ROT='0',
 VER='1',
 PACK_TYPE='0402LF',
 CDS_LIB='pure_quanta',
 CDS_PART_NAME='Q_RES_0402LF-2K,1%,1/16W,CHIP,A',
 WATTAGE='1/16W',
 TOLERANCE='1%',
 MATERIAL='CHIP',
 VALUE='2K',
 PRIM_FILE='./archive_libs/logical/q_res/chips/chips.prt';

PART_NAME
 R1405 'Q_RES_0402LF-2K,1%,1/16W,CHIP,A':;

SECTION_NUMBER 1
 '@S9S_MB_2U_LIB.S9S_MB_2U(SCH_1):PAGE208_I26@PURE_QUANTA.Q_RES(CHIPS)':
 C_PATH='@s9s_mb_2u_lib.s9s_mb_2u(sch_1):page208_i26@pure_quanta.q_res(chips)',
 P_PATH='@s9s_mb_2u_lib.s9s_mb_2u(sch_1):page219_i26@pure_quanta.q_res(chips)',
 PATH='I26',
 DRAWING='@S9S_MB_2U_LIB.S9S_MB_2U(SCH_1):PAGE208',
 PHYS_PAGE='219',
 XY='(-300,200)',
 ROT='0',
 VER='1',
 PACK_TYPE='0402LF',
 CDS_LIB='pure_quanta',
 CDS_PART_NAME='Q_RES_0402LF-2K,1%,1/16W,CHIP,A',
 WATTAGE='1/16W',
 TOLERANCE='1%',
 MATERIAL='CHIP',
 VALUE='2K',
 PRIM_FILE='./archive_libs/logical/q_res/chips/chips.prt';

PART_NAME
 R1406 'Q_RES_0402LF-2K,1%,1/16W,CHIP,A':;

SECTION_NUMBER 1
 '@S9S_MB_2U_LIB.S9S_MB_2U(SCH_1):PAGE208_I51@PURE_QUANTA.Q_RES(CHIPS)':
 C_PATH='@s9s_mb_2u_lib.s9s_mb_2u(sch_1):page208_i51@pure_quanta.q_res(chips)',
 P_PATH='@s9s_mb_2u_lib.s9s_mb_2u(sch_1):page219_i51@pure_quanta.q_res(chips)',
 PATH='I51',
 DRAWING='@S9S_MB_2U_LIB.S9S_MB_2U(SCH_1):PAGE208',
 PHYS_PAGE='219',
 XY='(-300,50)',
 ROT='0',
 VER='1',
 PACK_TYPE='0402LF',
 CDS_LIB='pure_quanta',
 CDS_PART_NAME='Q_RES_0402LF-2K,1%,1/16W,CHIP,A',
 WATTAGE='1/16W',
 TOLERANCE='1%',
 MATERIAL='CHIP',
 VALUE='2K',
 PRIM_FILE='./archive_libs/logical/q_res/chips/chips.prt';

PART_NAME
 R1407 'Q_RES_0402LF-2K,1%,1/16W,CHIP,A':;

SECTION_NUMBER 1
 '@S9S_MB_2U_LIB.S9S_MB_2U(SCH_1):PAGE208_I52@PURE_QUANTA.Q_RES(CHIPS)':
 C_PATH='@s9s_mb_2u_lib.s9s_mb_2u(sch_1):page208_i52@pure_quanta.q_res(chips)',
 P_PATH='@s9s_mb_2u_lib.s9s_mb_2u(sch_1):page219_i52@pure_quanta.q_res(chips)',
 PATH='I52',
 DRAWING='@S9S_MB_2U_LIB.S9S_MB_2U(SCH_1):PAGE208',
 PHYS_PAGE='219',
 XY='(-300,-100)',
 ROT='0',
 VER='1',
 PACK_TYPE='0402LF',
 CDS_LIB='pure_quanta',
 CDS_PART_NAME='Q_RES_0402LF-2K,1%,1/16W,CHIP,A',
 WATTAGE='1/16W',
 TOLERANCE='1%',
 MATERIAL='CHIP',
 VALUE='2K',
 PRIM_FILE='./archive_libs/logical/q_res/chips/chips.prt';

PART_NAME
 R1408 'Q_RES_0402LF-2K,1%,1/16W,CHIP,A':;

SECTION_NUMBER 1
 '@S9S_MB_2U_LIB.S9S_MB_2U(SCH_1):PAGE208_I53@PURE_QUANTA.Q_RES(CHIPS)':
 C_PATH='@s9s_mb_2u_lib.s9s_mb_2u(sch_1):page208_i53@pure_quanta.q_res(chips)',
 P_PATH='@s9s_mb_2u_lib.s9s_mb_2u(sch_1):page219_i53@pure_quanta.q_res(chips)',
 PATH='I53',
 DRAWING='@S9S_MB_2U_LIB.S9S_MB_2U(SCH_1):PAGE208',
 PHYS_PAGE='219',
 XY='(-300,-250)',
 ROT='0',
 VER='1',
 PACK_TYPE='0402LF',
 CDS_LIB='pure_quanta',
 CDS_PART_NAME='Q_RES_0402LF-2K,1%,1/16W,CHIP,A',
 WATTAGE='1/16W',
 TOLERANCE='1%',
 MATERIAL='CHIP',
 VALUE='2K',
 PRIM_FILE='./archive_libs/logical/q_res/chips/chips.prt';

PART_NAME
 R1409 'Q_RES_0402LF-2K,1%,1/16W,CHIP,A':;

SECTION_NUMBER 1
 '@S9S_MB_2U_LIB.S9S_MB_2U(SCH_1):PAGE208_I55@PURE_QUANTA.Q_RES(CHIPS)':
 C_PATH='@s9s_mb_2u_lib.s9s_mb_2u(sch_1):page208_i55@pure_quanta.q_res(chips)',
 P_PATH='@s9s_mb_2u_lib.s9s_mb_2u(sch_1):page219_i55@pure_quanta.q_res(chips)',
 PATH='I55',
 DRAWING='@S9S_MB_2U_LIB.S9S_MB_2U(SCH_1):PAGE208',
 PHYS_PAGE='219',
 XY='(-300,-400)',
 ROT='0',
 VER='1',
 PACK_TYPE='0402LF',
 CDS_LIB='pure_quanta',
 CDS_PART_NAME='Q_RES_0402LF-2K,1%,1/16W,CHIP,A',
 WATTAGE='1/16W',
 TOLERANCE='1%',
 MATERIAL='CHIP',
 VALUE='2K',
 PRIM_FILE='./archive_libs/logical/q_res/chips/chips.prt';

PART_NAME
 R1410 'Q_RES_0402LF-2K,1%,1/16W,CHIP,A':;

SECTION_NUMBER 1
 '@S9S_MB_2U_LIB.S9S_MB_2U(SCH_1):PAGE208_I54@PURE_QUANTA.Q_RES(CHIPS)':
 C_PATH='@s9s_mb_2u_lib.s9s_mb_2u(sch_1):page208_i54@pure_quanta.q_res(chips)',
 P_PATH='@s9s_mb_2u_lib.s9s_mb_2u(sch_1):page219_i54@pure_quanta.q_res(chips)',
 PATH='I54',
 DRAWING='@S9S_MB_2U_LIB.S9S_MB_2U(SCH_1):PAGE208',
 PHYS_PAGE='219',
 XY='(-300,-550)',
 ROT='0',
 VER='1',
 PACK_TYPE='0402LF',
 CDS_LIB='pure_quanta',
 CDS_PART_NAME='Q_RES_0402LF-2K,1%,1/16W,CHIP,A',
 WATTAGE='1/16W',
 TOLERANCE='1%',
 MATERIAL='CHIP',
 VALUE='2K',
 PRIM_FILE='./archive_libs/logical/q_res/chips/chips.prt';

PART_NAME
 R1411 'Q_RES_0402LF-2K,1%,1/16W,CHIP,A':;

SECTION_NUMBER 1
 '@S9S_MB_2U_LIB.S9S_MB_2U(SCH_1):PAGE208_I56@PURE_QUANTA.Q_RES(CHIPS)':
 C_PATH='@s9s_mb_2u_lib.s9s_mb_2u(sch_1):page208_i56@pure_quanta.q_res(chips)',
 P_PATH='@s9s_mb_2u_lib.s9s_mb_2u(sch_1):page219_i56@pure_quanta.q_res(chips)',
 PATH='I56',
 DRAWING='@S9S_MB_2U_LIB.S9S_MB_2U(SCH_1):PAGE208',
 PHYS_PAGE='219',
 XY='(-300,-700)',
 ROT='0',
 VER='1',
 PACK_TYPE='0402LF',
 CDS_LIB='pure_quanta',
 CDS_PART_NAME='Q_RES_0402LF-2K,1%,1/16W,CHIP,A',
 WATTAGE='1/16W',
 TOLERANCE='1%',
 MATERIAL='CHIP',
 VALUE='2K',
 PRIM_FILE='./archive_libs/logical/q_res/chips/chips.prt';

PART_NAME
 R1412 'Q_RES_0402LF-2K,1%,1/16W,CHIP,A':;

SECTION_NUMBER 1
 '@S9S_MB_2U_LIB.S9S_MB_2U(SCH_1):PAGE208_I57@PURE_QUANTA.Q_RES(CHIPS)':
 C_PATH='@s9s_mb_2u_lib.s9s_mb_2u(sch_1):page208_i57@pure_quanta.q_res(chips)',
 P_PATH='@s9s_mb_2u_lib.s9s_mb_2u(sch_1):page219_i57@pure_quanta.q_res(chips)',
 PATH='I57',
 DRAWING='@S9S_MB_2U_LIB.S9S_MB_2U(SCH_1):PAGE208',
 PHYS_PAGE='219',
 XY='(-300,-850)',
 ROT='0',
 VER='1',
 PACK_TYPE='0402LF',
 CDS_LIB='pure_quanta',
 CDS_PART_NAME='Q_RES_0402LF-2K,1%,1/16W,CHIP,A',
 WATTAGE='1/16W',
 TOLERANCE='1%',
 MATERIAL='CHIP',
 VALUE='2K',
 PRIM_FILE='./archive_libs/logical/q_res/chips/chips.prt';

PART_NAME
 R1413 'Q_RES_0402LF-2K,1%,1/16W,CHIP,A':;

SECTION_NUMBER 1
 '@S9S_MB_2U_LIB.S9S_MB_2U(SCH_1):PAGE208_I59@PURE_QUANTA.Q_RES(CHIPS)':
 C_PATH='@s9s_mb_2u_lib.s9s_mb_2u(sch_1):page208_i59@pure_quanta.q_res(chips)',
 P_PATH='@s9s_mb_2u_lib.s9s_mb_2u(sch_1):page219_i59@pure_quanta.q_res(chips)',
 PATH='I59',
 DRAWING='@S9S_MB_2U_LIB.S9S_MB_2U(SCH_1):PAGE208',
 PHYS_PAGE='219',
 XY='(-300,-1000)',
 ROT='0',
 VER='1',
 PACK_TYPE='0402LF',
 CDS_LIB='pure_quanta',
 CDS_PART_NAME='Q_RES_0402LF-2K,1%,1/16W,CHIP,A',
 WATTAGE='1/16W',
 TOLERANCE='1%',
 MATERIAL='CHIP',
 VALUE='2K',
 PRIM_FILE='./archive_libs/logical/q_res/chips/chips.prt';

PART_NAME
 R1414 'Q_RES_0402LF-2K,1%,1/16W,CHIP,A':;

SECTION_NUMBER 1
 '@S9S_MB_2U_LIB.S9S_MB_2U(SCH_1):PAGE208_I58@PURE_QUANTA.Q_RES(CHIPS)':
 C_PATH='@s9s_mb_2u_lib.s9s_mb_2u(sch_1):page208_i58@pure_quanta.q_res(chips)',
 P_PATH='@s9s_mb_2u_lib.s9s_mb_2u(sch_1):page219_i58@pure_quanta.q_res(chips)',
 PATH='I58',
 DRAWING='@S9S_MB_2U_LIB.S9S_MB_2U(SCH_1):PAGE208',
 PHYS_PAGE='219',
 XY='(-300,-1150)',
 ROT='0',
 VER='1',
 PACK_TYPE='0402LF',
 CDS_LIB='pure_quanta',
 CDS_PART_NAME='Q_RES_0402LF-2K,1%,1/16W,CHIP,A',
 WATTAGE='1/16W',
 TOLERANCE='1%',
 MATERIAL='CHIP',
 VALUE='2K',
 PRIM_FILE='./archive_libs/logical/q_res/chips/chips.prt';

PART_NAME
 R1415 'Q_RES_0402LF-2K,1%,1/16W,EMPTYA':;

SECTION_NUMBER 1
 '@S9S_MB_2U_LIB.S9S_MB_2U(SCH_1):PAGE208_I4@PURE_QUANTA.Q_RES(CHIPS)':
 C_PATH='@s9s_mb_2u_lib.s9s_mb_2u(sch_1):page208_i4@pure_quanta.q_res(chips)',
 P_PATH='@s9s_mb_2u_lib.s9s_mb_2u(sch_1):page219_i4@pure_quanta.q_res(chips)',
 PATH='I4',
 DRAWING='@S9S_MB_2U_LIB.S9S_MB_2U(SCH_1):PAGE208',
 PHYS_PAGE='219',
 XY='(-300,4000)',
 ROT='0',
 VER='1',
 PACK_TYPE='0402LF',
 CDS_LIB='pure_quanta',
 CDS_PART_NAME='Q_RES_0402LF-2K,1%,1/16W,EMPTYA',
 WATTAGE='1/16W',
 TOLERANCE='1%',
 MATERIAL='EMPTY',
 VALUE='2K',
 PRIM_FILE='./archive_libs/logical/q_res/chips/chips.prt';

PART_NAME
 R1416 'Q_RES_0402LF-2K,1%,1/16W,EMPTYA':;

SECTION_NUMBER 1
 '@S9S_MB_2U_LIB.S9S_MB_2U(SCH_1):PAGE208_I5@PURE_QUANTA.Q_RES(CHIPS)':
 C_PATH='@s9s_mb_2u_lib.s9s_mb_2u(sch_1):page208_i5@pure_quanta.q_res(chips)',
 P_PATH='@s9s_mb_2u_lib.s9s_mb_2u(sch_1):page219_i5@pure_quanta.q_res(chips)',
 PATH='I5',
 DRAWING='@S9S_MB_2U_LIB.S9S_MB_2U(SCH_1):PAGE208',
 PHYS_PAGE='219',
 XY='(-300,3850)',
 ROT='0',
 VER='1',
 PACK_TYPE='0402LF',
 CDS_LIB='pure_quanta',
 CDS_PART_NAME='Q_RES_0402LF-2K,1%,1/16W,EMPTYA',
 WATTAGE='1/16W',
 TOLERANCE='1%',
 MATERIAL='EMPTY',
 VALUE='2K',
 PRIM_FILE='./archive_libs/logical/q_res/chips/chips.prt';

PART_NAME
 R1417 'Q_RES_0402LF-2K,1%,1/16W,CHIP,A':;

SECTION_NUMBER 1
 '@S9S_MB_2U_LIB.S9S_MB_2U(SCH_1):PAGE208_I7@PURE_QUANTA.Q_RES(CHIPS)':
 C_PATH='@s9s_mb_2u_lib.s9s_mb_2u(sch_1):page208_i7@pure_quanta.q_res(chips)',
 P_PATH='@s9s_mb_2u_lib.s9s_mb_2u(sch_1):page219_i7@pure_quanta.q_res(chips)',
 PATH='I7',
 DRAWING='@S9S_MB_2U_LIB.S9S_MB_2U(SCH_1):PAGE208',
 PHYS_PAGE='219',
 XY='(-300,3700)',
 ROT='0',
 VER='1',
 PACK_TYPE='0402LF',
 CDS_LIB='pure_quanta',
 CDS_PART_NAME='Q_RES_0402LF-2K,1%,1/16W,CHIP,A',
 WATTAGE='1/16W',
 TOLERANCE='1%',
 MATERIAL='CHIP',
 VALUE='2K',
 PRIM_FILE='./archive_libs/logical/q_res/chips/chips.prt';

PART_NAME
 R1418 'Q_RES_0402LF-2K,1%,1/16W,CHIP,A':;

SECTION_NUMBER 1
 '@S9S_MB_2U_LIB.S9S_MB_2U(SCH_1):PAGE208_I6@PURE_QUANTA.Q_RES(CHIPS)':
 C_PATH='@s9s_mb_2u_lib.s9s_mb_2u(sch_1):page208_i6@pure_quanta.q_res(chips)',
 P_PATH='@s9s_mb_2u_lib.s9s_mb_2u(sch_1):page219_i6@pure_quanta.q_res(chips)',
 PATH='I6',
 DRAWING='@S9S_MB_2U_LIB.S9S_MB_2U(SCH_1):PAGE208',
 PHYS_PAGE='219',
 XY='(-300,3550)',
 ROT='0',
 VER='1',
 PACK_TYPE='0402LF',
 CDS_LIB='pure_quanta',
 CDS_PART_NAME='Q_RES_0402LF-2K,1%,1/16W,CHIP,A',
 WATTAGE='1/16W',
 TOLERANCE='1%',
 MATERIAL='CHIP',
 VALUE='2K',
 PRIM_FILE='./archive_libs/logical/q_res/chips/chips.prt';

PART_NAME
 R1419 'Q_RES_0402LF-2K,1%,1/16W,CHIP,A':;

SECTION_NUMBER 1
 '@S9S_MB_2U_LIB.S9S_MB_2U(SCH_1):PAGE208_I8@PURE_QUANTA.Q_RES(CHIPS)':
 C_PATH='@s9s_mb_2u_lib.s9s_mb_2u(sch_1):page208_i8@pure_quanta.q_res(chips)',
 P_PATH='@s9s_mb_2u_lib.s9s_mb_2u(sch_1):page219_i8@pure_quanta.q_res(chips)',
 PATH='I8',
 DRAWING='@S9S_MB_2U_LIB.S9S_MB_2U(SCH_1):PAGE208',
 PHYS_PAGE='219',
 XY='(-300,3400)',
 ROT='0',
 VER='1',
 PACK_TYPE='0402LF',
 CDS_LIB='pure_quanta',
 CDS_PART_NAME='Q_RES_0402LF-2K,1%,1/16W,CHIP,A',
 WATTAGE='1/16W',
 TOLERANCE='1%',
 MATERIAL='CHIP',
 VALUE='2K',
 PRIM_FILE='./archive_libs/logical/q_res/chips/chips.prt';

PART_NAME
 R1420 'Q_RES_0402LF-2K,1%,1/16W,CHIP,A':;

SECTION_NUMBER 1
 '@S9S_MB_2U_LIB.S9S_MB_2U(SCH_1):PAGE208_I9@PURE_QUANTA.Q_RES(CHIPS)':
 C_PATH='@s9s_mb_2u_lib.s9s_mb_2u(sch_1):page208_i9@pure_quanta.q_res(chips)',
 P_PATH='@s9s_mb_2u_lib.s9s_mb_2u(sch_1):page219_i9@pure_quanta.q_res(chips)',
 PATH='I9',
 DRAWING='@S9S_MB_2U_LIB.S9S_MB_2U(SCH_1):PAGE208',
 PHYS_PAGE='219',
 XY='(-300,3250)',
 ROT='0',
 VER='1',
 PACK_TYPE='0402LF',
 CDS_LIB='pure_quanta',
 CDS_PART_NAME='Q_RES_0402LF-2K,1%,1/16W,CHIP,A',
 WATTAGE='1/16W',
 TOLERANCE='1%',
 MATERIAL='CHIP',
 VALUE='2K',
 PRIM_FILE='./archive_libs/logical/q_res/chips/chips.prt';

PART_NAME
 R1421 'Q_RES_0402LF-2K,1%,1/16W,CHIP,A':;

SECTION_NUMBER 1
 '@S9S_MB_2U_LIB.S9S_MB_2U(SCH_1):PAGE208_I10@PURE_QUANTA.Q_RES(CHIPS)':
 C_PATH='@s9s_mb_2u_lib.s9s_mb_2u(sch_1):page208_i10@pure_quanta.q_res(chips)',
 P_PATH='@s9s_mb_2u_lib.s9s_mb_2u(sch_1):page219_i10@pure_quanta.q_res(chips)',
 PATH='I10',
 DRAWING='@S9S_MB_2U_LIB.S9S_MB_2U(SCH_1):PAGE208',
 PHYS_PAGE='219',
 XY='(-300,3100)',
 ROT='0',
 VER='1',
 PACK_TYPE='0402LF',
 CDS_LIB='pure_quanta',
 CDS_PART_NAME='Q_RES_0402LF-2K,1%,1/16W,CHIP,A',
 WATTAGE='1/16W',
 TOLERANCE='1%',
 MATERIAL='CHIP',
 VALUE='2K',
 PRIM_FILE='./archive_libs/logical/q_res/chips/chips.prt';

PART_NAME
 R1423 'Q_RES_0402LF-33.2,1%,1/16W,CHIA':;

SECTION_NUMBER 1
 '@S9S_MB_2U_LIB.S9S_MB_2U(SCH_1):PAGE211_I44@PURE_QUANTA.Q_RES(CHIPS)':
 C_PATH='@s9s_mb_2u_lib.s9s_mb_2u(sch_1):page211_i44@pure_quanta.q_res(chips)',
 P_PATH='@s9s_mb_2u_lib.s9s_mb_2u(sch_1):page222_i44@pure_quanta.q_res(chips)',
 PATH='I44',
 DRAWING='@S9S_MB_2U_LIB.S9S_MB_2U(SCH_1):PAGE211',
 PHYS_PAGE='222',
 XY='(-1625,1725)',
 ROT='0',
 VER='1',
 PACK_TYPE='0402LF',
 CDS_LIB='pure_quanta',
 CDS_PART_NAME='Q_RES_0402LF-33.2,1%,1/16W,CHIA',
 WATTAGE='1/16W',
 TOLERANCE='1%',
 MATERIAL='CHIP',
 VALUE='33.2',
 PRIM_FILE='./archive_libs/logical/q_res/chips/chips.prt';

PART_NAME
 R1434 'Q_RES_0402LF-10K,1%,1/16W,CHIPA':;

SECTION_NUMBER 1
 '@S9S_MB_2U_LIB.S9S_MB_2U(SCH_1):PAGE209_I44@PURE_QUANTA.Q_RES(CHIPS)':
 C_PATH='@s9s_mb_2u_lib.s9s_mb_2u(sch_1):page209_i44@pure_quanta.q_res(chips)',
 P_PATH='@s9s_mb_2u_lib.s9s_mb_2u(sch_1):page220_i44@pure_quanta.q_res(chips)',
 PATH='I44',
 DRAWING='@S9S_MB_2U_LIB.S9S_MB_2U(SCH_1):PAGE209',
 PHYS_PAGE='220',
 XY='(1775,850)',
 ROT='0',
 VER='1',
 PACK_TYPE='0402LF',
 CDS_LIB='pure_quanta',
 CDS_PART_NAME='Q_RES_0402LF-10K,1%,1/16W,CHIPA',
 WATTAGE='1/16W',
 TOLERANCE='1%',
 MATERIAL='CHIP',
 VALUE='10K',
 PRIM_FILE='./archive_libs/logical/q_res/chips/chips.prt';

PART_NAME
 R1435 'Q_RES_0402LF-10K,1%,1/16W,CHIPA':;

SECTION_NUMBER 1
 '@S9S_MB_2U_LIB.S9S_MB_2U(SCH_1):PAGE209_I43@PURE_QUANTA.Q_RES(CHIPS)':
 C_PATH='@s9s_mb_2u_lib.s9s_mb_2u(sch_1):page209_i43@pure_quanta.q_res(chips)',
 P_PATH='@s9s_mb_2u_lib.s9s_mb_2u(sch_1):page220_i43@pure_quanta.q_res(chips)',
 PATH='I43',
 DRAWING='@S9S_MB_2U_LIB.S9S_MB_2U(SCH_1):PAGE209',
 PHYS_PAGE='220',
 XY='(1775,700)',
 ROT='0',
 VER='1',
 PACK_TYPE='0402LF',
 CDS_LIB='pure_quanta',
 CDS_PART_NAME='Q_RES_0402LF-10K,1%,1/16W,CHIPA',
 WATTAGE='1/16W',
 TOLERANCE='1%',
 MATERIAL='CHIP',
 VALUE='10K',
 PRIM_FILE='./archive_libs/logical/q_res/chips/chips.prt';

PART_NAME
 R1437 'Q_RES_0402LF-10K,1%,1/16W,CHIPA':;

SECTION_NUMBER 1
 '@S9S_MB_2U_LIB.S9S_MB_2U(SCH_1):PAGE209_I42@PURE_QUANTA.Q_RES(CHIPS)':
 C_PATH='@s9s_mb_2u_lib.s9s_mb_2u(sch_1):page209_i42@pure_quanta.q_res(chips)',
 P_PATH='@s9s_mb_2u_lib.s9s_mb_2u(sch_1):page220_i42@pure_quanta.q_res(chips)',
 PATH='I42',
 DRAWING='@S9S_MB_2U_LIB.S9S_MB_2U(SCH_1):PAGE209',
 PHYS_PAGE='220',
 XY='(1775,400)',
 ROT='0',
 VER='1',
 PACK_TYPE='0402LF',
 CDS_LIB='pure_quanta',
 CDS_PART_NAME='Q_RES_0402LF-10K,1%,1/16W,CHIPA',
 WATTAGE='1/16W',
 TOLERANCE='1%',
 MATERIAL='CHIP',
 VALUE='10K',
 PRIM_FILE='./archive_libs/logical/q_res/chips/chips.prt';

PART_NAME
 R1440 'Q_RES_0402LF-10K,1%,1/16W,EMPTA':;

SECTION_NUMBER 1
 '@S9S_MB_2U_LIB.S9S_MB_2U(SCH_1):PAGE209_I41@PURE_QUANTA.Q_RES(CHIPS)':
 C_PATH='@s9s_mb_2u_lib.s9s_mb_2u(sch_1):page209_i41@pure_quanta.q_res(chips)',
 P_PATH='@s9s_mb_2u_lib.s9s_mb_2u(sch_1):page220_i41@pure_quanta.q_res(chips)',
 PATH='I41',
 DRAWING='@S9S_MB_2U_LIB.S9S_MB_2U(SCH_1):PAGE209',
 PHYS_PAGE='220',
 XY='(1775,-50)',
 ROT='0',
 VER='1',
 PACK_TYPE='0402LF',
 CDS_LIB='pure_quanta',
 CDS_PART_NAME='Q_RES_0402LF-10K,1%,1/16W,EMPTA',
 WATTAGE='1/16W',
 TOLERANCE='1%',
 MATERIAL='EMPTY',
 VALUE='10K',
 PRIM_FILE='./archive_libs/logical/q_res/chips/chips.prt';

PART_NAME
 R1442 'Q_RES_0402LF-33.2,1%,1/16W,CHIA':;

SECTION_NUMBER 1
 '@S9S_MB_2U_LIB.S9S_MB_2U(SCH_1):PAGE211_I48@PURE_QUANTA.Q_RES(CHIPS)':
 C_PATH='@s9s_mb_2u_lib.s9s_mb_2u(sch_1):page211_i48@pure_quanta.q_res(chips)',
 P_PATH='@s9s_mb_2u_lib.s9s_mb_2u(sch_1):page222_i48@pure_quanta.q_res(chips)',
 PATH='I48',
 DRAWING='@S9S_MB_2U_LIB.S9S_MB_2U(SCH_1):PAGE211',
 PHYS_PAGE='222',
 XY='(-1625,1500)',
 ROT='0',
 VER='1',
 PACK_TYPE='0402LF',
 CDS_LIB='pure_quanta',
 CDS_PART_NAME='Q_RES_0402LF-33.2,1%,1/16W,CHIA',
 WATTAGE='1/16W',
 TOLERANCE='1%',
 MATERIAL='CHIP',
 VALUE='33.2',
 PRIM_FILE='./archive_libs/logical/q_res/chips/chips.prt';

PART_NAME
 R1443 'Q_RES_0402LF-33.2,1%,1/16W,CHIA':;

SECTION_NUMBER 1
 '@S9S_MB_2U_LIB.S9S_MB_2U(SCH_1):PAGE211_I49@PURE_QUANTA.Q_RES(CHIPS)':
 C_PATH='@s9s_mb_2u_lib.s9s_mb_2u(sch_1):page211_i49@pure_quanta.q_res(chips)',
 P_PATH='@s9s_mb_2u_lib.s9s_mb_2u(sch_1):page222_i49@pure_quanta.q_res(chips)',
 PATH='I49',
 DRAWING='@S9S_MB_2U_LIB.S9S_MB_2U(SCH_1):PAGE211',
 PHYS_PAGE='222',
 XY='(-1625,1250)',
 ROT='0',
 VER='1',
 PACK_TYPE='0402LF',
 CDS_LIB='pure_quanta',
 CDS_PART_NAME='Q_RES_0402LF-33.2,1%,1/16W,CHIA',
 WATTAGE='1/16W',
 TOLERANCE='1%',
 MATERIAL='CHIP',
 VALUE='33.2',
 PRIM_FILE='./archive_libs/logical/q_res/chips/chips.prt';

PART_NAME
 R1444 'Q_RES_0402LF-33.2,1%,1/16W,CHIA':;

SECTION_NUMBER 1
 '@S9S_MB_2U_LIB.S9S_MB_2U(SCH_1):PAGE211_I54@PURE_QUANTA.Q_RES(CHIPS)':
 C_PATH='@s9s_mb_2u_lib.s9s_mb_2u(sch_1):page211_i54@pure_quanta.q_res(chips)',
 P_PATH='@s9s_mb_2u_lib.s9s_mb_2u(sch_1):page222_i54@pure_quanta.q_res(chips)',
 PATH='I54',
 DRAWING='@S9S_MB_2U_LIB.S9S_MB_2U(SCH_1):PAGE211',
 PHYS_PAGE='222',
 XY='(-1625,1025)',
 ROT='0',
 VER='1',
 PACK_TYPE='0402LF',
 CDS_LIB='pure_quanta',
 CDS_PART_NAME='Q_RES_0402LF-33.2,1%,1/16W,CHIA',
 WATTAGE='1/16W',
 TOLERANCE='1%',
 MATERIAL='CHIP',
 VALUE='33.2',
 PRIM_FILE='./archive_libs/logical/q_res/chips/chips.prt';

PART_NAME
 R1445 'Q_RES_0402LF-2K,1%,1/16W,CHIP,A':;

SECTION_NUMBER 1
 '@S9S_MB_2U_LIB.S9S_MB_2U(SCH_1):PAGE268_I11@PURE_QUANTA.Q_RES(CHIPS)':
 C_PATH='@s9s_mb_2u_lib.s9s_mb_2u(sch_1):page268_i11@pure_quanta.q_res(chips)',
 P_PATH='@s9s_mb_2u_lib.s9s_mb_2u(sch_1):page282_i11@pure_quanta.q_res(chips)',
 PATH='I11',
 DRAWING='@S9S_MB_2U_LIB.S9S_MB_2U(SCH_1):PAGE268',
 PHYS_PAGE='282',
 XY='(-9125,9675)',
 ROT='0',
 VER='2',
 PACK_TYPE='0402LF',
 LOCATION='R1445',
 CDS_LIB='pure_quanta',
 CDS_PART_NAME='Q_RES_0402LF-2K,1%,1/16W,CHIP,A',
 WATTAGE='1/16W',
 TOLERANCE='1%',
 MATERIAL='CHIP',
 VALUE='2K',
 PRIM_FILE='./archive_libs/logical/q_res/chips/chips.prt';

PART_NAME
 R1446 'Q_RES_0402LF-33.2,1%,1/16W,CHIA':;

SECTION_NUMBER 1
 '@S9S_MB_2U_LIB.S9S_MB_2U(SCH_1):PAGE213_I29@PURE_QUANTA.Q_RES(CHIPS)':
 C_PATH='@s9s_mb_2u_lib.s9s_mb_2u(sch_1):page213_i29@pure_quanta.q_res(chips)',
 P_PATH='@s9s_mb_2u_lib.s9s_mb_2u(sch_1):page224_i29@pure_quanta.q_res(chips)',
 PATH='I29',
 DRAWING='@S9S_MB_2U_LIB.S9S_MB_2U(SCH_1):PAGE213',
 PHYS_PAGE='224',
 XY='(-5850,2900)',
 ROT='0',
 VER='1',
 PACK_TYPE='0402LF',
 CDS_LIB='pure_quanta',
 CDS_PART_NAME='Q_RES_0402LF-33.2,1%,1/16W,CHIA',
 WATTAGE='1/16W',
 TOLERANCE='1%',
 MATERIAL='CHIP',
 VALUE='33.2',
 PRIM_FILE='./archive_libs/logical/q_res/chips/chips.prt';

PART_NAME
 R1447 'Q_RES_0402LF-33.2,1%,1/16W,CHIA':;

SECTION_NUMBER 1
 '@S9S_MB_2U_LIB.S9S_MB_2U(SCH_1):PAGE211_I68@PURE_QUANTA.Q_RES(CHIPS)':
 C_PATH='@s9s_mb_2u_lib.s9s_mb_2u(sch_1):page211_i68@pure_quanta.q_res(chips)',
 P_PATH='@s9s_mb_2u_lib.s9s_mb_2u(sch_1):page222_i68@pure_quanta.q_res(chips)',
 PATH='I68',
 DRAWING='@S9S_MB_2U_LIB.S9S_MB_2U(SCH_1):PAGE211',
 PHYS_PAGE='222',
 XY='(-1625,-375)',
 ROT='0',
 VER='1',
 PACK_TYPE='0402LF',
 CDS_LIB='pure_quanta',
 CDS_PART_NAME='Q_RES_0402LF-33.2,1%,1/16W,CHIA',
 WATTAGE='1/16W',
 TOLERANCE='1%',
 MATERIAL='CHIP',
 VALUE='33.2',
 PRIM_FILE='./archive_libs/logical/q_res/chips/chips.prt';

PART_NAME
 R1448 'Q_RES_0402LF-33.2,1%,1/16W,CHIA':;

SECTION_NUMBER 1
 '@S9S_MB_2U_LIB.S9S_MB_2U(SCH_1):PAGE211_I62@PURE_QUANTA.Q_RES(CHIPS)':
 C_PATH='@s9s_mb_2u_lib.s9s_mb_2u(sch_1):page211_i62@pure_quanta.q_res(chips)',
 P_PATH='@s9s_mb_2u_lib.s9s_mb_2u(sch_1):page222_i62@pure_quanta.q_res(chips)',
 PATH='I62',
 DRAWING='@S9S_MB_2U_LIB.S9S_MB_2U(SCH_1):PAGE211',
 PHYS_PAGE='222',
 XY='(-1625,-600)',
 ROT='0',
 VER='1',
 PACK_TYPE='0402LF',
 CDS_LIB='pure_quanta',
 CDS_PART_NAME='Q_RES_0402LF-33.2,1%,1/16W,CHIA',
 WATTAGE='1/16W',
 TOLERANCE='1%',
 MATERIAL='CHIP',
 VALUE='33.2',
 PRIM_FILE='./archive_libs/logical/q_res/chips/chips.prt';

PART_NAME
 R1449 'Q_RES_0402LF-10K,1%,1/16W,CHIPA':;

SECTION_NUMBER 1
 '@S9S_MB_2U_LIB.S9S_MB_2U(SCH_1):PAGE192_I41@PURE_QUANTA.Q_RES(CHIPS)':
 C_PATH='@s9s_mb_2u_lib.s9s_mb_2u(sch_1):page192_i41@pure_quanta.q_res(chips)',
 P_PATH='@s9s_mb_2u_lib.s9s_mb_2u(sch_1):page204_i41@pure_quanta.q_res(chips)',
 PATH='I41',
 DRAWING='@S9S_MB_2U_LIB.S9S_MB_2U(SCH_1):PAGE192',
 PHYS_PAGE='204',
 XY='(-1850,3025)',
 ROT='0',
 VER='1',
 PACK_TYPE='0402LF',
 CDS_LIB='pure_quanta',
 CDS_PART_NAME='Q_RES_0402LF-10K,1%,1/16W,CHIPA',
 WATTAGE='1/16W',
 TOLERANCE='1%',
 MATERIAL='CHIP',
 VALUE='10K',
 PRIM_FILE='./archive_libs/logical/q_res/chips/chips.prt';

PART_NAME
 R1450 'Q_RES_0402LF-10K,1%,1/16W,CHIPA':;

SECTION_NUMBER 1
 '@S9S_MB_2U_LIB.S9S_MB_2U(SCH_1):PAGE192_I42@PURE_QUANTA.Q_RES(CHIPS)':
 C_PATH='@s9s_mb_2u_lib.s9s_mb_2u(sch_1):page192_i42@pure_quanta.q_res(chips)',
 P_PATH='@s9s_mb_2u_lib.s9s_mb_2u(sch_1):page204_i42@pure_quanta.q_res(chips)',
 PATH='I42',
 DRAWING='@S9S_MB_2U_LIB.S9S_MB_2U(SCH_1):PAGE192',
 PHYS_PAGE='204',
 XY='(-1850,2900)',
 ROT='0',
 VER='1',
 PACK_TYPE='0402LF',
 CDS_LIB='pure_quanta',
 CDS_PART_NAME='Q_RES_0402LF-10K,1%,1/16W,CHIPA',
 WATTAGE='1/16W',
 TOLERANCE='1%',
 MATERIAL='CHIP',
 VALUE='10K',
 PRIM_FILE='./archive_libs/logical/q_res/chips/chips.prt';

PART_NAME
 R1451 'Q_RES_0402LF-2K,1%,1/16W,CHIP,A':;

SECTION_NUMBER 1
 '@S9S_MB_2U_LIB.S9S_MB_2U(SCH_1):PAGE175_I109@PURE_QUANTA.Q_RES(CHIPS)':
 C_PATH='@s9s_mb_2u_lib.s9s_mb_2u(sch_1):page175_i109@pure_quanta.q_res(chips)',
 P_PATH='@s9s_mb_2u_lib.s9s_mb_2u(sch_1):page183_i109@pure_quanta.q_res(chips)',
 PATH='I109',
 DRAWING='@S9S_MB_2U_LIB.S9S_MB_2U(SCH_1):PAGE175',
 PHYS_PAGE='183',
 XY='(3475,-775)',
 ROT='0',
 VER='1',
 PACK_TYPE='0402LF',
 CDS_LIB='pure_quanta',
 CDS_PART_NAME='Q_RES_0402LF-2K,1%,1/16W,CHIP,A',
 WATTAGE='1/16W',
 TOLERANCE='1%',
 MATERIAL='CHIP',
 VALUE='2K',
 PRIM_FILE='./archive_libs/logical/q_res/chips/chips.prt';

PART_NAME
 R1452 'Q_RES_0402LF-2K,1%,1/16W,CHIP,A':;

SECTION_NUMBER 1
 '@S9S_MB_2U_LIB.S9S_MB_2U(SCH_1):PAGE175_I112@PURE_QUANTA.Q_RES(CHIPS)':
 C_PATH='@s9s_mb_2u_lib.s9s_mb_2u(sch_1):page175_i112@pure_quanta.q_res(chips)',
 P_PATH='@s9s_mb_2u_lib.s9s_mb_2u(sch_1):page183_i112@pure_quanta.q_res(chips)',
 PATH='I112',
 DRAWING='@S9S_MB_2U_LIB.S9S_MB_2U(SCH_1):PAGE175',
 PHYS_PAGE='183',
 XY='(3475,-825)',
 ROT='0',
 VER='1',
 PACK_TYPE='0402LF',
 CDS_LIB='pure_quanta',
 CDS_PART_NAME='Q_RES_0402LF-2K,1%,1/16W,CHIP,A',
 WATTAGE='1/16W',
 TOLERANCE='1%',
 MATERIAL='CHIP',
 VALUE='2K',
 PRIM_FILE='./archive_libs/logical/q_res/chips/chips.prt';

PART_NAME
 R1453 'Q_RES_0402LF-2K,1%,1/16W,CHIP,A':;

SECTION_NUMBER 1
 '@S9S_MB_2U_LIB.S9S_MB_2U(SCH_1):PAGE175_I120@PURE_QUANTA.Q_RES(CHIPS)':
 C_PATH='@s9s_mb_2u_lib.s9s_mb_2u(sch_1):page175_i120@pure_quanta.q_res(chips)',
 P_PATH='@s9s_mb_2u_lib.s9s_mb_2u(sch_1):page183_i120@pure_quanta.q_res(chips)',
 PATH='I120',
 DRAWING='@S9S_MB_2U_LIB.S9S_MB_2U(SCH_1):PAGE175',
 PHYS_PAGE='183',
 XY='(3475,-925)',
 ROT='0',
 VER='1',
 PACK_TYPE='0402LF',
 CDS_LIB='pure_quanta',
 CDS_PART_NAME='Q_RES_0402LF-2K,1%,1/16W,CHIP,A',
 WATTAGE='1/16W',
 TOLERANCE='1%',
 MATERIAL='CHIP',
 VALUE='2K',
 PRIM_FILE='./archive_libs/logical/q_res/chips/chips.prt';

PART_NAME
 R1454 'Q_RES_0402LF-2K,1%,1/16W,CHIP,A':;

SECTION_NUMBER 1
 '@S9S_MB_2U_LIB.S9S_MB_2U(SCH_1):PAGE175_I121@PURE_QUANTA.Q_RES(CHIPS)':
 C_PATH='@s9s_mb_2u_lib.s9s_mb_2u(sch_1):page175_i121@pure_quanta.q_res(chips)',
 P_PATH='@s9s_mb_2u_lib.s9s_mb_2u(sch_1):page183_i121@pure_quanta.q_res(chips)',
 PATH='I121',
 DRAWING='@S9S_MB_2U_LIB.S9S_MB_2U(SCH_1):PAGE175',
 PHYS_PAGE='183',
 XY='(3475,-975)',
 ROT='0',
 VER='1',
 PACK_TYPE='0402LF',
 CDS_LIB='pure_quanta',
 CDS_PART_NAME='Q_RES_0402LF-2K,1%,1/16W,CHIP,A',
 WATTAGE='1/16W',
 TOLERANCE='1%',
 MATERIAL='CHIP',
 VALUE='2K',
 PRIM_FILE='./archive_libs/logical/q_res/chips/chips.prt';

PART_NAME
 R1455 'Q_RES_0402LF-49.9,1%,1/16W,CHIA':;

SECTION_NUMBER 1
 '@S9S_MB_2U_LIB.S9S_MB_2U(SCH_1):PAGE193_I27@PURE_QUANTA.Q_RES(CHIPS)':
 C_PATH='@s9s_mb_2u_lib.s9s_mb_2u(sch_1):page193_i27@pure_quanta.q_res(chips)',
 P_PATH='@s9s_mb_2u_lib.s9s_mb_2u(sch_1):page205_i27@pure_quanta.q_res(chips)',
 PATH='I27',
 DRAWING='@S9S_MB_2U_LIB.S9S_MB_2U(SCH_1):PAGE193',
 PHYS_PAGE='205',
 XY='(-5725,-1575)',
 ROT='0',
 VER='1',
 PACK_TYPE='0402LF',
 CDS_LIB='pure_quanta',
 CDS_PART_NAME='Q_RES_0402LF-49.9,1%,1/16W,CHIA',
 WATTAGE='1/16W',
 TOLERANCE='1%',
 MATERIAL='CHIP',
 VALUE='49.9',
 PRIM_FILE='./archive_libs/logical/q_res/chips/chips.prt';

PART_NAME
 R1456 'Q_RES_0402LF-49.9,1%,1/16W,CHIA':;

SECTION_NUMBER 1
 '@S9S_MB_2U_LIB.S9S_MB_2U(SCH_1):PAGE193_I28@PURE_QUANTA.Q_RES(CHIPS)':
 C_PATH='@s9s_mb_2u_lib.s9s_mb_2u(sch_1):page193_i28@pure_quanta.q_res(chips)',
 P_PATH='@s9s_mb_2u_lib.s9s_mb_2u(sch_1):page205_i28@pure_quanta.q_res(chips)',
 PATH='I28',
 DRAWING='@S9S_MB_2U_LIB.S9S_MB_2U(SCH_1):PAGE193',
 PHYS_PAGE='205',
 XY='(-5725,-1800)',
 ROT='0',
 VER='1',
 PACK_TYPE='0402LF',
 CDS_LIB='pure_quanta',
 CDS_PART_NAME='Q_RES_0402LF-49.9,1%,1/16W,CHIA',
 WATTAGE='1/16W',
 TOLERANCE='1%',
 MATERIAL='CHIP',
 VALUE='49.9',
 PRIM_FILE='./archive_libs/logical/q_res/chips/chips.prt';

PART_NAME
 R1457 'Q_RES_0402LF-10K,1%,1/16W,CHIPA':;

SECTION_NUMBER 1
 '@S9S_MB_2U_LIB.S9S_MB_2U(SCH_1):PAGE188_I36@PURE_QUANTA.Q_RES(CHIPS)':
 C_PATH='@s9s_mb_2u_lib.s9s_mb_2u(sch_1):page188_i36@pure_quanta.q_res(chips)',
 P_PATH='@s9s_mb_2u_lib.s9s_mb_2u(sch_1):page200_i36@pure_quanta.q_res(chips)',
 PATH='I36',
 DRAWING='@S9S_MB_2U_LIB.S9S_MB_2U(SCH_1):PAGE188',
 PHYS_PAGE='200',
 XY='(3075,3025)',
 ROT='0',
 VER='2',
 PACK_TYPE='0402LF',
 CDS_LIB='pure_quanta',
 CDS_PART_NAME='Q_RES_0402LF-10K,1%,1/16W,CHIPA',
 WATTAGE='1/16W',
 TOLERANCE='1%',
 MATERIAL='CHIP',
 VALUE='10K',
 PRIM_FILE='./archive_libs/logical/q_res/chips/chips.prt';

PART_NAME
 R1458 'Q_RES_0402LF-10K,1%,1/16W,CHIPA':;

SECTION_NUMBER 1
 '@S9S_MB_2U_LIB.S9S_MB_2U(SCH_1):PAGE192_I50@PURE_QUANTA.Q_RES(CHIPS)':
 C_PATH='@s9s_mb_2u_lib.s9s_mb_2u(sch_1):page192_i50@pure_quanta.q_res(chips)',
 P_PATH='@s9s_mb_2u_lib.s9s_mb_2u(sch_1):page204_i50@pure_quanta.q_res(chips)',
 PATH='I50',
 DRAWING='@S9S_MB_2U_LIB.S9S_MB_2U(SCH_1):PAGE192',
 PHYS_PAGE='204',
 XY='(1200,-850)',
 ROT='0',
 VER='1',
 PACK_TYPE='0402LF',
 CDS_LIB='pure_quanta',
 CDS_PART_NAME='Q_RES_0402LF-10K,1%,1/16W,CHIPA',
 WATTAGE='1/16W',
 TOLERANCE='1%',
 MATERIAL='CHIP',
 VALUE='10K',
 PRIM_FILE='./archive_libs/logical/q_res/chips/chips.prt';

PART_NAME
 R1459 'Q_RES_0402LF-10K,1%,1/16W,CHIPA':;

SECTION_NUMBER 1
 '@S9S_MB_2U_LIB.S9S_MB_2U(SCH_1):PAGE192_I51@PURE_QUANTA.Q_RES(CHIPS)':
 C_PATH='@s9s_mb_2u_lib.s9s_mb_2u(sch_1):page192_i51@pure_quanta.q_res(chips)',
 P_PATH='@s9s_mb_2u_lib.s9s_mb_2u(sch_1):page204_i51@pure_quanta.q_res(chips)',
 PATH='I51',
 DRAWING='@S9S_MB_2U_LIB.S9S_MB_2U(SCH_1):PAGE192',
 PHYS_PAGE='204',
 XY='(1200,-975)',
 ROT='0',
 VER='1',
 PACK_TYPE='0402LF',
 CDS_LIB='pure_quanta',
 CDS_PART_NAME='Q_RES_0402LF-10K,1%,1/16W,CHIPA',
 WATTAGE='1/16W',
 TOLERANCE='1%',
 MATERIAL='CHIP',
 VALUE='10K',
 PRIM_FILE='./archive_libs/logical/q_res/chips/chips.prt';

PART_NAME
 R1460 'Q_RES_0402LF-2.2K,5%,1/16W,EMPA':;

SECTION_NUMBER 1
 '@S9S_MB_2U_LIB.S9S_MB_2U(SCH_1):PAGE228_I176@PURE_QUANTA.Q_RES(CHIPS)':
 C_PATH='@s9s_mb_2u_lib.s9s_mb_2u(sch_1):page228_i176@pure_quanta.q_res(chips)',
 P_PATH='@s9s_mb_2u_lib.s9s_mb_2u(sch_1):page241_i176@pure_quanta.q_res(chips)',
 PATH='I176',
 DRAWING='@S9S_MB_2U_LIB.S9S_MB_2U(SCH_1):PAGE228',
 PHYS_PAGE='241',
 XY='(5000,4325)',
 ROT='0',
 VER='1',
 PACK_TYPE='0402LF',
 CDS_LIB='pure_quanta',
 CDS_PART_NAME='Q_RES_0402LF-2.2K,5%,1/16W,EMPA',
 WATTAGE='1/16W',
 TOLERANCE='5%',
 MATERIAL='EMPTY',
 VALUE='2.2K',
 PRIM_FILE='./archive_libs/logical/q_res/chips/chips.prt';

PART_NAME
 R1461 'Q_RES_0402LF-0,5%,1/16W,CHIP,CA':;

SECTION_NUMBER 1
 '@S9S_MB_2U_LIB.S9S_MB_2U(SCH_1):PAGE177_I80@PURE_QUANTA.Q_RES(CHIPS)':
 C_PATH='@s9s_mb_2u_lib.s9s_mb_2u(sch_1):page177_i80@pure_quanta.q_res(chips)',
 P_PATH='@s9s_mb_2u_lib.s9s_mb_2u(sch_1):page185_i80@pure_quanta.q_res(chips)',
 PATH='I80',
 DRAWING='@S9S_MB_2U_LIB.S9S_MB_2U(SCH_1):PAGE177',
 PHYS_PAGE='185',
 XY='(4225,-500)',
 ROT='0',
 VER='1',
 PACK_TYPE='0402LF',
 CDS_LIB='pure_quanta',
 CDS_PART_NAME='Q_RES_0402LF-0,5%,1/16W,CHIP,CA',
 WATTAGE='1/16W',
 TOLERANCE='5%',
 MATERIAL='CHIP',
 VALUE='0',
 PRIM_FILE='./archive_libs/logical/q_res/chips/chips.prt';

PART_NAME
 R1462 'Q_RES_0402LF-1K,1%,1/16W,CHIP,A':;

SECTION_NUMBER 1
 '@S9S_MB_2U_LIB.S9S_MB_2U(SCH_1):PAGE197_I274@PURE_QUANTA.Q_RES(CHIPS)':
 C_PATH='@s9s_mb_2u_lib.s9s_mb_2u(sch_1):page197_i274@pure_quanta.q_res(chips)',
 P_PATH='@s9s_mb_2u_lib.s9s_mb_2u(sch_1):page208_i274@pure_quanta.q_res(chips)',
 PATH='I274',
 DRAWING='@S9S_MB_2U_LIB.S9S_MB_2U(SCH_1):PAGE197',
 PHYS_PAGE='208',
 XY='(-4125,9800)',
 ROT='0',
 VER='2',
 PACK_TYPE='0402LF',
 CDS_LIB='pure_quanta',
 CDS_PART_NAME='Q_RES_0402LF-1K,1%,1/16W,CHIP,A',
 WATTAGE='1/16W',
 TOLERANCE='1%',
 MATERIAL='CHIP',
 VALUE='1K',
 PRIM_FILE='./archive_libs/logical/q_res/chips/chips.prt';

PART_NAME
 R1463 'Q_RES_0402LF-0,5%,1/16W,CHIP,CA':;

SECTION_NUMBER 1
 '@S9S_MB_2U_LIB.S9S_MB_2U(SCH_1):PAGE181_I129@PURE_QUANTA.Q_RES(CHIPS)':
 C_PATH='@s9s_mb_2u_lib.s9s_mb_2u(sch_1):page181_i129@pure_quanta.q_res(chips)',
 P_PATH='@s9s_mb_2u_lib.s9s_mb_2u(sch_1):page189_i129@pure_quanta.q_res(chips)',
 PATH='I129',
 DRAWING='@S9S_MB_2U_LIB.S9S_MB_2U(SCH_1):PAGE181',
 PHYS_PAGE='189',
 XY='(3150,3950)',
 ROT='0',
 VER='1',
 PACK_TYPE='0402LF',
 CDS_LIB='pure_quanta',
 CDS_PART_NAME='Q_RES_0402LF-0,5%,1/16W,CHIP,CA',
 WATTAGE='1/16W',
 TOLERANCE='5%',
 MATERIAL='CHIP',
 VALUE='0',
 PRIM_FILE='./archive_libs/logical/q_res/chips/chips.prt';

PART_NAME
 R1464 'Q_RES_0402LF-0,5%,1/16W,CHIP,CA':;

SECTION_NUMBER 1
 '@S9S_MB_2U_LIB.S9S_MB_2U(SCH_1):PAGE181_I144@PURE_QUANTA.Q_RES(CHIPS)':
 C_PATH='@s9s_mb_2u_lib.s9s_mb_2u(sch_1):page181_i144@pure_quanta.q_res(chips)',
 P_PATH='@s9s_mb_2u_lib.s9s_mb_2u(sch_1):page189_i144@pure_quanta.q_res(chips)',
 PATH='I144',
 DRAWING='@S9S_MB_2U_LIB.S9S_MB_2U(SCH_1):PAGE181',
 PHYS_PAGE='189',
 XY='(3200,1275)',
 ROT='0',
 VER='1',
 PACK_TYPE='0402LF',
 CDS_LIB='pure_quanta',
 CDS_PART_NAME='Q_RES_0402LF-0,5%,1/16W,CHIP,CA',
 WATTAGE='1/16W',
 TOLERANCE='5%',
 MATERIAL='CHIP',
 VALUE='0',
 PRIM_FILE='./archive_libs/logical/q_res/chips/chips.prt';

PART_NAME
 R1465 'Q_RES_0402LF-10K,1%,1/16W,EMPTA':;

SECTION_NUMBER 1
 '@S9S_MB_2U_LIB.S9S_MB_2U(SCH_1):PAGE312_I3@PURE_QUANTA.Q_RES(CHIPS)':
 C_PATH='@s9s_mb_2u_lib.s9s_mb_2u(sch_1):page312_i3@pure_quanta.q_res(chips)',
 P_PATH='@s9s_mb_2u_lib.s9s_mb_2u(sch_1):page215_i3@pure_quanta.q_res(chips)',
 PATH='I3',
 DRAWING='@S9S_MB_2U_LIB.S9S_MB_2U(SCH_1):PAGE312',
 PHYS_PAGE='215',
 XY='(975,3650)',
 ROT='0',
 VER='2',
 PACK_TYPE='0402LF',
 CDS_LIB='pure_quanta',
 CDS_PART_NAME='Q_RES_0402LF-10K,1%,1/16W,EMPTA',
 WATTAGE='1/16W',
 TOLERANCE='1%',
 MATERIAL='EMPTY',
 VALUE='10K',
 PRIM_FILE='./archive_libs/logical/q_res/chips/chips.prt';

PART_NAME
 R1467 'Q_RES_0402LF-4.7K,1%,1/16W,EMPA':;

SECTION_NUMBER 1
 '@S9S_MB_2U_LIB.S9S_MB_2U(SCH_1):PAGE314_I178@PURE_QUANTA.Q_RES(CHIPS)':
 C_PATH='@s9s_mb_2u_lib.s9s_mb_2u(sch_1):page314_i178@pure_quanta.q_res(chips)',
 P_PATH='@s9s_mb_2u_lib.s9s_mb_2u(sch_1):page213_i178@pure_quanta.q_res(chips)',
 PATH='I178',
 DRAWING='@S9S_MB_2U_LIB.S9S_MB_2U(SCH_1):PAGE314',
 PHYS_PAGE='213',
 XY='(2750,4150)',
 ROT='2',
 VER='2',
 PACK_TYPE='0402LF',
 CDS_LIB='pure_quanta',
 CDS_PART_NAME='Q_RES_0402LF-4.7K,1%,1/16W,EMPA',
 WATTAGE='1/16W',
 TOLERANCE='1%',
 MATERIAL='EMPTY',
 VALUE='4.7K',
 PRIM_FILE='./archive_libs/logical/q_res/chips/chips.prt';

PART_NAME
 R1469 'Q_RES_0402LF-33.2,1%,1/16W,CHIA':;

SECTION_NUMBER 1
 '@S9S_MB_2U_LIB.S9S_MB_2U(SCH_1):PAGE212_I55@PURE_QUANTA.Q_RES(CHIPS)':
 C_PATH='@s9s_mb_2u_lib.s9s_mb_2u(sch_1):page212_i55@pure_quanta.q_res(chips)',
 P_PATH='@s9s_mb_2u_lib.s9s_mb_2u(sch_1):page223_i55@pure_quanta.q_res(chips)',
 PATH='I55',
 DRAWING='@S9S_MB_2U_LIB.S9S_MB_2U(SCH_1):PAGE212',
 PHYS_PAGE='223',
 XY='(1925,3575)',
 ROT='0',
 VER='1',
 PACK_TYPE='0402LF',
 CDS_LIB='pure_quanta',
 CDS_PART_NAME='Q_RES_0402LF-33.2,1%,1/16W,CHIA',
 WATTAGE='1/16W',
 TOLERANCE='1%',
 MATERIAL='CHIP',
 VALUE='33.2',
 PRIM_FILE='./archive_libs/logical/q_res/chips/chips.prt';

PART_NAME
 R1470 'Q_RES_0402LF-33.2,1%,1/16W,CHIA':;

SECTION_NUMBER 1
 '@S9S_MB_2U_LIB.S9S_MB_2U(SCH_1):PAGE212_I56@PURE_QUANTA.Q_RES(CHIPS)':
 C_PATH='@s9s_mb_2u_lib.s9s_mb_2u(sch_1):page212_i56@pure_quanta.q_res(chips)',
 P_PATH='@s9s_mb_2u_lib.s9s_mb_2u(sch_1):page223_i56@pure_quanta.q_res(chips)',
 PATH='I56',
 DRAWING='@S9S_MB_2U_LIB.S9S_MB_2U(SCH_1):PAGE212',
 PHYS_PAGE='223',
 XY='(1925,3375)',
 ROT='0',
 VER='1',
 PACK_TYPE='0402LF',
 CDS_LIB='pure_quanta',
 CDS_PART_NAME='Q_RES_0402LF-33.2,1%,1/16W,CHIA',
 WATTAGE='1/16W',
 TOLERANCE='1%',
 MATERIAL='CHIP',
 VALUE='33.2',
 PRIM_FILE='./archive_libs/logical/q_res/chips/chips.prt';

PART_NAME
 R1471 'Q_RES_0402LF-4.75K,1%,1/16W,CHA':;

SECTION_NUMBER 1
 '@S9S_MB_2U_LIB.S9S_MB_2U(SCH_1):PAGE197_I267@PURE_QUANTA.Q_RES(CHIPS)':
 C_PATH='@s9s_mb_2u_lib.s9s_mb_2u(sch_1):page197_i267@pure_quanta.q_res(chips)',
 P_PATH='@s9s_mb_2u_lib.s9s_mb_2u(sch_1):page208_i267@pure_quanta.q_res(chips)',
 PATH='I267',
 DRAWING='@S9S_MB_2U_LIB.S9S_MB_2U(SCH_1):PAGE197',
 PHYS_PAGE='208',
 XY='(-3625,10725)',
 ROT='0',
 VER='2',
 PACK_TYPE='0402LF',
 CDS_LIB='pure_quanta',
 CDS_PART_NAME='Q_RES_0402LF-4.75K,1%,1/16W,CHA',
 WATTAGE='1/16W',
 TOLERANCE='1%',
 MATERIAL='CHIP',
 VALUE='4.75K',
 PRIM_FILE='./archive_libs/logical/q_res/chips/chips.prt';

PART_NAME
 R1472 'Q_RES_0402LF-33.2,1%,1/16W,CHIA':;

SECTION_NUMBER 1
 '@S9S_MB_2U_LIB.S9S_MB_2U(SCH_1):PAGE133_I144@PURE_QUANTA.Q_RES(CHIPS)':
 C_PATH='@s9s_mb_2u_lib.s9s_mb_2u(sch_1):page133_i144@pure_quanta.q_res(chips)',
 P_PATH='@s9s_mb_2u_lib.s9s_mb_2u(sch_1):page131_i144@pure_quanta.q_res(chips)',
 PATH='I144',
 DRAWING='@S9S_MB_2U_LIB.S9S_MB_2U(SCH_1):PAGE133',
 PHYS_PAGE='131',
 XY='(625,-725)',
 ROT='0',
 VER='1',
 PACK_TYPE='0402LF',
 CDS_LIB='pure_quanta',
 CDS_PART_NAME='Q_RES_0402LF-33.2,1%,1/16W,CHIA',
 WATTAGE='1/16W',
 TOLERANCE='1%',
 MATERIAL='CHIP',
 VALUE='33.2',
 PRIM_FILE='./archive_libs/logical/q_res/chips/chips.prt';

PART_NAME
 R1473 'Q_RES_0402LF-1K,1%,1/16W,CHIP,A':;

SECTION_NUMBER 1
 '@S9S_MB_2U_LIB.S9S_MB_2U(SCH_1):PAGE209_I37@PURE_QUANTA.Q_RES(CHIPS)':
 C_PATH='@s9s_mb_2u_lib.s9s_mb_2u(sch_1):page209_i37@pure_quanta.q_res(chips)',
 P_PATH='@s9s_mb_2u_lib.s9s_mb_2u(sch_1):page220_i37@pure_quanta.q_res(chips)',
 PATH='I37',
 DRAWING='@S9S_MB_2U_LIB.S9S_MB_2U(SCH_1):PAGE209',
 PHYS_PAGE='220',
 XY='(1775,-875)',
 ROT='0',
 VER='1',
 PACK_TYPE='0402LF',
 CDS_LIB='pure_quanta',
 CDS_PART_NAME='Q_RES_0402LF-1K,1%,1/16W,CHIP,A',
 WATTAGE='1/16W',
 TOLERANCE='1%',
 MATERIAL='CHIP',
 VALUE='1K',
 PRIM_FILE='./archive_libs/logical/q_res/chips/chips.prt';

PART_NAME
 R1474 'Q_RES_0402LF-1K,1%,1/16W,CHIP,A':;

SECTION_NUMBER 1
 '@S9S_MB_2U_LIB.S9S_MB_2U(SCH_1):PAGE209_I36@PURE_QUANTA.Q_RES(CHIPS)':
 C_PATH='@s9s_mb_2u_lib.s9s_mb_2u(sch_1):page209_i36@pure_quanta.q_res(chips)',
 P_PATH='@s9s_mb_2u_lib.s9s_mb_2u(sch_1):page220_i36@pure_quanta.q_res(chips)',
 PATH='I36',
 DRAWING='@S9S_MB_2U_LIB.S9S_MB_2U(SCH_1):PAGE209',
 PHYS_PAGE='220',
 XY='(1775,-975)',
 ROT='0',
 VER='1',
 PACK_TYPE='0402LF',
 CDS_LIB='pure_quanta',
 CDS_PART_NAME='Q_RES_0402LF-1K,1%,1/16W,CHIP,A',
 WATTAGE='1/16W',
 TOLERANCE='1%',
 MATERIAL='CHIP',
 VALUE='1K',
 PRIM_FILE='./archive_libs/logical/q_res/chips/chips.prt';

PART_NAME
 R1475 'Q_RES_0402LF-1K,1%,1/16W,EMPTYA':;

SECTION_NUMBER 1
 '@S9S_MB_2U_LIB.S9S_MB_2U(SCH_1):PAGE188_I44@PURE_QUANTA.Q_RES(CHIPS)':
 C_PATH='@s9s_mb_2u_lib.s9s_mb_2u(sch_1):page188_i44@pure_quanta.q_res(chips)',
 P_PATH='@s9s_mb_2u_lib.s9s_mb_2u(sch_1):page200_i44@pure_quanta.q_res(chips)',
 PATH='I44',
 DRAWING='@S9S_MB_2U_LIB.S9S_MB_2U(SCH_1):PAGE188',
 PHYS_PAGE='200',
 XY='(-150,1600)',
 ROT='0',
 VER='2',
 PACK_TYPE='0402LF',
 CDS_LIB='pure_quanta',
 CDS_PART_NAME='Q_RES_0402LF-1K,1%,1/16W,EMPTYA',
 WATTAGE='1/16W',
 TOLERANCE='1%',
 MATERIAL='EMPTY',
 VALUE='1K',
 PRIM_FILE='./archive_libs/logical/q_res/chips/chips.prt';

PART_NAME
 R1476 'Q_RES_0402LF-1K,1%,1/16W,CHIP,A':;

SECTION_NUMBER 1
 '@S9S_MB_2U_LIB.S9S_MB_2U(SCH_1):PAGE188_I43@PURE_QUANTA.Q_RES(CHIPS)':
 C_PATH='@s9s_mb_2u_lib.s9s_mb_2u(sch_1):page188_i43@pure_quanta.q_res(chips)',
 P_PATH='@s9s_mb_2u_lib.s9s_mb_2u(sch_1):page200_i43@pure_quanta.q_res(chips)',
 PATH='I43',
 DRAWING='@S9S_MB_2U_LIB.S9S_MB_2U(SCH_1):PAGE188',
 PHYS_PAGE='200',
 XY='(-150,1075)',
 ROT='0',
 VER='2',
 PACK_TYPE='0402LF',
 CDS_LIB='pure_quanta',
 CDS_PART_NAME='Q_RES_0402LF-1K,1%,1/16W,CHIP,A',
 WATTAGE='1/16W',
 TOLERANCE='1%',
 MATERIAL='CHIP',
 VALUE='1K',
 PRIM_FILE='./archive_libs/logical/q_res/chips/chips.prt';

PART_NAME
 R1477 'Q_RES_0402LF-1K,1%,1/16W,EMPTYA':;

SECTION_NUMBER 1
 '@S9S_MB_2U_LIB.S9S_MB_2U(SCH_1):PAGE188_I47@PURE_QUANTA.Q_RES(CHIPS)':
 C_PATH='@s9s_mb_2u_lib.s9s_mb_2u(sch_1):page188_i47@pure_quanta.q_res(chips)',
 P_PATH='@s9s_mb_2u_lib.s9s_mb_2u(sch_1):page200_i47@pure_quanta.q_res(chips)',
 PATH='I47',
 DRAWING='@S9S_MB_2U_LIB.S9S_MB_2U(SCH_1):PAGE188',
 PHYS_PAGE='200',
 XY='(3075,1600)',
 ROT='0',
 VER='2',
 PACK_TYPE='0402LF',
 CDS_LIB='pure_quanta',
 CDS_PART_NAME='Q_RES_0402LF-1K,1%,1/16W,EMPTYA',
 WATTAGE='1/16W',
 TOLERANCE='1%',
 MATERIAL='EMPTY',
 VALUE='1K',
 PRIM_FILE='./archive_libs/logical/q_res/chips/chips.prt';

PART_NAME
 R1478 'Q_RES_0402LF-10K,1%,1/16W,CHIPA':;

SECTION_NUMBER 1
 '@S9S_MB_2U_LIB.S9S_MB_2U(SCH_1):PAGE188_I50@PURE_QUANTA.Q_RES(CHIPS)':
 C_PATH='@s9s_mb_2u_lib.s9s_mb_2u(sch_1):page188_i50@pure_quanta.q_res(chips)',
 P_PATH='@s9s_mb_2u_lib.s9s_mb_2u(sch_1):page200_i50@pure_quanta.q_res(chips)',
 PATH='I50',
 DRAWING='@S9S_MB_2U_LIB.S9S_MB_2U(SCH_1):PAGE188',
 PHYS_PAGE='200',
 XY='(3075,1075)',
 ROT='0',
 VER='2',
 PACK_TYPE='0402LF',
 CDS_LIB='pure_quanta',
 CDS_PART_NAME='Q_RES_0402LF-10K,1%,1/16W,CHIPA',
 WATTAGE='1/16W',
 TOLERANCE='1%',
 MATERIAL='CHIP',
 VALUE='10K',
 PRIM_FILE='./archive_libs/logical/q_res/chips/chips.prt';

PART_NAME
 R1479 'Q_RES_0402LF-10,1%,1/16W,CHIP,A':;

SECTION_NUMBER 1
 '@S9S_MB_2U_LIB.S9S_MB_2U(SCH_1):PAGE190_I102@PURE_QUANTA.Q_RES(CHIPS)':
 C_PATH='@s9s_mb_2u_lib.s9s_mb_2u(sch_1):page190_i102@pure_quanta.q_res(chips)',
 P_PATH='@s9s_mb_2u_lib.s9s_mb_2u(sch_1):page202_i102@pure_quanta.q_res(chips)',
 PATH='I102',
 DRAWING='@S9S_MB_2U_LIB.S9S_MB_2U(SCH_1):PAGE190',
 PHYS_PAGE='202',
 XY='(-450,225)',
 ROT='0',
 VER='1',
 PACK_TYPE='0402LF',
 LOCATION='R1479',
 CDS_LIB='pure_quanta',
 CDS_PART_NAME='Q_RES_0402LF-10,1%,1/16W,CHIP,A',
 WATTAGE='1/16W',
 TOLERANCE='1%',
 MATERIAL='CHIP',
 VALUE='10',
 PRIM_FILE='./archive_libs/logical/q_res/chips/chips.prt';

PART_NAME
 R1483 'Q_RES_0402LF-10K,1%,1/16W,EMPTA':;

SECTION_NUMBER 1
 '@S9S_MB_2U_LIB.S9S_MB_2U(SCH_1):PAGE197_I265@PURE_QUANTA.Q_RES(CHIPS)':
 C_PATH='@s9s_mb_2u_lib.s9s_mb_2u(sch_1):page197_i265@pure_quanta.q_res(chips)',
 P_PATH='@s9s_mb_2u_lib.s9s_mb_2u(sch_1):page208_i265@pure_quanta.q_res(chips)',
 PATH='I265',
 DRAWING='@S9S_MB_2U_LIB.S9S_MB_2U(SCH_1):PAGE197',
 PHYS_PAGE='208',
 XY='(-3150,10725)',
 ROT='0',
 VER='2',
 PACK_TYPE='0402LF',
 CDS_LIB='pure_quanta',
 CDS_PART_NAME='Q_RES_0402LF-10K,1%,1/16W,EMPTA',
 WATTAGE='1/16W',
 TOLERANCE='1%',
 MATERIAL='EMPTY',
 VALUE='10K',
 PRIM_FILE='./archive_libs/logical/q_res/chips/chips.prt';

PART_NAME
 R1484 'Q_RES_0402LF-1K,1%,1/16W,EMPTYA':;

SECTION_NUMBER 1
 '@S9S_MB_2U_LIB.S9S_MB_2U(SCH_1):PAGE197_I268@PURE_QUANTA.Q_RES(CHIPS)':
 C_PATH='@s9s_mb_2u_lib.s9s_mb_2u(sch_1):page197_i268@pure_quanta.q_res(chips)',
 P_PATH='@s9s_mb_2u_lib.s9s_mb_2u(sch_1):page208_i268@pure_quanta.q_res(chips)',
 PATH='I268',
 DRAWING='@S9S_MB_2U_LIB.S9S_MB_2U(SCH_1):PAGE197',
 PHYS_PAGE='208',
 XY='(-3150,9800)',
 ROT='0',
 VER='2',
 PACK_TYPE='0402LF',
 CDS_LIB='pure_quanta',
 CDS_PART_NAME='Q_RES_0402LF-1K,1%,1/16W,EMPTYA',
 WATTAGE='1/16W',
 TOLERANCE='1%',
 MATERIAL='EMPTY',
 VALUE='1K',
 PRIM_FILE='./archive_libs/logical/q_res/chips/chips.prt';

PART_NAME
 R1485 'Q_RES_0402LF-200,1%,1/16W,EMPTA':;

SECTION_NUMBER 1
 '@S9S_MB_2U_LIB.S9S_MB_2U(SCH_1):PAGE174_I75@PURE_QUANTA.Q_RES(CHIPS)':
 C_PATH='@s9s_mb_2u_lib.s9s_mb_2u(sch_1):page174_i75@pure_quanta.q_res(chips)',
 P_PATH='@s9s_mb_2u_lib.s9s_mb_2u(sch_1):page182_i75@pure_quanta.q_res(chips)',
 PATH='I75',
 DRAWING='@S9S_MB_2U_LIB.S9S_MB_2U(SCH_1):PAGE174',
 PHYS_PAGE='182',
 XY='(5125,600)',
 ROT='0',
 VER='2',
 PACK_TYPE='0402LF',
 CDS_LIB='pure_quanta',
 CDS_PART_NAME='Q_RES_0402LF-200,1%,1/16W,EMPTA',
 WATTAGE='1/16W',
 TOLERANCE='1%',
 MATERIAL='EMPTY',
 VALUE='200',
 PRIM_FILE='./archive_libs/logical/q_res/chips/chips.prt';

PART_NAME
 R1486 'Q_RES_0402LF-200,1%,1/16W,EMPTA':;

SECTION_NUMBER 1
 '@S9S_MB_2U_LIB.S9S_MB_2U(SCH_1):PAGE174_I74@PURE_QUANTA.Q_RES(CHIPS)':
 C_PATH='@s9s_mb_2u_lib.s9s_mb_2u(sch_1):page174_i74@pure_quanta.q_res(chips)',
 P_PATH='@s9s_mb_2u_lib.s9s_mb_2u(sch_1):page182_i74@pure_quanta.q_res(chips)',
 PATH='I74',
 DRAWING='@S9S_MB_2U_LIB.S9S_MB_2U(SCH_1):PAGE174',
 PHYS_PAGE='182',
 XY='(5400,600)',
 ROT='0',
 VER='2',
 PACK_TYPE='0402LF',
 CDS_LIB='pure_quanta',
 CDS_PART_NAME='Q_RES_0402LF-200,1%,1/16W,EMPTA',
 WATTAGE='1/16W',
 TOLERANCE='1%',
 MATERIAL='EMPTY',
 VALUE='200',
 PRIM_FILE='./archive_libs/logical/q_res/chips/chips.prt';

PART_NAME
 R1487 'Q_RES_0402LF-100,1%,1/16W,CHIPA':;

SECTION_NUMBER 1
 '@S9S_MB_2U_LIB.S9S_MB_2U(SCH_1):PAGE175_I125@PURE_QUANTA.Q_RES(CHIPS)':
 C_PATH='@s9s_mb_2u_lib.s9s_mb_2u(sch_1):page175_i125@pure_quanta.q_res(chips)',
 P_PATH='@s9s_mb_2u_lib.s9s_mb_2u(sch_1):page183_i125@pure_quanta.q_res(chips)',
 PATH='I125',
 DRAWING='@S9S_MB_2U_LIB.S9S_MB_2U(SCH_1):PAGE175',
 PHYS_PAGE='183',
 XY='(2950,300)',
 ROT='0',
 VER='1',
 PACK_TYPE='0402LF',
 CDS_LIB='pure_quanta',
 CDS_PART_NAME='Q_RES_0402LF-100,1%,1/16W,CHIPA',
 WATTAGE='1/16W',
 TOLERANCE='1%',
 MATERIAL='CHIP',
 VALUE='100',
 PRIM_FILE='./archive_libs/logical/q_res/chips/chips.prt';

PART_NAME
 R1492 'Q_RES_0402LF-10K,1%,1/16W,CHIPA':;

SECTION_NUMBER 1
 '@S9S_MB_2U_LIB.S9S_MB_2U(SCH_1):PAGE209_I35@PURE_QUANTA.Q_RES(CHIPS)':
 C_PATH='@s9s_mb_2u_lib.s9s_mb_2u(sch_1):page209_i35@pure_quanta.q_res(chips)',
 P_PATH='@s9s_mb_2u_lib.s9s_mb_2u(sch_1):page220_i35@pure_quanta.q_res(chips)',
 PATH='I35',
 DRAWING='@S9S_MB_2U_LIB.S9S_MB_2U(SCH_1):PAGE209',
 PHYS_PAGE='220',
 XY='(1775,-1075)',
 ROT='0',
 VER='1',
 PACK_TYPE='0402LF',
 CDS_LIB='pure_quanta',
 CDS_PART_NAME='Q_RES_0402LF-10K,1%,1/16W,CHIPA',
 WATTAGE='1/16W',
 TOLERANCE='1%',
 MATERIAL='CHIP',
 VALUE='10K',
 PRIM_FILE='./archive_libs/logical/q_res/chips/chips.prt';

PART_NAME
 R1493 'Q_RES_0402LF-1K,1%,1/16W,CHIP,A':;

SECTION_NUMBER 1
 '@S9S_MB_2U_LIB.S9S_MB_2U(SCH_1):PAGE312_I191@PURE_QUANTA.Q_RES(CHIPS)':
 C_PATH='@s9s_mb_2u_lib.s9s_mb_2u(sch_1):page312_i191@pure_quanta.q_res(chips)',
 P_PATH='@s9s_mb_2u_lib.s9s_mb_2u(sch_1):page215_i191@pure_quanta.q_res(chips)',
 PATH='I191',
 DRAWING='@S9S_MB_2U_LIB.S9S_MB_2U(SCH_1):PAGE312',
 PHYS_PAGE='215',
 XY='(-6000,3875)',
 ROT='0',
 VER='2',
 PACK_TYPE='0402LF',
 CDS_LIB='pure_quanta',
 CDS_PART_NAME='Q_RES_0402LF-1K,1%,1/16W,CHIP,A',
 WATTAGE='1/16W',
 TOLERANCE='1%',
 MATERIAL='CHIP',
 VALUE='1K',
 PRIM_FILE='./archive_libs/logical/q_res/chips/chips.prt';

PART_NAME
 R1494 'Q_RES_0402LF-1K,1%,1/16W,EMPTYA':;

SECTION_NUMBER 1
 '@S9S_MB_2U_LIB.S9S_MB_2U(SCH_1):PAGE209_I21@PURE_QUANTA.Q_RES(CHIPS)':
 C_PATH='@s9s_mb_2u_lib.s9s_mb_2u(sch_1):page209_i21@pure_quanta.q_res(chips)',
 P_PATH='@s9s_mb_2u_lib.s9s_mb_2u(sch_1):page220_i21@pure_quanta.q_res(chips)',
 PATH='I21',
 DRAWING='@S9S_MB_2U_LIB.S9S_MB_2U(SCH_1):PAGE209',
 PHYS_PAGE='220',
 XY='(1775,-1825)',
 ROT='0',
 VER='1',
 PACK_TYPE='0402LF',
 CDS_LIB='pure_quanta',
 CDS_PART_NAME='Q_RES_0402LF-1K,1%,1/16W,EMPTYA',
 WATTAGE='1/16W',
 TOLERANCE='1%',
 MATERIAL='EMPTY',
 VALUE='1K',
 PRIM_FILE='./archive_libs/logical/q_res/chips/chips.prt';

PART_NAME
 R1495 'Q_RES_0402LF-10K,1%,1/16W,CHIPA':;

SECTION_NUMBER 1
 '@S9S_MB_2U_LIB.S9S_MB_2U(SCH_1):PAGE312_I190@PURE_QUANTA.Q_RES(CHIPS)':
 C_PATH='@s9s_mb_2u_lib.s9s_mb_2u(sch_1):page312_i190@pure_quanta.q_res(chips)',
 P_PATH='@s9s_mb_2u_lib.s9s_mb_2u(sch_1):page215_i190@pure_quanta.q_res(chips)',
 PATH='I190',
 DRAWING='@S9S_MB_2U_LIB.S9S_MB_2U(SCH_1):PAGE312',
 PHYS_PAGE='215',
 XY='(-6000,3325)',
 ROT='0',
 VER='2',
 PACK_TYPE='0402LF',
 CDS_LIB='pure_quanta',
 CDS_PART_NAME='Q_RES_0402LF-10K,1%,1/16W,CHIPA',
 WATTAGE='1/16W',
 TOLERANCE='1%',
 MATERIAL='CHIP',
 VALUE='10K',
 PRIM_FILE='./archive_libs/logical/q_res/chips/chips.prt';

PART_NAME
 R1496 'Q_RES_0402LF-10K,1%,1/16W,CHIPA':;

SECTION_NUMBER 1
 '@S9S_MB_2U_LIB.S9S_MB_2U(SCH_1):PAGE188_I71@PURE_QUANTA.Q_RES(CHIPS)':
 C_PATH='@s9s_mb_2u_lib.s9s_mb_2u(sch_1):page188_i71@pure_quanta.q_res(chips)',
 P_PATH='@s9s_mb_2u_lib.s9s_mb_2u(sch_1):page200_i71@pure_quanta.q_res(chips)',
 PATH='I71',
 DRAWING='@S9S_MB_2U_LIB.S9S_MB_2U(SCH_1):PAGE188',
 PHYS_PAGE='200',
 XY='(-150,-450)',
 ROT='0',
 VER='2',
 PACK_TYPE='0402LF',
 CDS_LIB='pure_quanta',
 CDS_PART_NAME='Q_RES_0402LF-10K,1%,1/16W,CHIPA',
 WATTAGE='1/16W',
 TOLERANCE='1%',
 MATERIAL='CHIP',
 VALUE='10K',
 PRIM_FILE='./archive_libs/logical/q_res/chips/chips.prt';

PART_NAME
 R1497 'Q_RES_0402LF-12K,1%,1/16W,EMPTA':;

SECTION_NUMBER 1
 '@S9S_MB_2U_LIB.S9S_MB_2U(SCH_1):PAGE188_I70@PURE_QUANTA.Q_RES(CHIPS)':
 C_PATH='@s9s_mb_2u_lib.s9s_mb_2u(sch_1):page188_i70@pure_quanta.q_res(chips)',
 P_PATH='@s9s_mb_2u_lib.s9s_mb_2u(sch_1):page200_i70@pure_quanta.q_res(chips)',
 PATH='I70',
 DRAWING='@S9S_MB_2U_LIB.S9S_MB_2U(SCH_1):PAGE188',
 PHYS_PAGE='200',
 XY='(-150,-975)',
 ROT='0',
 VER='2',
 PACK_TYPE='0402LF',
 CDS_LIB='pure_quanta',
 CDS_PART_NAME='Q_RES_0402LF-12K,1%,1/16W,EMPTA',
 WATTAGE='1/16W',
 TOLERANCE='1%',
 MATERIAL='EMPTY',
 VALUE='12K',
 PRIM_FILE='./archive_libs/logical/q_res/chips/chips.prt';

PART_NAME
 R1498 'Q_RES_0402LF-1K,1%,1/16W,EMPTYA':;

SECTION_NUMBER 1
 '@S9S_MB_2U_LIB.S9S_MB_2U(SCH_1):PAGE188_I76@PURE_QUANTA.Q_RES(CHIPS)':
 C_PATH='@s9s_mb_2u_lib.s9s_mb_2u(sch_1):page188_i76@pure_quanta.q_res(chips)',
 P_PATH='@s9s_mb_2u_lib.s9s_mb_2u(sch_1):page200_i76@pure_quanta.q_res(chips)',
 PATH='I76',
 DRAWING='@S9S_MB_2U_LIB.S9S_MB_2U(SCH_1):PAGE188',
 PHYS_PAGE='200',
 XY='(3075,-450)',
 ROT='0',
 VER='2',
 PACK_TYPE='0402LF',
 CDS_LIB='pure_quanta',
 CDS_PART_NAME='Q_RES_0402LF-1K,1%,1/16W,EMPTYA',
 WATTAGE='1/16W',
 TOLERANCE='1%',
 MATERIAL='EMPTY',
 VALUE='1K',
 PRIM_FILE='./archive_libs/logical/q_res/chips/chips.prt';

PART_NAME
 R1499 'Q_RES_0402LF-1K,1%,1/16W,CHIP,A':;

SECTION_NUMBER 1
 '@S9S_MB_2U_LIB.S9S_MB_2U(SCH_1):PAGE188_I77@PURE_QUANTA.Q_RES(CHIPS)':
 C_PATH='@s9s_mb_2u_lib.s9s_mb_2u(sch_1):page188_i77@pure_quanta.q_res(chips)',
 P_PATH='@s9s_mb_2u_lib.s9s_mb_2u(sch_1):page200_i77@pure_quanta.q_res(chips)',
 PATH='I77',
 DRAWING='@S9S_MB_2U_LIB.S9S_MB_2U(SCH_1):PAGE188',
 PHYS_PAGE='200',
 XY='(3075,-975)',
 ROT='0',
 VER='2',
 PACK_TYPE='0402LF',
 CDS_LIB='pure_quanta',
 CDS_PART_NAME='Q_RES_0402LF-1K,1%,1/16W,CHIP,A',
 WATTAGE='1/16W',
 TOLERANCE='1%',
 MATERIAL='CHIP',
 VALUE='1K',
 PRIM_FILE='./archive_libs/logical/q_res/chips/chips.prt';

PART_NAME
 R1500 'Q_RES_0402LF-4.75K,1%,1/16W,CHA':;

SECTION_NUMBER 1
 '@S9S_MB_2U_LIB.S9S_MB_2U(SCH_1):PAGE197_I271@PURE_QUANTA.Q_RES(CHIPS)':
 C_PATH='@s9s_mb_2u_lib.s9s_mb_2u(sch_1):page197_i271@pure_quanta.q_res(chips)',
 P_PATH='@s9s_mb_2u_lib.s9s_mb_2u(sch_1):page208_i271@pure_quanta.q_res(chips)',
 PATH='I271',
 DRAWING='@S9S_MB_2U_LIB.S9S_MB_2U(SCH_1):PAGE197',
 PHYS_PAGE='208',
 XY='(-3875,9800)',
 ROT='0',
 VER='2',
 PACK_TYPE='0402LF',
 CDS_LIB='pure_quanta',
 CDS_PART_NAME='Q_RES_0402LF-4.75K,1%,1/16W,CHA',
 WATTAGE='1/16W',
 TOLERANCE='1%',
 MATERIAL='CHIP',
 VALUE='4.75K',
 PRIM_FILE='./archive_libs/logical/q_res/chips/chips.prt';

PART_NAME
 R1502 'Q_RES_0402LF-4.75K,1%,1/16W,CHA':;

SECTION_NUMBER 1
 '@S9S_MB_2U_LIB.S9S_MB_2U(SCH_1):PAGE197_I270@PURE_QUANTA.Q_RES(CHIPS)':
 C_PATH='@s9s_mb_2u_lib.s9s_mb_2u(sch_1):page197_i270@pure_quanta.q_res(chips)',
 P_PATH='@s9s_mb_2u_lib.s9s_mb_2u(sch_1):page208_i270@pure_quanta.q_res(chips)',
 PATH='I270',
 DRAWING='@S9S_MB_2U_LIB.S9S_MB_2U(SCH_1):PAGE197',
 PHYS_PAGE='208',
 XY='(-3625,9800)',
 ROT='0',
 VER='2',
 PACK_TYPE='0402LF',
 CDS_LIB='pure_quanta',
 CDS_PART_NAME='Q_RES_0402LF-4.75K,1%,1/16W,CHA',
 WATTAGE='1/16W',
 TOLERANCE='1%',
 MATERIAL='CHIP',
 VALUE='4.75K',
 PRIM_FILE='./archive_libs/logical/q_res/chips/chips.prt';

PART_NAME
 R1504 'Q_RES_0402LF-33.2,1%,1/16W,CHIA':;

SECTION_NUMBER 1
 '@S9S_MB_2U_LIB.S9S_MB_2U(SCH_1):PAGE152_I10@PURE_QUANTA.Q_RES(CHIPS)':
 C_PATH='@s9s_mb_2u_lib.s9s_mb_2u(sch_1):page152_i10@pure_quanta.q_res(chips)',
 P_PATH='@s9s_mb_2u_lib.s9s_mb_2u(sch_1):page155_i10@pure_quanta.q_res(chips)',
 PATH='I10',
 DRAWING='@S9S_MB_2U_LIB.S9S_MB_2U(SCH_1):PAGE152',
 PHYS_PAGE='155',
 XY='(-6250,6775)',
 ROT='0',
 VER='1',
 PACK_TYPE='0402LF',
 CDS_LIB='pure_quanta',
 CDS_PART_NAME='Q_RES_0402LF-33.2,1%,1/16W,CHIA',
 WATTAGE='1/16W',
 TOLERANCE='1%',
 MATERIAL='CHIP',
 VALUE='33.2',
 PRIM_FILE='./archive_libs/logical/q_res/chips/chips.prt';

PART_NAME
 R1505 'Q_RES_0402LF-33.2,1%,1/16W,CHIA':;

SECTION_NUMBER 1
 '@S9S_MB_2U_LIB.S9S_MB_2U(SCH_1):PAGE152_I13@PURE_QUANTA.Q_RES(CHIPS)':
 C_PATH='@s9s_mb_2u_lib.s9s_mb_2u(sch_1):page152_i13@pure_quanta.q_res(chips)',
 P_PATH='@s9s_mb_2u_lib.s9s_mb_2u(sch_1):page155_i13@pure_quanta.q_res(chips)',
 PATH='I13',
 DRAWING='@S9S_MB_2U_LIB.S9S_MB_2U(SCH_1):PAGE152',
 PHYS_PAGE='155',
 XY='(-6250,6550)',
 ROT='0',
 VER='1',
 PACK_TYPE='0402LF',
 CDS_LIB='pure_quanta',
 CDS_PART_NAME='Q_RES_0402LF-33.2,1%,1/16W,CHIA',
 WATTAGE='1/16W',
 TOLERANCE='1%',
 MATERIAL='CHIP',
 VALUE='33.2',
 PRIM_FILE='./archive_libs/logical/q_res/chips/chips.prt';

PART_NAME
 R1514 'Q_RES_0402LF-33.2,1%,1/16W,CHIA':;

SECTION_NUMBER 1
 '@S9S_MB_2U_LIB.S9S_MB_2U(SCH_1):PAGE212_I105@PURE_QUANTA.Q_RES(CHIPS)':
 C_PATH='@s9s_mb_2u_lib.s9s_mb_2u(sch_1):page212_i105@pure_quanta.q_res(chips)',
 P_PATH='@s9s_mb_2u_lib.s9s_mb_2u(sch_1):page223_i105@pure_quanta.q_res(chips)',
 PATH='I105',
 DRAWING='@S9S_MB_2U_LIB.S9S_MB_2U(SCH_1):PAGE212',
 PHYS_PAGE='223',
 XY='(1900,2875)',
 ROT='0',
 VER='1',
 PACK_TYPE='0402LF',
 CDS_LIB='pure_quanta',
 CDS_PART_NAME='Q_RES_0402LF-33.2,1%,1/16W,CHIA',
 WATTAGE='1/16W',
 TOLERANCE='1%',
 MATERIAL='CHIP',
 VALUE='33.2',
 PRIM_FILE='./archive_libs/logical/q_res/chips/chips.prt';

PART_NAME
 R1520 'Q_RES_0402LF-33.2,1%,1/16W,CHIA':;

SECTION_NUMBER 1
 '@S9S_MB_2U_LIB.S9S_MB_2U(SCH_1):PAGE212_I113@PURE_QUANTA.Q_RES(CHIPS)':
 C_PATH='@s9s_mb_2u_lib.s9s_mb_2u(sch_1):page212_i113@pure_quanta.q_res(chips)',
 P_PATH='@s9s_mb_2u_lib.s9s_mb_2u(sch_1):page223_i113@pure_quanta.q_res(chips)',
 PATH='I113',
 DRAWING='@S9S_MB_2U_LIB.S9S_MB_2U(SCH_1):PAGE212',
 PHYS_PAGE='223',
 XY='(1900,925)',
 ROT='0',
 VER='1',
 PACK_TYPE='0402LF',
 CDS_LIB='pure_quanta',
 CDS_PART_NAME='Q_RES_0402LF-33.2,1%,1/16W,CHIA',
 WATTAGE='1/16W',
 TOLERANCE='1%',
 MATERIAL='CHIP',
 VALUE='33.2',
 PRIM_FILE='./archive_libs/logical/q_res/chips/chips.prt';

PART_NAME
 R1525 'Q_RES_0402LF-0,5%,1/16W,CHIP,CA':;

SECTION_NUMBER 1
 '@S9S_MB_2U_LIB.S9S_MB_2U(SCH_1):PAGE228_I40@PURE_QUANTA.Q_RES(CHIPS)':
 C_PATH='@s9s_mb_2u_lib.s9s_mb_2u(sch_1):page228_i40@pure_quanta.q_res(chips)',
 P_PATH='@s9s_mb_2u_lib.s9s_mb_2u(sch_1):page241_i40@pure_quanta.q_res(chips)',
 PATH='I40',
 DRAWING='@S9S_MB_2U_LIB.S9S_MB_2U(SCH_1):PAGE228',
 PHYS_PAGE='241',
 XY='(-350,5500)',
 ROT='0',
 VER='1',
 PACK_TYPE='0402LF',
 CDS_LIB='pure_quanta',
 CDS_PART_NAME='Q_RES_0402LF-0,5%,1/16W,CHIP,CA',
 WATTAGE='1/16W',
 TOLERANCE='5%',
 MATERIAL='CHIP',
 VALUE='0',
 PRIM_FILE='./archive_libs/logical/q_res/chips/chips.prt';

PART_NAME
 R1526 'Q_RES_0402LF-33.2,1%,1/16W,CHIA':;

SECTION_NUMBER 1
 '@S9S_MB_2U_LIB.S9S_MB_2U(SCH_1):PAGE228_I41@PURE_QUANTA.Q_RES(CHIPS)':
 C_PATH='@s9s_mb_2u_lib.s9s_mb_2u(sch_1):page228_i41@pure_quanta.q_res(chips)',
 P_PATH='@s9s_mb_2u_lib.s9s_mb_2u(sch_1):page241_i41@pure_quanta.q_res(chips)',
 PATH='I41',
 DRAWING='@S9S_MB_2U_LIB.S9S_MB_2U(SCH_1):PAGE228',
 PHYS_PAGE='241',
 XY='(-350,5450)',
 ROT='0',
 VER='1',
 PACK_TYPE='0402LF',
 CDS_LIB='pure_quanta',
 CDS_PART_NAME='Q_RES_0402LF-33.2,1%,1/16W,CHIA',
 WATTAGE='1/16W',
 TOLERANCE='1%',
 MATERIAL='CHIP',
 VALUE='33.2',
 PRIM_FILE='./archive_libs/logical/q_res/chips/chips.prt';

PART_NAME
 R1527 'Q_RES_0402LF-1K,1%,1/16W,CHIP,A':;

SECTION_NUMBER 1
 '@S9S_MB_2U_LIB.S9S_MB_2U(SCH_1):PAGE197_I269@PURE_QUANTA.Q_RES(CHIPS)':
 C_PATH='@s9s_mb_2u_lib.s9s_mb_2u(sch_1):page197_i269@pure_quanta.q_res(chips)',
 P_PATH='@s9s_mb_2u_lib.s9s_mb_2u(sch_1):page208_i269@pure_quanta.q_res(chips)',
 PATH='I269',
 DRAWING='@S9S_MB_2U_LIB.S9S_MB_2U(SCH_1):PAGE197',
 PHYS_PAGE='208',
 XY='(-3375,9800)',
 ROT='0',
 VER='2',
 PACK_TYPE='0402LF',
 CDS_LIB='pure_quanta',
 CDS_PART_NAME='Q_RES_0402LF-1K,1%,1/16W,CHIP,A',
 WATTAGE='1/16W',
 TOLERANCE='1%',
 MATERIAL='CHIP',
 VALUE='1K',
 PRIM_FILE='./archive_libs/logical/q_res/chips/chips.prt';

PART_NAME
 R1541 'Q_RES_0402LF-100K,1%,1/16W,CHIA':;

SECTION_NUMBER 1
 '@S9S_MB_2U_LIB.S9S_MB_2U(SCH_1):PAGE212_I92@PURE_QUANTA.Q_RES(CHIPS)':
 C_PATH='@s9s_mb_2u_lib.s9s_mb_2u(sch_1):page212_i92@pure_quanta.q_res(chips)',
 P_PATH='@s9s_mb_2u_lib.s9s_mb_2u(sch_1):page223_i92@pure_quanta.q_res(chips)',
 PATH='I92',
 DRAWING='@S9S_MB_2U_LIB.S9S_MB_2U(SCH_1):PAGE212',
 PHYS_PAGE='223',
 XY='(-3775,2750)',
 ROT='0',
 VER='1',
 PACK_TYPE='0402LF',
 CDS_LIB='pure_quanta',
 CDS_PART_NAME='Q_RES_0402LF-100K,1%,1/16W,CHIA',
 WATTAGE='1/16W',
 TOLERANCE='1%',
 MATERIAL='CHIP',
 VALUE='100K',
 PRIM_FILE='./archive_libs/logical/q_res/chips/chips.prt';

PART_NAME
 R1543 'Q_RES_0402LF-0,5%,1/16W,CHIP,CA':;

SECTION_NUMBER 1
 '@S9S_MB_2U_LIB.S9S_MB_2U(SCH_1):PAGE195_I534@PURE_QUANTA.Q_RES(CHIPS)':
 C_PATH='@s9s_mb_2u_lib.s9s_mb_2u(sch_1):page195_i534@pure_quanta.q_res(chips)',
 P_PATH='@s9s_mb_2u_lib.s9s_mb_2u(sch_1):page206_i534@pure_quanta.q_res(chips)',
 PATH='I534',
 DRAWING='@S9S_MB_2U_LIB.S9S_MB_2U(SCH_1):PAGE195',
 PHYS_PAGE='206',
 XY='(-5300,2050)',
 ROT='0',
 VER='1',
 PACK_TYPE='0402LF',
 LOCATION='R1543',
 CDS_LIB='pure_quanta',
 CDS_PART_NAME='Q_RES_0402LF-0,5%,1/16W,CHIP,CA',
 WATTAGE='1/16W',
 TOLERANCE='5%',
 MATERIAL='CHIP',
 VALUE='0',
 PRIM_FILE='./archive_libs/logical/q_res/chips/chips.prt';

PART_NAME
 R1545 'Q_RES_0402LF-2K,1%,1/16W,CHIP,A':;

SECTION_NUMBER 1
 '@S9S_MB_2U_LIB.S9S_MB_2U(SCH_1):PAGE175_I137@PURE_QUANTA.Q_RES(CHIPS)':
 C_PATH='@s9s_mb_2u_lib.s9s_mb_2u(sch_1):page175_i137@pure_quanta.q_res(chips)',
 P_PATH='@s9s_mb_2u_lib.s9s_mb_2u(sch_1):page183_i137@pure_quanta.q_res(chips)',
 PATH='I137',
 DRAWING='@S9S_MB_2U_LIB.S9S_MB_2U(SCH_1):PAGE175',
 PHYS_PAGE='183',
 XY='(3475,-625)',
 ROT='0',
 VER='1',
 PACK_TYPE='0402LF',
 CDS_LIB='pure_quanta',
 CDS_PART_NAME='Q_RES_0402LF-2K,1%,1/16W,CHIP,A',
 WATTAGE='1/16W',
 TOLERANCE='1%',
 MATERIAL='CHIP',
 VALUE='2K',
 PRIM_FILE='./archive_libs/logical/q_res/chips/chips.prt';

PART_NAME
 R1546 'Q_RES_0402LF-2K,1%,1/16W,CHIP,A':;

SECTION_NUMBER 1
 '@S9S_MB_2U_LIB.S9S_MB_2U(SCH_1):PAGE175_I138@PURE_QUANTA.Q_RES(CHIPS)':
 C_PATH='@s9s_mb_2u_lib.s9s_mb_2u(sch_1):page175_i138@pure_quanta.q_res(chips)',
 P_PATH='@s9s_mb_2u_lib.s9s_mb_2u(sch_1):page183_i138@pure_quanta.q_res(chips)',
 PATH='I138',
 DRAWING='@S9S_MB_2U_LIB.S9S_MB_2U(SCH_1):PAGE175',
 PHYS_PAGE='183',
 XY='(3475,-675)',
 ROT='0',
 VER='1',
 PACK_TYPE='0402LF',
 CDS_LIB='pure_quanta',
 CDS_PART_NAME='Q_RES_0402LF-2K,1%,1/16W,CHIP,A',
 WATTAGE='1/16W',
 TOLERANCE='1%',
 MATERIAL='CHIP',
 VALUE='2K',
 PRIM_FILE='./archive_libs/logical/q_res/chips/chips.prt';

PART_NAME
 R1547 'Q_RES_0402LF-0,5%,1/16W,CHIP,CA':;

SECTION_NUMBER 1
 '@S9S_MB_2U_LIB.S9S_MB_2U(SCH_1):PAGE314_I139@PURE_QUANTA.Q_RES(CHIPS)':
 C_PATH='@s9s_mb_2u_lib.s9s_mb_2u(sch_1):page314_i139@pure_quanta.q_res(chips)',
 P_PATH='@s9s_mb_2u_lib.s9s_mb_2u(sch_1):page213_i139@pure_quanta.q_res(chips)',
 PATH='I139',
 DRAWING='@S9S_MB_2U_LIB.S9S_MB_2U(SCH_1):PAGE314',
 PHYS_PAGE='213',
 XY='(2725,700)',
 ROT='0',
 VER='1',
 PACK_TYPE='0402LF',
 CDS_LIB='pure_quanta',
 CDS_PART_NAME='Q_RES_0402LF-0,5%,1/16W,CHIP,CA',
 WATTAGE='1/16W',
 TOLERANCE='5%',
 MATERIAL='CHIP',
 VALUE='0',
 PRIM_FILE='./archive_libs/logical/q_res/chips/chips.prt';

PART_NAME
 R1551 'Q_RES_0402LF-4.7K,1%,1/16W,EMPA':;

SECTION_NUMBER 1
 '@S9S_MB_2U_LIB.S9S_MB_2U(SCH_1):PAGE314_I179@PURE_QUANTA.Q_RES(CHIPS)':
 C_PATH='@s9s_mb_2u_lib.s9s_mb_2u(sch_1):page314_i179@pure_quanta.q_res(chips)',
 P_PATH='@s9s_mb_2u_lib.s9s_mb_2u(sch_1):page213_i179@pure_quanta.q_res(chips)',
 PATH='I179',
 DRAWING='@S9S_MB_2U_LIB.S9S_MB_2U(SCH_1):PAGE314',
 PHYS_PAGE='213',
 XY='(2825,4150)',
 ROT='0',
 VER='2',
 PACK_TYPE='0402LF',
 CDS_LIB='pure_quanta',
 CDS_PART_NAME='Q_RES_0402LF-4.7K,1%,1/16W,EMPA',
 WATTAGE='1/16W',
 TOLERANCE='1%',
 MATERIAL='EMPTY',
 VALUE='4.7K',
 PRIM_FILE='./archive_libs/logical/q_res/chips/chips.prt';

PART_NAME
 R1554 'Q_RES_0402LF-10K,1%,1/16W,CHIPA':;

SECTION_NUMBER 1
 '@S9S_MB_2U_LIB.S9S_MB_2U(SCH_1):PAGE192_I62@PURE_QUANTA.Q_RES(CHIPS)':
 C_PATH='@s9s_mb_2u_lib.s9s_mb_2u(sch_1):page192_i62@pure_quanta.q_res(chips)',
 P_PATH='@s9s_mb_2u_lib.s9s_mb_2u(sch_1):page204_i62@pure_quanta.q_res(chips)',
 PATH='I62',
 DRAWING='@S9S_MB_2U_LIB.S9S_MB_2U(SCH_1):PAGE192',
 PHYS_PAGE='204',
 XY='(-4950,1050)',
 ROT='0',
 VER='1',
 PACK_TYPE='0402LF',
 CDS_LIB='pure_quanta',
 CDS_PART_NAME='Q_RES_0402LF-10K,1%,1/16W,CHIPA',
 WATTAGE='1/16W',
 TOLERANCE='1%',
 MATERIAL='CHIP',
 VALUE='10K',
 PRIM_FILE='./archive_libs/logical/q_res/chips/chips.prt';

PART_NAME
 R1558 'Q_RES_0402LF-10K,1%,1/16W,EMPTA':;

SECTION_NUMBER 1
 '@S9S_MB_2U_LIB.S9S_MB_2U(SCH_1):PAGE209_I15@PURE_QUANTA.Q_RES(CHIPS)':
 C_PATH='@s9s_mb_2u_lib.s9s_mb_2u(sch_1):page209_i15@pure_quanta.q_res(chips)',
 P_PATH='@s9s_mb_2u_lib.s9s_mb_2u(sch_1):page220_i15@pure_quanta.q_res(chips)',
 PATH='I15',
 DRAWING='@S9S_MB_2U_LIB.S9S_MB_2U(SCH_1):PAGE209',
 PHYS_PAGE='220',
 XY='(-1850,-150)',
 ROT='0',
 VER='1',
 PACK_TYPE='0402LF',
 CDS_LIB='pure_quanta',
 CDS_PART_NAME='Q_RES_0402LF-10K,1%,1/16W,EMPTA',
 WATTAGE='1/16W',
 TOLERANCE='1%',
 MATERIAL='EMPTY',
 VALUE='10K',
 PRIM_FILE='./archive_libs/logical/q_res/chips/chips.prt';

PART_NAME
 R1571 'Q_RES_0402LF-100K,1%,1/16W,CHIA':;

SECTION_NUMBER 1
 '@S9S_MB_2U_LIB.S9S_MB_2U(SCH_1):PAGE245_I72@PURE_QUANTA.Q_RES(CHIPS)':
 C_PATH='@s9s_mb_2u_lib.s9s_mb_2u(sch_1):page245_i72@pure_quanta.q_res(chips)',
 P_PATH='@s9s_mb_2u_lib.s9s_mb_2u(sch_1):page259_i72@pure_quanta.q_res(chips)',
 PATH='I72',
 DRAWING='@S9S_MB_2U_LIB.S9S_MB_2U(SCH_1):PAGE245',
 PHYS_PAGE='259',
 XY='(-3275,-1025)',
 ROT='0',
 VER='2',
 PACK_TYPE='0402LF',
 LOCATION='R1571',
 CDS_LIB='pure_quanta',
 CDS_PART_NAME='Q_RES_0402LF-100K,1%,1/16W,CHIA',
 WATTAGE='1/16W',
 TOLERANCE='1%',
 MATERIAL='CHIP',
 VALUE='100K',
 PRIM_FILE='./archive_libs/logical/q_res/chips/chips.prt';

PART_NAME
 R1581 'Q_RES_0402LF-2K,1%,1/16W,CHIP,A':;

SECTION_NUMBER 1
 '@S9S_MB_2U_LIB.S9S_MB_2U(SCH_1):PAGE175_I142@PURE_QUANTA.Q_RES(CHIPS)':
 C_PATH='@s9s_mb_2u_lib.s9s_mb_2u(sch_1):page175_i142@pure_quanta.q_res(chips)',
 P_PATH='@s9s_mb_2u_lib.s9s_mb_2u(sch_1):page183_i142@pure_quanta.q_res(chips)',
 PATH='I142',
 DRAWING='@S9S_MB_2U_LIB.S9S_MB_2U(SCH_1):PAGE175',
 PHYS_PAGE='183',
 XY='(3475,-1075)',
 ROT='0',
 VER='1',
 PACK_TYPE='0402LF',
 CDS_LIB='pure_quanta',
 CDS_PART_NAME='Q_RES_0402LF-2K,1%,1/16W,CHIP,A',
 WATTAGE='1/16W',
 TOLERANCE='1%',
 MATERIAL='CHIP',
 VALUE='2K',
 PRIM_FILE='./archive_libs/logical/q_res/chips/chips.prt';

PART_NAME
 R1582 'Q_RES_0402LF-2K,1%,1/16W,CHIP,A':;

SECTION_NUMBER 1
 '@S9S_MB_2U_LIB.S9S_MB_2U(SCH_1):PAGE175_I141@PURE_QUANTA.Q_RES(CHIPS)':
 C_PATH='@s9s_mb_2u_lib.s9s_mb_2u(sch_1):page175_i141@pure_quanta.q_res(chips)',
 P_PATH='@s9s_mb_2u_lib.s9s_mb_2u(sch_1):page183_i141@pure_quanta.q_res(chips)',
 PATH='I141',
 DRAWING='@S9S_MB_2U_LIB.S9S_MB_2U(SCH_1):PAGE175',
 PHYS_PAGE='183',
 XY='(3475,-1125)',
 ROT='0',
 VER='1',
 PACK_TYPE='0402LF',
 CDS_LIB='pure_quanta',
 CDS_PART_NAME='Q_RES_0402LF-2K,1%,1/16W,CHIP,A',
 WATTAGE='1/16W',
 TOLERANCE='1%',
 MATERIAL='CHIP',
 VALUE='2K',
 PRIM_FILE='./archive_libs/logical/q_res/chips/chips.prt';

PART_NAME
 R1583 'Q_RES_0402LF-10K,1%,1/16W,CHIPA':;

SECTION_NUMBER 1
 '@S9S_MB_2U_LIB.S9S_MB_2U(SCH_1):PAGE175_I144@PURE_QUANTA.Q_RES(CHIPS)':
 C_PATH='@s9s_mb_2u_lib.s9s_mb_2u(sch_1):page175_i144@pure_quanta.q_res(chips)',
 P_PATH='@s9s_mb_2u_lib.s9s_mb_2u(sch_1):page183_i144@pure_quanta.q_res(chips)',
 PATH='I144',
 DRAWING='@S9S_MB_2U_LIB.S9S_MB_2U(SCH_1):PAGE175',
 PHYS_PAGE='183',
 XY='(3475,-1175)',
 ROT='0',
 VER='1',
 PACK_TYPE='0402LF',
 CDS_LIB='pure_quanta',
 CDS_PART_NAME='Q_RES_0402LF-10K,1%,1/16W,CHIPA',
 WATTAGE='1/16W',
 TOLERANCE='1%',
 MATERIAL='CHIP',
 VALUE='10K',
 PRIM_FILE='./archive_libs/logical/q_res/chips/chips.prt';

PART_NAME
 R1592 'Q_RES_0402LF-10K,1%,1/16W,CHIPA':;

SECTION_NUMBER 1
 '@S9S_MB_2U_LIB.S9S_MB_2U(SCH_1):PAGE152_I37@PURE_QUANTA.Q_RES(CHIPS)':
 C_PATH='@s9s_mb_2u_lib.s9s_mb_2u(sch_1):page152_i37@pure_quanta.q_res(chips)',
 P_PATH='@s9s_mb_2u_lib.s9s_mb_2u(sch_1):page155_i37@pure_quanta.q_res(chips)',
 PATH='I37',
 DRAWING='@S9S_MB_2U_LIB.S9S_MB_2U(SCH_1):PAGE152',
 PHYS_PAGE='155',
 XY='(-9575,4475)',
 ROT='0',
 VER='2',
 PACK_TYPE='0402LF',
 CDS_LIB='pure_quanta',
 CDS_PART_NAME='Q_RES_0402LF-10K,1%,1/16W,CHIPA',
 WATTAGE='1/16W',
 TOLERANCE='1%',
 MATERIAL='CHIP',
 VALUE='10K',
 PRIM_FILE='./archive_libs/logical/q_res/chips/chips.prt';

PART_NAME
 R1593 'Q_RES_0402LF-4.7K,1%,1/16W,CHIA':;

SECTION_NUMBER 1
 '@S9S_MB_2U_LIB.S9S_MB_2U(SCH_1):PAGE152_I42@PURE_QUANTA.Q_RES(CHIPS)':
 C_PATH='@s9s_mb_2u_lib.s9s_mb_2u(sch_1):page152_i42@pure_quanta.q_res(chips)',
 P_PATH='@s9s_mb_2u_lib.s9s_mb_2u(sch_1):page155_i42@pure_quanta.q_res(chips)',
 PATH='I42',
 DRAWING='@S9S_MB_2U_LIB.S9S_MB_2U(SCH_1):PAGE152',
 PHYS_PAGE='155',
 XY='(-6050,5950)',
 ROT='0',
 VER='2',
 PACK_TYPE='0402LF',
 CDS_LIB='pure_quanta',
 CDS_PART_NAME='Q_RES_0402LF-4.7K,1%,1/16W,CHIA',
 WATTAGE='1/16W',
 TOLERANCE='1%',
 MATERIAL='CHIP',
 VALUE='4.7K',
 PRIM_FILE='./archive_libs/logical/q_res/chips/chips.prt';

PART_NAME
 R1594 'Q_RES_0402LF-33.2,1%,1/16W,CHIA':;

SECTION_NUMBER 1
 '@S9S_MB_2U_LIB.S9S_MB_2U(SCH_1):PAGE152_I26@PURE_QUANTA.Q_RES(CHIPS)':
 C_PATH='@s9s_mb_2u_lib.s9s_mb_2u(sch_1):page152_i26@pure_quanta.q_res(chips)',
 P_PATH='@s9s_mb_2u_lib.s9s_mb_2u(sch_1):page155_i26@pure_quanta.q_res(chips)',
 PATH='I26',
 DRAWING='@S9S_MB_2U_LIB.S9S_MB_2U(SCH_1):PAGE152',
 PHYS_PAGE='155',
 XY='(-6900,4100)',
 ROT='0',
 VER='1',
 PACK_TYPE='0402LF',
 CDS_LIB='pure_quanta',
 CDS_PART_NAME='Q_RES_0402LF-33.2,1%,1/16W,CHIA',
 WATTAGE='1/16W',
 TOLERANCE='1%',
 MATERIAL='CHIP',
 VALUE='33.2',
 PRIM_FILE='./archive_libs/logical/q_res/chips/chips.prt';

PART_NAME
 R1595 'Q_RES_0402LF-33.2,1%,1/16W,CHIA':;

SECTION_NUMBER 1
 '@S9S_MB_2U_LIB.S9S_MB_2U(SCH_1):PAGE152_I40@PURE_QUANTA.Q_RES(CHIPS)':
 C_PATH='@s9s_mb_2u_lib.s9s_mb_2u(sch_1):page152_i40@pure_quanta.q_res(chips)',
 P_PATH='@s9s_mb_2u_lib.s9s_mb_2u(sch_1):page155_i40@pure_quanta.q_res(chips)',
 PATH='I40',
 DRAWING='@S9S_MB_2U_LIB.S9S_MB_2U(SCH_1):PAGE152',
 PHYS_PAGE='155',
 XY='(-5500,5575)',
 ROT='0',
 VER='1',
 PACK_TYPE='0402LF',
 CDS_LIB='pure_quanta',
 CDS_PART_NAME='Q_RES_0402LF-33.2,1%,1/16W,CHIA',
 WATTAGE='1/16W',
 TOLERANCE='1%',
 MATERIAL='CHIP',
 VALUE='33.2',
 PRIM_FILE='./archive_libs/logical/q_res/chips/chips.prt';

PART_NAME
 R1600 'Q_RES_0402LF-33.2,1%,1/16W,CHIA':;

SECTION_NUMBER 1
 '@S9S_MB_2U_LIB.S9S_MB_2U(SCH_1):PAGE175_I148@PURE_QUANTA.Q_RES(CHIPS)':
 C_PATH='@s9s_mb_2u_lib.s9s_mb_2u(sch_1):page175_i148@pure_quanta.q_res(chips)',
 P_PATH='@s9s_mb_2u_lib.s9s_mb_2u(sch_1):page183_i148@pure_quanta.q_res(chips)',
 PATH='I148',
 DRAWING='@S9S_MB_2U_LIB.S9S_MB_2U(SCH_1):PAGE175',
 PHYS_PAGE='183',
 XY='(2950,1275)',
 ROT='0',
 VER='1',
 PACK_TYPE='0402LF',
 CDS_LIB='pure_quanta',
 CDS_PART_NAME='Q_RES_0402LF-33.2,1%,1/16W,CHIA',
 WATTAGE='1/16W',
 TOLERANCE='1%',
 MATERIAL='CHIP',
 VALUE='33.2',
 PRIM_FILE='./archive_libs/logical/q_res/chips/chips.prt';

PART_NAME
 R1601 'Q_RES_0402LF-10K,1%,1/16W,CHIPA':;

SECTION_NUMBER 1
 '@S9S_MB_2U_LIB.S9S_MB_2U(SCH_1):PAGE175_I151@PURE_QUANTA.Q_RES(CHIPS)':
 C_PATH='@s9s_mb_2u_lib.s9s_mb_2u(sch_1):page175_i151@pure_quanta.q_res(chips)',
 P_PATH='@s9s_mb_2u_lib.s9s_mb_2u(sch_1):page183_i151@pure_quanta.q_res(chips)',
 PATH='I151',
 DRAWING='@S9S_MB_2U_LIB.S9S_MB_2U(SCH_1):PAGE175',
 PHYS_PAGE='183',
 XY='(3475,-25)',
 ROT='0',
 VER='1',
 PACK_TYPE='0402LF',
 CDS_LIB='pure_quanta',
 CDS_PART_NAME='Q_RES_0402LF-10K,1%,1/16W,CHIPA',
 WATTAGE='1/16W',
 TOLERANCE='1%',
 MATERIAL='CHIP',
 VALUE='10K',
 PRIM_FILE='./archive_libs/logical/q_res/chips/chips.prt';

PART_NAME
 R1605 'Q_RES_0402LF-1K,1%,1/16W,CHIP,A':;

SECTION_NUMBER 1
 '@S9S_MB_2U_LIB.S9S_MB_2U(SCH_1):PAGE182_I105@PURE_QUANTA.Q_RES(CHIPS)':
 C_PATH='@s9s_mb_2u_lib.s9s_mb_2u(sch_1):page182_i105@pure_quanta.q_res(chips)',
 P_PATH='@s9s_mb_2u_lib.s9s_mb_2u(sch_1):page190_i105@pure_quanta.q_res(chips)',
 PATH='I105',
 DRAWING='@S9S_MB_2U_LIB.S9S_MB_2U(SCH_1):PAGE182',
 PHYS_PAGE='190',
 XY='(13350,2900)',
 ROT='0',
 VER='2',
 PACK_TYPE='0402LF',
 CDS_LIB='pure_quanta',
 CDS_PART_NAME='Q_RES_0402LF-1K,1%,1/16W,CHIP,A',
 WATTAGE='1/16W',
 TOLERANCE='1%',
 MATERIAL='CHIP',
 VALUE='1K',
 PRIM_FILE='./archive_libs/logical/q_res/chips/chips.prt';

PART_NAME
 R1606 'Q_RES_0402LF-33.2,1%,1/16W,CHIA':;

SECTION_NUMBER 1
 '@S9S_MB_2U_LIB.S9S_MB_2U(SCH_1):PAGE314_I109@PURE_QUANTA.Q_RES(CHIPS)':
 C_PATH='@s9s_mb_2u_lib.s9s_mb_2u(sch_1):page314_i109@pure_quanta.q_res(chips)',
 P_PATH='@s9s_mb_2u_lib.s9s_mb_2u(sch_1):page213_i109@pure_quanta.q_res(chips)',
 PATH='I109',
 DRAWING='@S9S_MB_2U_LIB.S9S_MB_2U(SCH_1):PAGE314',
 PHYS_PAGE='213',
 XY='(2725,-925)',
 ROT='0',
 VER='1',
 PACK_TYPE='0402LF',
 LOCATION='R1606',
 CDS_LIB='pure_quanta',
 CDS_PART_NAME='Q_RES_0402LF-33.2,1%,1/16W,CHIA',
 WATTAGE='1/16W',
 TOLERANCE='1%',
 MATERIAL='CHIP',
 VALUE='33.2',
 PRIM_FILE='./archive_libs/logical/q_res/chips/chips.prt';

PART_NAME
 R1607 'Q_RES_0402LF-0,5%,1/16W,EMPTY,A':;

SECTION_NUMBER 1
 '@S9S_MB_2U_LIB.S9S_MB_2U(SCH_1):PAGE246_I10@PURE_QUANTA.Q_RES(CHIPS)':
 C_PATH='@s9s_mb_2u_lib.s9s_mb_2u(sch_1):page246_i10@pure_quanta.q_res(chips)',
 P_PATH='@s9s_mb_2u_lib.s9s_mb_2u(sch_1):page260_i10@pure_quanta.q_res(chips)',
 PATH='I10',
 DRAWING='@S9S_MB_2U_LIB.S9S_MB_2U(SCH_1):PAGE246',
 BOM_COST='VR_SYSTEM ',
 PHYS_PAGE='260',
 XY='(-6275,4925)',
 ROT='0',
 VER='1',
 PACK_TYPE='0402LF',
 CDS_LIB='pure_quanta',
 CDS_PART_NAME='Q_RES_0402LF-0,5%,1/16W,EMPTY,A',
 WATTAGE='1/16W',
 TOLERANCE='5%',
 MATERIAL='EMPTY',
 VALUE='0',
 PRIM_FILE='./archive_libs/logical/q_res/chips/chips.prt';

PART_NAME
 R1640 'Q_RES_0402LF-0,5%,1/16W,CHIP,CA':;

SECTION_NUMBER 1
 '@S9S_MB_2U_LIB.S9S_MB_2U(SCH_1):PAGE246_I9@PURE_QUANTA.Q_RES(CHIPS)':
 C_PATH='@s9s_mb_2u_lib.s9s_mb_2u(sch_1):page246_i9@pure_quanta.q_res(chips)',
 P_PATH='@s9s_mb_2u_lib.s9s_mb_2u(sch_1):page260_i9@pure_quanta.q_res(chips)',
 PATH='I9',
 DRAWING='@S9S_MB_2U_LIB.S9S_MB_2U(SCH_1):PAGE246',
 BOM_COST='VR_SYSTEM ',
 PHYS_PAGE='260',
 XY='(-6275,4700)',
 ROT='0',
 VER='1',
 PACK_TYPE='0402LF',
 CDS_LIB='pure_quanta',
 CDS_PART_NAME='Q_RES_0402LF-0,5%,1/16W,CHIP,CA',
 WATTAGE='1/16W',
 TOLERANCE='5%',
 MATERIAL='CHIP',
 VALUE='0',
 PRIM_FILE='./archive_libs/logical/q_res/chips/chips.prt';

PART_NAME
 R1641 'Q_RES_0402LF-100K,1%,1/16W,CHIA':;

SECTION_NUMBER 1
 '@S9S_MB_2U_LIB.S9S_MB_2U(SCH_1):PAGE246_I14@PURE_QUANTA.Q_RES(CHIPS)':
 C_PATH='@s9s_mb_2u_lib.s9s_mb_2u(sch_1):page246_i14@pure_quanta.q_res(chips)',
 P_PATH='@s9s_mb_2u_lib.s9s_mb_2u(sch_1):page260_i14@pure_quanta.q_res(chips)',
 PATH='I14',
 DRAWING='@S9S_MB_2U_LIB.S9S_MB_2U(SCH_1):PAGE246',
 PHYS_PAGE='260',
 XY='(-5775,4650)',
 ROT='0',
 VER='2',
 PACK_TYPE='0402LF',
 CDS_LIB='pure_quanta',
 CDS_PART_NAME='Q_RES_0402LF-100K,1%,1/16W,CHIA',
 WATTAGE='1/16W',
 TOLERANCE='1%',
 MATERIAL='CHIP',
 VALUE='100K',
 PRIM_FILE='./archive_libs/logical/q_res/chips/chips.prt';

PART_NAME
 R1642 'Q_RES_0402LF-10K,1%,1/16W,CHIPA':
 REUSE_ID='3';

SECTION_NUMBER 1
 '@S9S_MB_2U_LIB.S9S_MB_2U(SCH_1):PAGE246_I22@PURE_QUANTA.Q_RES(CHIPS)':
 C_PATH='@s9s_mb_2u_lib.s9s_mb_2u(sch_1):page246_i22@pure_quanta.q_res(chips)',
 P_PATH='@s9s_mb_2u_lib.s9s_mb_2u(sch_1):page260_i22@pure_quanta.q_res(chips)',
 PATH='I22',
 DRAWING='@S9S_MB_2U_LIB.S9S_MB_2U(SCH_1):PAGE246',
 BOM_COST='VR_SYSTEM ',
 PHYS_PAGE='260',
 XY='(-5575,6600)',
 ROT='0',
 VER='1',
 PACK_TYPE='0402LF',
 CDS_LIB='pure_quanta',
 CDS_PART_NAME='Q_RES_0402LF-10K,1%,1/16W,CHIPA',
 WATTAGE='1/16W',
 TOLERANCE='1%',
 MATERIAL='CHIP',
 REUSE_ID='3',
 VALUE='10K',
 PRIM_FILE='./archive_libs/logical/q_res/chips/chips.prt';

PART_NAME
 R1643 'Q_RES_0402LF-100K,1%,1/16W,CHIA':
 REUSE_ID='1';

SECTION_NUMBER 1
 '@S9S_MB_2U_LIB.S9S_MB_2U(SCH_1):PAGE246_I17@PURE_QUANTA.Q_RES(CHIPS)':
 C_PATH='@s9s_mb_2u_lib.s9s_mb_2u(sch_1):page246_i17@pure_quanta.q_res(chips)',
 P_PATH='@s9s_mb_2u_lib.s9s_mb_2u(sch_1):page260_i17@pure_quanta.q_res(chips)',
 PATH='I17',
 DRAWING='@S9S_MB_2U_LIB.S9S_MB_2U(SCH_1):PAGE246',
 BOM_COST='VR_SYSTEM ',
 PHYS_PAGE='260',
 XY='(-5125,5525)',
 ROT='0',
 VER='2',
 PACK_TYPE='0402LF',
 CDS_LIB='pure_quanta',
 CDS_PART_NAME='Q_RES_0402LF-100K,1%,1/16W,CHIA',
 WATTAGE='1/16W',
 TOLERANCE='1%',
 MATERIAL='CHIP',
 REUSE_ID='1',
 VALUE='100K',
 PRIM_FILE='./archive_libs/logical/q_res/chips/chips.prt';

PART_NAME
 R1648 'Q_RES_0402LF-0,5%,1/16W,EMPTY,A':;

SECTION_NUMBER 1
 '@S9S_MB_2U_LIB.S9S_MB_2U(SCH_1):PAGE224_I3@PURE_QUANTA.Q_RES(CHIPS)':
 C_PATH='@s9s_mb_2u_lib.s9s_mb_2u(sch_1):page224_i3@pure_quanta.q_res(chips)',
 P_PATH='@s9s_mb_2u_lib.s9s_mb_2u(sch_1):page236_i3@pure_quanta.q_res(chips)',
 PATH='I3',
 DRAWING='@S9S_MB_2U_LIB.S9S_MB_2U(SCH_1):PAGE224',
 PHYS_PAGE='236',
 XY='(2000,4800)',
 ROT='0',
 VER='2',
 PACK_TYPE='0402LF',
 CDS_LIB='pure_quanta',
 CDS_PART_NAME='Q_RES_0402LF-0,5%,1/16W,EMPTY,A',
 WATTAGE='1/16W',
 TOLERANCE='5%',
 MATERIAL='EMPTY',
 VALUE='0',
 PRIM_FILE='./archive_libs/logical/q_res/chips/chips.prt';

PART_NAME
 R1650 'Q_RES_0402LF-0,5%,1/16W,CHIP,CA':;

SECTION_NUMBER 1
 '@S9S_MB_2U_LIB.S9S_MB_2U(SCH_1):PAGE248_I51@PURE_QUANTA.Q_RES(CHIPS)':
 C_PATH='@s9s_mb_2u_lib.s9s_mb_2u(sch_1):page248_i51@pure_quanta.q_res(chips)',
 P_PATH='@s9s_mb_2u_lib.s9s_mb_2u(sch_1):page262_i51@pure_quanta.q_res(chips)',
 PATH='I51',
 DRAWING='@S9S_MB_2U_LIB.S9S_MB_2U(SCH_1):PAGE248',
 PHYS_PAGE='262',
 XY='(975,150)',
 ROT='0',
 VER='1',
 PACK_TYPE='0402LF',
 LOCATION='R1650',
 CDS_LIB='pure_quanta',
 CDS_PART_NAME='Q_RES_0402LF-0,5%,1/16W,CHIP,CA',
 WATTAGE='1/16W',
 TOLERANCE='5%',
 MATERIAL='CHIP',
 VALUE='0',
 PRIM_FILE='./archive_libs/logical/q_res/chips/chips.prt';

PART_NAME
 R1652 'Q_RES_0402LF-0,5%,1/16W,CHIP,CA':;

SECTION_NUMBER 1
 '@S9S_MB_2U_LIB.S9S_MB_2U(SCH_1):PAGE268_I33@PURE_QUANTA.Q_RES(CHIPS)':
 C_PATH='@s9s_mb_2u_lib.s9s_mb_2u(sch_1):page268_i33@pure_quanta.q_res(chips)',
 P_PATH='@s9s_mb_2u_lib.s9s_mb_2u(sch_1):page282_i33@pure_quanta.q_res(chips)',
 PATH='I33',
 DRAWING='@S9S_MB_2U_LIB.S9S_MB_2U(SCH_1):PAGE268',
 PHYS_PAGE='282',
 XY='(-5075,10625)',
 ROT='0',
 VER='1',
 PACK_TYPE='0402LF',
 LOCATION='R1652',
 CDS_LIB='pure_quanta',
 CDS_PART_NAME='Q_RES_0402LF-0,5%,1/16W,CHIP,CA',
 WATTAGE='1/16W',
 TOLERANCE='5%',
 MATERIAL='CHIP',
 VALUE='0',
 PRIM_FILE='./archive_libs/logical/q_res/chips/chips.prt';

PART_NAME
 R1654 'Q_RES_0402LF-1K,1%,1/16W,CHIP,A':
 REUSE_ID='3';

SECTION_NUMBER 1
 '@S9S_MB_2U_LIB.S9S_MB_2U(SCH_1):PAGE246_I27@PURE_QUANTA.Q_RES(CHIPS)':
 C_PATH='@s9s_mb_2u_lib.s9s_mb_2u(sch_1):page246_i27@pure_quanta.q_res(chips)',
 P_PATH='@s9s_mb_2u_lib.s9s_mb_2u(sch_1):page260_i27@pure_quanta.q_res(chips)',
 PATH='I27',
 DRAWING='@S9S_MB_2U_LIB.S9S_MB_2U(SCH_1):PAGE246',
 BOM_COST='VR_SYSTEM ',
 PHYS_PAGE='260',
 XY='(-4350,6300)',
 ROT='0',
 VER='2',
 PACK_TYPE='0402LF',
 CDS_LIB='pure_quanta',
 CDS_PART_NAME='Q_RES_0402LF-1K,1%,1/16W,CHIP,A',
 WATTAGE='1/16W',
 TOLERANCE='1%',
 MATERIAL='CHIP',
 REUSE_ID='3',
 VALUE='1K',
 PRIM_FILE='./archive_libs/logical/q_res/chips/chips.prt';

PART_NAME
 R1655 'Q_RES_0402LF-10K,1%,1/16W,CHIPA':;

SECTION_NUMBER 1
 '@S9S_MB_2U_LIB.S9S_MB_2U(SCH_1):PAGE246_I6@PURE_QUANTA.Q_RES(CHIPS)':
 C_PATH='@s9s_mb_2u_lib.s9s_mb_2u(sch_1):page246_i6@pure_quanta.q_res(chips)',
 P_PATH='@s9s_mb_2u_lib.s9s_mb_2u(sch_1):page260_i6@pure_quanta.q_res(chips)',
 PATH='I6',
 DRAWING='@S9S_MB_2U_LIB.S9S_MB_2U(SCH_1):PAGE246',
 PHYS_PAGE='260',
 XY='(-1200,4800)',
 ROT='0',
 VER='2',
 PACK_TYPE='0402LF',
 CDS_LIB='pure_quanta',
 CDS_PART_NAME='Q_RES_0402LF-10K,1%,1/16W,CHIPA',
 WATTAGE='1/16W',
 TOLERANCE='1%',
 MATERIAL='CHIP',
 VALUE='10K',
 PRIM_FILE='./archive_libs/logical/q_res/chips/chips.prt';

PART_NAME
 R1656 'Q_RES_0402LF-33.2,1%,1/16W,CHIA':;

SECTION_NUMBER 1
 '@S9S_MB_2U_LIB.S9S_MB_2U(SCH_1):PAGE175_I178@PURE_QUANTA.Q_RES(CHIPS)':
 C_PATH='@s9s_mb_2u_lib.s9s_mb_2u(sch_1):page175_i178@pure_quanta.q_res(chips)',
 P_PATH='@s9s_mb_2u_lib.s9s_mb_2u(sch_1):page183_i178@pure_quanta.q_res(chips)',
 PATH='I178',
 DRAWING='@S9S_MB_2U_LIB.S9S_MB_2U(SCH_1):PAGE175',
 PHYS_PAGE='183',
 XY='(2950,1150)',
 ROT='0',
 VER='1',
 PACK_TYPE='0402LF',
 CDS_LIB='pure_quanta',
 CDS_PART_NAME='Q_RES_0402LF-33.2,1%,1/16W,CHIA',
 WATTAGE='1/16W',
 TOLERANCE='1%',
 MATERIAL='CHIP',
 VALUE='33.2',
 PRIM_FILE='./archive_libs/logical/q_res/chips/chips.prt';

PART_NAME
 R1657 'Q_RES_0402LF-33.2,1%,1/16W,CHIA':;

SECTION_NUMBER 1
 '@S9S_MB_2U_LIB.S9S_MB_2U(SCH_1):PAGE175_I180@PURE_QUANTA.Q_RES(CHIPS)':
 C_PATH='@s9s_mb_2u_lib.s9s_mb_2u(sch_1):page175_i180@pure_quanta.q_res(chips)',
 P_PATH='@s9s_mb_2u_lib.s9s_mb_2u(sch_1):page183_i180@pure_quanta.q_res(chips)',
 PATH='I180',
 DRAWING='@S9S_MB_2U_LIB.S9S_MB_2U(SCH_1):PAGE175',
 PHYS_PAGE='183',
 XY='(2950,1025)',
 ROT='0',
 VER='1',
 PACK_TYPE='0402LF',
 CDS_LIB='pure_quanta',
 CDS_PART_NAME='Q_RES_0402LF-33.2,1%,1/16W,CHIA',
 WATTAGE='1/16W',
 TOLERANCE='1%',
 MATERIAL='CHIP',
 VALUE='33.2',
 PRIM_FILE='./archive_libs/logical/q_res/chips/chips.prt';

PART_NAME
 R1659 'Q_RES_0402LF-10K,1%,1/16W,CHIPA':;

SECTION_NUMBER 1
 '@S9S_MB_2U_LIB.S9S_MB_2U(SCH_1):PAGE175_I181@PURE_QUANTA.Q_RES(CHIPS)':
 C_PATH='@s9s_mb_2u_lib.s9s_mb_2u(sch_1):page175_i181@pure_quanta.q_res(chips)',
 P_PATH='@s9s_mb_2u_lib.s9s_mb_2u(sch_1):page183_i181@pure_quanta.q_res(chips)',
 PATH='I181',
 DRAWING='@S9S_MB_2U_LIB.S9S_MB_2U(SCH_1):PAGE175',
 PHYS_PAGE='183',
 XY='(3475,-125)',
 ROT='0',
 VER='1',
 PACK_TYPE='0402LF',
 CDS_LIB='pure_quanta',
 CDS_PART_NAME='Q_RES_0402LF-10K,1%,1/16W,CHIPA',
 WATTAGE='1/16W',
 TOLERANCE='1%',
 MATERIAL='CHIP',
 VALUE='10K',
 PRIM_FILE='./archive_libs/logical/q_res/chips/chips.prt';

PART_NAME
 R1660 'Q_RES_0402LF-10K,1%,1/16W,EMPTA':;

SECTION_NUMBER 1
 '@S9S_MB_2U_LIB.S9S_MB_2U(SCH_1):PAGE209_I14@PURE_QUANTA.Q_RES(CHIPS)':
 C_PATH='@s9s_mb_2u_lib.s9s_mb_2u(sch_1):page209_i14@pure_quanta.q_res(chips)',
 P_PATH='@s9s_mb_2u_lib.s9s_mb_2u(sch_1):page220_i14@pure_quanta.q_res(chips)',
 PATH='I14',
 DRAWING='@S9S_MB_2U_LIB.S9S_MB_2U(SCH_1):PAGE209',
 PHYS_PAGE='220',
 XY='(-1850,-500)',
 ROT='0',
 VER='1',
 PACK_TYPE='0402LF',
 CDS_LIB='pure_quanta',
 CDS_PART_NAME='Q_RES_0402LF-10K,1%,1/16W,EMPTA',
 WATTAGE='1/16W',
 TOLERANCE='1%',
 MATERIAL='EMPTY',
 VALUE='10K',
 PRIM_FILE='./archive_libs/logical/q_res/chips/chips.prt';

PART_NAME
 R1661 'Q_RES_0402LF-33.2,1%,1/16W,CHIA':;

SECTION_NUMBER 1
 '@S9S_MB_2U_LIB.S9S_MB_2U(SCH_1):PAGE228_I89@PURE_QUANTA.Q_RES(CHIPS)':
 C_PATH='@s9s_mb_2u_lib.s9s_mb_2u(sch_1):page228_i89@pure_quanta.q_res(chips)',
 P_PATH='@s9s_mb_2u_lib.s9s_mb_2u(sch_1):page241_i89@pure_quanta.q_res(chips)',
 PATH='I89',
 DRAWING='@S9S_MB_2U_LIB.S9S_MB_2U(SCH_1):PAGE228',
 PHYS_PAGE='241',
 XY='(-325,2725)',
 ROT='0',
 VER='1',
 PACK_TYPE='0402LF',
 CDS_LIB='pure_quanta',
 CDS_PART_NAME='Q_RES_0402LF-33.2,1%,1/16W,CHIA',
 WATTAGE='1/16W',
 TOLERANCE='1%',
 MATERIAL='CHIP',
 VALUE='33.2',
 PRIM_FILE='./archive_libs/logical/q_res/chips/chips.prt';

PART_NAME
 R1662 'Q_RES_0402LF-33.2,1%,1/16W,CHIA':;

SECTION_NUMBER 1
 '@S9S_MB_2U_LIB.S9S_MB_2U(SCH_1):PAGE228_I90@PURE_QUANTA.Q_RES(CHIPS)':
 C_PATH='@s9s_mb_2u_lib.s9s_mb_2u(sch_1):page228_i90@pure_quanta.q_res(chips)',
 P_PATH='@s9s_mb_2u_lib.s9s_mb_2u(sch_1):page241_i90@pure_quanta.q_res(chips)',
 PATH='I90',
 DRAWING='@S9S_MB_2U_LIB.S9S_MB_2U(SCH_1):PAGE228',
 PHYS_PAGE='241',
 XY='(-325,2675)',
 ROT='0',
 VER='1',
 PACK_TYPE='0402LF',
 CDS_LIB='pure_quanta',
 CDS_PART_NAME='Q_RES_0402LF-33.2,1%,1/16W,CHIA',
 WATTAGE='1/16W',
 TOLERANCE='1%',
 MATERIAL='CHIP',
 VALUE='33.2',
 PRIM_FILE='./archive_libs/logical/q_res/chips/chips.prt';

PART_NAME
 R1671 'Q_RES_0402LF-0,5%,1/16W,CHIP,CA':;

SECTION_NUMBER 1
 '@S9S_MB_2U_LIB.S9S_MB_2U(SCH_1):PAGE150_I51@PURE_QUANTA.Q_RES(CHIPS)':
 C_PATH='@s9s_mb_2u_lib.s9s_mb_2u(sch_1):page150_i51@pure_quanta.q_res(chips)',
 P_PATH='@s9s_mb_2u_lib.s9s_mb_2u(sch_1):page153_i51@pure_quanta.q_res(chips)',
 PATH='I51',
 DRAWING='@S9S_MB_2U_LIB.S9S_MB_2U(SCH_1):PAGE150',
 PHYS_PAGE='153',
 XY='(-2900,5750)',
 ROT='0',
 VER='1',
 PACK_TYPE='0402LF',
 CDS_LIB='pure_quanta',
 CDS_PART_NAME='Q_RES_0402LF-0,5%,1/16W,CHIP,CA',
 WATTAGE='1/16W',
 TOLERANCE='5%',
 MATERIAL='CHIP',
 VALUE='0',
 PRIM_FILE='./archive_libs/logical/q_res/chips/chips.prt';

PART_NAME
 R1673 'Q_RES_0402LF-10K,1%,1/16W,CHIPA':;

SECTION_NUMBER 1
 '@S9S_MB_2U_LIB.S9S_MB_2U(SCH_1):PAGE297_I312@PURE_QUANTA.Q_RES(CHIPS)':
 C_PATH='@s9s_mb_2u_lib.s9s_mb_2u(sch_1):page297_i312@pure_quanta.q_res(chips)',
 P_PATH='@s9s_mb_2u_lib.s9s_mb_2u(sch_1):page191_i312@pure_quanta.q_res(chips)',
 PATH='I312',
 DRAWING='@S9S_MB_2U_LIB.S9S_MB_2U(SCH_1):PAGE297',
 PHYS_PAGE='191',
 XY='(2300,4625)',
 ROT='0',
 VER='2',
 PACK_TYPE='0402LF',
 LOCATION='R1673',
 CDS_LIB='pure_quanta',
 CDS_PART_NAME='Q_RES_0402LF-10K,1%,1/16W,CHIPA',
 WATTAGE='1/16W',
 TOLERANCE='1%',
 MATERIAL='CHIP',
 VALUE='10K',
 PRIM_FILE='./archive_libs/logical/q_res/chips/chips.prt';

PART_NAME
 R1675 'Q_RES_0402LF-2.49K,1%,1/16W,CHA':;

SECTION_NUMBER 1
 '@S9S_MB_2U_LIB.S9S_MB_2U(SCH_1):PAGE174_I82@PURE_QUANTA.Q_RES(CHIPS)':
 C_PATH='@s9s_mb_2u_lib.s9s_mb_2u(sch_1):page174_i82@pure_quanta.q_res(chips)',
 P_PATH='@s9s_mb_2u_lib.s9s_mb_2u(sch_1):page182_i82@pure_quanta.q_res(chips)',
 PATH='I82',
 DRAWING='@S9S_MB_2U_LIB.S9S_MB_2U(SCH_1):PAGE174',
 PHYS_PAGE='182',
 XY='(3850,-350)',
 ROT='0',
 VER='1',
 PACK_TYPE='0402LF',
 CDS_LIB='pure_quanta',
 CDS_PART_NAME='Q_RES_0402LF-2.49K,1%,1/16W,CHA',
 WATTAGE='1/16W',
 TOLERANCE='1%',
 MATERIAL='CHIP',
 VALUE='2.49K',
 PRIM_FILE='./archive_libs/logical/q_res/chips/chips.prt';

PART_NAME
 R1676 'Q_RES_0402LF-1K,1%,1/16W,EMPTYA':;

SECTION_NUMBER 1
 '@S9S_MB_2U_LIB.S9S_MB_2U(SCH_1):PAGE174_I94@PURE_QUANTA.Q_RES(CHIPS)':
 C_PATH='@s9s_mb_2u_lib.s9s_mb_2u(sch_1):page174_i94@pure_quanta.q_res(chips)',
 P_PATH='@s9s_mb_2u_lib.s9s_mb_2u(sch_1):page182_i94@pure_quanta.q_res(chips)',
 PATH='I94',
 DRAWING='@S9S_MB_2U_LIB.S9S_MB_2U(SCH_1):PAGE174',
 PHYS_PAGE='182',
 XY='(3850,-600)',
 ROT='0',
 VER='1',
 PACK_TYPE='0402LF',
 LOCATION='R1676',
 CDS_LIB='pure_quanta',
 CDS_PART_NAME='Q_RES_0402LF-1K,1%,1/16W,EMPTYA',
 WATTAGE='1/16W',
 TOLERANCE='1%',
 MATERIAL='EMPTY',
 VALUE='1K',
 PRIM_FILE='./archive_libs/logical/q_res/chips/chips.prt';

PART_NAME
 R1680 'Q_RES_0402LF-0,5%,1/16W,CHIP,CA':;

SECTION_NUMBER 1
 '@S9S_MB_2U_LIB.S9S_MB_2U(SCH_1):PAGE197_I252@PURE_QUANTA.Q_RES(CHIPS)':
 C_PATH='@s9s_mb_2u_lib.s9s_mb_2u(sch_1):page197_i252@pure_quanta.q_res(chips)',
 P_PATH='@s9s_mb_2u_lib.s9s_mb_2u(sch_1):page208_i252@pure_quanta.q_res(chips)',
 PATH='I252',
 DRAWING='@S9S_MB_2U_LIB.S9S_MB_2U(SCH_1):PAGE197',
 PHYS_PAGE='208',
 XY='(-2325,6125)',
 ROT='0',
 VER='1',
 PACK_TYPE='0402LF',
 CDS_LIB='pure_quanta',
 CDS_PART_NAME='Q_RES_0402LF-0,5%,1/16W,CHIP,CA',
 WATTAGE='1/16W',
 TOLERANCE='5%',
 MATERIAL='CHIP',
 VALUE='0',
 PRIM_FILE='./archive_libs/logical/q_res/chips/chips.prt';

PART_NAME
 R1681 'Q_RES_0402LF-10K,1%,1/16W,CHIPA':;

SECTION_NUMBER 1
 '@S9S_MB_2U_LIB.S9S_MB_2U(SCH_1):PAGE314_I47@PURE_QUANTA.Q_RES(CHIPS)':
 C_PATH='@s9s_mb_2u_lib.s9s_mb_2u(sch_1):page314_i47@pure_quanta.q_res(chips)',
 P_PATH='@s9s_mb_2u_lib.s9s_mb_2u(sch_1):page213_i47@pure_quanta.q_res(chips)',
 PATH='I47',
 DRAWING='@S9S_MB_2U_LIB.S9S_MB_2U(SCH_1):PAGE314',
 PHYS_PAGE='213',
 XY='(-2300,2625)',
 ROT='2',
 VER='2',
 PACK_TYPE='0402LF',
 CDS_LIB='pure_quanta',
 CDS_PART_NAME='Q_RES_0402LF-10K,1%,1/16W,CHIPA',
 WATTAGE='1/16W',
 TOLERANCE='1%',
 MATERIAL='CHIP',
 VALUE='10K',
 PRIM_FILE='./archive_libs/logical/q_res/chips/chips.prt';

PART_NAME
 R1688 'Q_RES_0402LF-100K,1%,1/16W,CHIA':;

SECTION_NUMBER 1
 '@S9S_MB_2U_LIB.S9S_MB_2U(SCH_1):PAGE232_I18@PURE_QUANTA.Q_RES(CHIPS)':
 C_PATH='@s9s_mb_2u_lib.s9s_mb_2u(sch_1):page232_i18@pure_quanta.q_res(chips)',
 P_PATH='@s9s_mb_2u_lib.s9s_mb_2u(sch_1):page244_i18@pure_quanta.q_res(chips)',
 PATH='I18',
 DRAWING='@S9S_MB_2U_LIB.S9S_MB_2U(SCH_1):PAGE232',
 PHYS_PAGE='244',
 XY='(-2250,2075)',
 ROT='2',
 VER='2',
 PACK_TYPE='0402LF',
 CDS_LIB='pure_quanta',
 CDS_PART_NAME='Q_RES_0402LF-100K,1%,1/16W,CHIA',
 WATTAGE='1/16W',
 TOLERANCE='1%',
 MATERIAL='CHIP',
 VALUE='100K',
 PRIM_FILE='./archive_libs/logical/q_res/chips/chips.prt';

PART_NAME
 R1689 'Q_RES_0402LF-6.19K,1%,1/16W,CHA':;

SECTION_NUMBER 1
 '@S9S_MB_2U_LIB.S9S_MB_2U(SCH_1):PAGE232_I16@PURE_QUANTA.Q_RES(CHIPS)':
 C_PATH='@s9s_mb_2u_lib.s9s_mb_2u(sch_1):page232_i16@pure_quanta.q_res(chips)',
 P_PATH='@s9s_mb_2u_lib.s9s_mb_2u(sch_1):page244_i16@pure_quanta.q_res(chips)',
 PATH='I16',
 DRAWING='@S9S_MB_2U_LIB.S9S_MB_2U(SCH_1):PAGE232',
 PHYS_PAGE='244',
 XY='(-2250,1650)',
 ROT='2',
 VER='2',
 PACK_TYPE='0402LF',
 CDS_LIB='pure_quanta',
 CDS_PART_NAME='Q_RES_0402LF-6.19K,1%,1/16W,CHA',
 WATTAGE='1/16W',
 TOLERANCE='1%',
 MATERIAL='CHIP',
 VALUE='6.19K',
 PRIM_FILE='./archive_libs/logical/q_res/chips/chips.prt';

PART_NAME
 R1690 'Q_RES_0402LF-10K,1%,1/16W,CHIPA':;

SECTION_NUMBER 1
 '@S9S_MB_2U_LIB.S9S_MB_2U(SCH_1):PAGE232_I22@PURE_QUANTA.Q_RES(CHIPS)':
 C_PATH='@s9s_mb_2u_lib.s9s_mb_2u(sch_1):page232_i22@pure_quanta.q_res(chips)',
 P_PATH='@s9s_mb_2u_lib.s9s_mb_2u(sch_1):page244_i22@pure_quanta.q_res(chips)',
 PATH='I22',
 DRAWING='@S9S_MB_2U_LIB.S9S_MB_2U(SCH_1):PAGE232',
 PHYS_PAGE='244',
 XY='(-1850,2075)',
 ROT='0',
 VER='2',
 PACK_TYPE='0402LF',
 CDS_LIB='pure_quanta',
 CDS_PART_NAME='Q_RES_0402LF-10K,1%,1/16W,CHIPA',
 WATTAGE='1/16W',
 TOLERANCE='1%',
 MATERIAL='CHIP',
 VALUE='10K',
 PRIM_FILE='./archive_libs/logical/q_res/chips/chips.prt';

PART_NAME
 R1691 'Q_RES_0402LF-10K,1%,1/16W,EMPTA':;

SECTION_NUMBER 1
 '@S9S_MB_2U_LIB.S9S_MB_2U(SCH_1):PAGE232_I4@PURE_QUANTA.Q_RES(CHIPS)':
 C_PATH='@s9s_mb_2u_lib.s9s_mb_2u(sch_1):page232_i4@pure_quanta.q_res(chips)',
 P_PATH='@s9s_mb_2u_lib.s9s_mb_2u(sch_1):page244_i4@pure_quanta.q_res(chips)',
 PATH='I4',
 DRAWING='@S9S_MB_2U_LIB.S9S_MB_2U(SCH_1):PAGE232',
 PHYS_PAGE='244',
 XY='(-2175,-2075)',
 ROT='0',
 VER='2',
 PACK_TYPE='0402LF',
 CDS_LIB='pure_quanta',
 CDS_PART_NAME='Q_RES_0402LF-10K,1%,1/16W,EMPTA',
 WATTAGE='1/16W',
 TOLERANCE='1%',
 MATERIAL='EMPTY',
 VALUE='10K',
 PRIM_FILE='./archive_libs/logical/q_res/chips/chips.prt';

PART_NAME
 R1692 'Q_RES_0402LF-100K,1%,1/16W,CHIA':;

SECTION_NUMBER 1
 '@S9S_MB_2U_LIB.S9S_MB_2U(SCH_1):PAGE232_I3@PURE_QUANTA.Q_RES(CHIPS)':
 C_PATH='@s9s_mb_2u_lib.s9s_mb_2u(sch_1):page232_i3@pure_quanta.q_res(chips)',
 P_PATH='@s9s_mb_2u_lib.s9s_mb_2u(sch_1):page244_i3@pure_quanta.q_res(chips)',
 PATH='I3',
 DRAWING='@S9S_MB_2U_LIB.S9S_MB_2U(SCH_1):PAGE232',
 PHYS_PAGE='244',
 XY='(-2175,-2550)',
 ROT='0',
 VER='2',
 PACK_TYPE='0402LF',
 CDS_LIB='pure_quanta',
 CDS_PART_NAME='Q_RES_0402LF-100K,1%,1/16W,CHIA',
 WATTAGE='1/16W',
 TOLERANCE='1%',
 MATERIAL='CHIP',
 VALUE='100K',
 PRIM_FILE='./archive_libs/logical/q_res/chips/chips.prt';

PART_NAME
 R1693 'Q_RES_0402LF-33.2,1%,1/16W,CHIA':;

SECTION_NUMBER 1
 '@S9S_MB_2U_LIB.S9S_MB_2U(SCH_1):PAGE232_I32@PURE_QUANTA.Q_RES(CHIPS)':
 C_PATH='@s9s_mb_2u_lib.s9s_mb_2u(sch_1):page232_i32@pure_quanta.q_res(chips)',
 P_PATH='@s9s_mb_2u_lib.s9s_mb_2u(sch_1):page244_i32@pure_quanta.q_res(chips)',
 PATH='I32',
 DRAWING='@S9S_MB_2U_LIB.S9S_MB_2U(SCH_1):PAGE232',
 PHYS_PAGE='244',
 XY='(400,-2300)',
 ROT='0',
 VER='1',
 PACK_TYPE='0402LF',
 CDS_LIB='pure_quanta',
 CDS_PART_NAME='Q_RES_0402LF-33.2,1%,1/16W,CHIA',
 WATTAGE='1/16W',
 TOLERANCE='1%',
 MATERIAL='CHIP',
 VALUE='33.2',
 PRIM_FILE='./archive_libs/logical/q_res/chips/chips.prt';

PART_NAME
 R1694 'Q_RES_0402LF-10K,1%,1/16W,CHIPA':;

SECTION_NUMBER 1
 '@S9S_MB_2U_LIB.S9S_MB_2U(SCH_1):PAGE232_I33@PURE_QUANTA.Q_RES(CHIPS)':
 C_PATH='@s9s_mb_2u_lib.s9s_mb_2u(sch_1):page232_i33@pure_quanta.q_res(chips)',
 P_PATH='@s9s_mb_2u_lib.s9s_mb_2u(sch_1):page244_i33@pure_quanta.q_res(chips)',
 PATH='I33',
 DRAWING='@S9S_MB_2U_LIB.S9S_MB_2U(SCH_1):PAGE232',
 PHYS_PAGE='244',
 XY='(975,-1975)',
 ROT='2',
 VER='2',
 PACK_TYPE='0402LF',
 CDS_LIB='pure_quanta',
 CDS_PART_NAME='Q_RES_0402LF-10K,1%,1/16W,CHIPA',
 WATTAGE='1/16W',
 TOLERANCE='1%',
 MATERIAL='CHIP',
 VALUE='10K',
 PRIM_FILE='./archive_libs/logical/q_res/chips/chips.prt';

PART_NAME
 R1695 'Q_RES_0402LF-0,5%,1/16W,EMPTY,A':;

SECTION_NUMBER 1
 '@S9S_MB_2U_LIB.S9S_MB_2U(SCH_1):PAGE232_I36@PURE_QUANTA.Q_RES(CHIPS)':
 C_PATH='@s9s_mb_2u_lib.s9s_mb_2u(sch_1):page232_i36@pure_quanta.q_res(chips)',
 P_PATH='@s9s_mb_2u_lib.s9s_mb_2u(sch_1):page244_i36@pure_quanta.q_res(chips)',
 PATH='I36',
 DRAWING='@S9S_MB_2U_LIB.S9S_MB_2U(SCH_1):PAGE232',
 PHYS_PAGE='244',
 XY='(1600,-2525)',
 ROT='0',
 VER='2',
 PACK_TYPE='0402LF',
 CDS_LIB='pure_quanta',
 CDS_PART_NAME='Q_RES_0402LF-0,5%,1/16W,EMPTY,A',
 WATTAGE='1/16W',
 TOLERANCE='5%',
 MATERIAL='EMPTY',
 VALUE='0',
 PRIM_FILE='./archive_libs/logical/q_res/chips/chips.prt';

PART_NAME
 R1700 'Q_RES_0402LF-200K,1%,1/16W,CHIA':;

SECTION_NUMBER 1
 '@S9S_MB_2U_LIB.S9S_MB_2U(SCH_1):PAGE183_I72@PURE_QUANTA.Q_RES(CHIPS)':
 C_PATH='@s9s_mb_2u_lib.s9s_mb_2u(sch_1):page183_i72@pure_quanta.q_res(chips)',
 P_PATH='@s9s_mb_2u_lib.s9s_mb_2u(sch_1):page194_i72@pure_quanta.q_res(chips)',
 PATH='I72',
 DRAWING='@S9S_MB_2U_LIB.S9S_MB_2U(SCH_1):PAGE183',
 PHYS_PAGE='194',
 XY='(0,3750)',
 ROT='0',
 VER='2',
 PACK_TYPE='0402LF',
 CDS_LIB='pure_quanta',
 CDS_PART_NAME='Q_RES_0402LF-200K,1%,1/16W,CHIA',
 WATTAGE='1/16W',
 TOLERANCE='1%',
 MATERIAL='CHIP',
 VALUE='200K',
 PRIM_FILE='./archive_libs/logical/q_res/chips/chips.prt';

PART_NAME
 R1702 'Q_RES_0402LF-4.7K,5%,1/16W,CHIA':;

SECTION_NUMBER 1
 '@S9S_MB_2U_LIB.S9S_MB_2U(SCH_1):PAGE183_I43@PURE_QUANTA.Q_RES(CHIPS)':
 C_PATH='@s9s_mb_2u_lib.s9s_mb_2u(sch_1):page183_i43@pure_quanta.q_res(chips)',
 P_PATH='@s9s_mb_2u_lib.s9s_mb_2u(sch_1):page194_i43@pure_quanta.q_res(chips)',
 PATH='I43',
 DRAWING='@S9S_MB_2U_LIB.S9S_MB_2U(SCH_1):PAGE183',
 PHYS_PAGE='194',
 XY='(2250,3775)',
 ROT='0',
 VER='2',
 PACK_TYPE='0402LF',
 CDS_LIB='pure_quanta',
 CDS_PART_NAME='Q_RES_0402LF-4.7K,5%,1/16W,CHIA',
 WATTAGE='1/16W',
 TOLERANCE='5%',
 MATERIAL='CHIP',
 VALUE='4.7K',
 PRIM_FILE='./archive_libs/logical/q_res/chips/chips.prt';

PART_NAME
 R1703 'Q_RES_0402LF-4.7K,5%,1/16W,CHIA':;

SECTION_NUMBER 1
 '@S9S_MB_2U_LIB.S9S_MB_2U(SCH_1):PAGE183_I45@PURE_QUANTA.Q_RES(CHIPS)':
 C_PATH='@s9s_mb_2u_lib.s9s_mb_2u(sch_1):page183_i45@pure_quanta.q_res(chips)',
 P_PATH='@s9s_mb_2u_lib.s9s_mb_2u(sch_1):page194_i45@pure_quanta.q_res(chips)',
 PATH='I45',
 DRAWING='@S9S_MB_2U_LIB.S9S_MB_2U(SCH_1):PAGE183',
 PHYS_PAGE='194',
 XY='(2500,3775)',
 ROT='0',
 VER='2',
 PACK_TYPE='0402LF',
 CDS_LIB='pure_quanta',
 CDS_PART_NAME='Q_RES_0402LF-4.7K,5%,1/16W,CHIA',
 WATTAGE='1/16W',
 TOLERANCE='5%',
 MATERIAL='CHIP',
 VALUE='4.7K',
 PRIM_FILE='./archive_libs/logical/q_res/chips/chips.prt';

PART_NAME
 R1706 'Q_RES_0402LF-10K,1%,1/16W,EMPTA':;

SECTION_NUMBER 1
 '@S9S_MB_2U_LIB.S9S_MB_2U(SCH_1):PAGE246_I89@PURE_QUANTA.Q_RES(CHIPS)':
 C_PATH='@s9s_mb_2u_lib.s9s_mb_2u(sch_1):page246_i89@pure_quanta.q_res(chips)',
 P_PATH='@s9s_mb_2u_lib.s9s_mb_2u(sch_1):page260_i89@pure_quanta.q_res(chips)',
 PATH='I89',
 DRAWING='@S9S_MB_2U_LIB.S9S_MB_2U(SCH_1):PAGE246',
 PHYS_PAGE='260',
 XY='(-5900,3350)',
 ROT='0',
 VER='2',
 PACK_TYPE='0402LF',
 CDS_LIB='pure_quanta',
 CDS_PART_NAME='Q_RES_0402LF-10K,1%,1/16W,EMPTA',
 WATTAGE='1/16W',
 TOLERANCE='1%',
 MATERIAL='EMPTY',
 VALUE='10K',
 PRIM_FILE='./archive_libs/logical/q_res/chips/chips.prt';

PART_NAME
 R1710 'Q_RES_0402LF-49.9,1%,1/16W,CHIA':;

SECTION_NUMBER 1
 '@S9S_MB_2U_LIB.S9S_MB_2U(SCH_1):PAGE312_I38@PURE_QUANTA.Q_RES(CHIPS)':
 C_PATH='@s9s_mb_2u_lib.s9s_mb_2u(sch_1):page312_i38@pure_quanta.q_res(chips)',
 P_PATH='@s9s_mb_2u_lib.s9s_mb_2u(sch_1):page215_i38@pure_quanta.q_res(chips)',
 PATH='I38',
 DRAWING='@S9S_MB_2U_LIB.S9S_MB_2U(SCH_1):PAGE312',
 PHYS_PAGE='215',
 XY='(950,2375)',
 ROT='0',
 VER='1',
 PACK_TYPE='0402LF',
 CDS_LIB='pure_quanta',
 CDS_PART_NAME='Q_RES_0402LF-49.9,1%,1/16W,CHIA',
 WATTAGE='1/16W',
 TOLERANCE='1%',
 MATERIAL='CHIP',
 VALUE='49.9',
 PRIM_FILE='./archive_libs/logical/q_res/chips/chips.prt';

PART_NAME
 R1712 'Q_RES_0402LF-4.7K,5%,1/16W,EMPA':;

SECTION_NUMBER 1
 '@S9S_MB_2U_LIB.S9S_MB_2U(SCH_1):PAGE252_I42@PURE_QUANTA.Q_RES(CHIPS)':
 C_PATH='@s9s_mb_2u_lib.s9s_mb_2u(sch_1):page252_i42@pure_quanta.q_res(chips)',
 P_PATH='@s9s_mb_2u_lib.s9s_mb_2u(sch_1):page266_i42@pure_quanta.q_res(chips)',
 PATH='I42',
 DRAWING='@S9S_MB_2U_LIB.S9S_MB_2U(SCH_1):PAGE252',
 PHYS_PAGE='266',
 XY='(-5125,5600)',
 ROT='0',
 VER='1',
 PACK_TYPE='0402LF',
 LOCATION='R1712',
 CDS_LIB='pure_quanta',
 CDS_PART_NAME='Q_RES_0402LF-4.7K,5%,1/16W,EMPA',
 WATTAGE='1/16W',
 TOLERANCE='5%',
 MATERIAL='EMPTY',
 VALUE='4.7K',
 PRIM_FILE='./archive_libs/logical/q_res/chips/chips.prt';

PART_NAME
 R1713 'Q_RES_0402LF-4.7K,5%,1/16W,EMPA':;

SECTION_NUMBER 1
 '@S9S_MB_2U_LIB.S9S_MB_2U(SCH_1):PAGE252_I40@PURE_QUANTA.Q_RES(CHIPS)':
 C_PATH='@s9s_mb_2u_lib.s9s_mb_2u(sch_1):page252_i40@pure_quanta.q_res(chips)',
 P_PATH='@s9s_mb_2u_lib.s9s_mb_2u(sch_1):page266_i40@pure_quanta.q_res(chips)',
 PATH='I40',
 DRAWING='@S9S_MB_2U_LIB.S9S_MB_2U(SCH_1):PAGE252',
 PHYS_PAGE='266',
 XY='(-5125,5550)',
 ROT='0',
 VER='1',
 PACK_TYPE='0402LF',
 LOCATION='R1713',
 CDS_LIB='pure_quanta',
 CDS_PART_NAME='Q_RES_0402LF-4.7K,5%,1/16W,EMPA',
 WATTAGE='1/16W',
 TOLERANCE='5%',
 MATERIAL='EMPTY',
 VALUE='4.7K',
 PRIM_FILE='./archive_libs/logical/q_res/chips/chips.prt';

PART_NAME
 R1714 'Q_RES_0402LF-0,5%,1/16W,CHIP,CA':
 ROOM='HSC1_BOM1';

SECTION_NUMBER 1
 '@S9S_MB_2U_LIB.S9S_MB_2U(SCH_1):PAGE303_I37@PURE_QUANTA.Q_RES(CHIPS)':
 C_PATH='@s9s_mb_2u_lib.s9s_mb_2u(sch_1):page303_i37@pure_quanta.q_res(chips)',
 P_PATH='@s9s_mb_2u_lib.s9s_mb_2u(sch_1):page301_i37@pure_quanta.q_res(chips)',
 PATH='I37',
 DRAWING='@S9S_MB_2U_LIB.S9S_MB_2U(SCH_1):PAGE303',
 PHYS_PAGE='301',
 XY='(-15400,3775)',
 ROT='0',
 VER='1',
 PACK_TYPE='0402LF',
 LOCATION='R1714',
 CDS_LIB='pure_quanta',
 CDS_PART_NAME='Q_RES_0402LF-0,5%,1/16W,CHIP,CA',
 WATTAGE='1/16W',
 TOLERANCE='5%',
 MATERIAL='CHIP',
 ROOM='HSC1_BOM1',
 VALUE='0',
 PRIM_FILE='./archive_libs/logical/q_res/chips/chips.prt';

PART_NAME
 R1717 'Q_RES_0402LF-49.9,1%,1/16W,CHIA':;

SECTION_NUMBER 1
 '@S9S_MB_2U_LIB.S9S_MB_2U(SCH_1):PAGE264_I25@PURE_QUANTA.Q_RES(CHIPS)':
 C_PATH='@s9s_mb_2u_lib.s9s_mb_2u(sch_1):page264_i25@pure_quanta.q_res(chips)',
 P_PATH='@s9s_mb_2u_lib.s9s_mb_2u(sch_1):page278_i25@pure_quanta.q_res(chips)',
 PATH='I25',
 DRAWING='@S9S_MB_2U_LIB.S9S_MB_2U(SCH_1):PAGE264',
 PHYS_PAGE='278',
 XY='(-11350,8675)',
 ROT='0',
 VER='1',
 PACK_TYPE='0402LF',
 LOCATION='R1717',
 CDS_LIB='pure_quanta',
 CDS_PART_NAME='Q_RES_0402LF-49.9,1%,1/16W,CHIA',
 WATTAGE='1/16W',
 TOLERANCE='1%',
 MATERIAL='CHIP',
 VALUE='49.9',
 PRIM_FILE='./archive_libs/logical/q_res/chips/chips.prt';

PART_NAME
 R1718 'Q_RES_0402LF-49.9,1%,1/16W,CHIA':;

SECTION_NUMBER 1
 '@S9S_MB_2U_LIB.S9S_MB_2U(SCH_1):PAGE282_I33@PURE_QUANTA.Q_RES(CHIPS)':
 C_PATH='@s9s_mb_2u_lib.s9s_mb_2u(sch_1):page282_i33@pure_quanta.q_res(chips)',
 P_PATH='@s9s_mb_2u_lib.s9s_mb_2u(sch_1):page296_i33@pure_quanta.q_res(chips)',
 PATH='I33',
 DRAWING='@S9S_MB_2U_LIB.S9S_MB_2U(SCH_1):PAGE282',
 PHYS_PAGE='296',
 XY='(-6800,5175)',
 ROT='0',
 VER='1',
 PACK_TYPE='0402LF',
 LOCATION='R1718',
 CDS_LIB='pure_quanta',
 CDS_PART_NAME='Q_RES_0402LF-49.9,1%,1/16W,CHIA',
 WATTAGE='1/16W',
 TOLERANCE='1%',
 MATERIAL='CHIP',
 VALUE='49.9',
 PRIM_FILE='./archive_libs/logical/q_res/chips/chips.prt';

PART_NAME
 R1719 'Q_RES_0402LF-33.2,1%,1/16W,CHIA':;

SECTION_NUMBER 1
 '@S9S_MB_2U_LIB.S9S_MB_2U(SCH_1):PAGE151_I5@PURE_QUANTA.Q_RES(CHIPS)':
 C_PATH='@s9s_mb_2u_lib.s9s_mb_2u(sch_1):page151_i5@pure_quanta.q_res(chips)',
 P_PATH='@s9s_mb_2u_lib.s9s_mb_2u(sch_1):page154_i5@pure_quanta.q_res(chips)',
 PATH='I5',
 DRAWING='@S9S_MB_2U_LIB.S9S_MB_2U(SCH_1):PAGE151',
 PHYS_PAGE='154',
 XY='(-4675,3675)',
 ROT='0',
 VER='1',
 PACK_TYPE='0402LF',
 CDS_LIB='pure_quanta',
 CDS_PART_NAME='Q_RES_0402LF-33.2,1%,1/16W,CHIA',
 WATTAGE='1/16W',
 TOLERANCE='1%',
 MATERIAL='CHIP',
 VALUE='33.2',
 PRIM_FILE='./archive_libs/logical/q_res/chips/chips.prt';

PART_NAME
 R1720 'Q_RES_0402LF-0,5%,1/16W,EMPTY,A':;

SECTION_NUMBER 1
 '@S9S_MB_2U_LIB.S9S_MB_2U(SCH_1):PAGE171_I103@PURE_QUANTA.Q_RES(CHIPS)':
 C_PATH='@s9s_mb_2u_lib.s9s_mb_2u(sch_1):page171_i103@pure_quanta.q_res(chips)',
 P_PATH='@s9s_mb_2u_lib.s9s_mb_2u(sch_1):page179_i103@pure_quanta.q_res(chips)',
 PATH='I103',
 DRAWING='@S9S_MB_2U_LIB.S9S_MB_2U(SCH_1):PAGE171',
 PHYS_PAGE='179',
 XY='(-325,675)',
 ROT='0',
 VER='1',
 PACK_TYPE='0402LF',
 CDS_LIB='pure_quanta',
 CDS_PART_NAME='Q_RES_0402LF-0,5%,1/16W,EMPTY,A',
 WATTAGE='1/16W',
 TOLERANCE='5%',
 MATERIAL='EMPTY',
 VALUE='0',
 PRIM_FILE='./archive_libs/logical/q_res/chips/chips.prt';

PART_NAME
 R1721 'Q_RES_0402LF-0,5%,1/16W,CHIP,CA':;

SECTION_NUMBER 1
 '@S9S_MB_2U_LIB.S9S_MB_2U(SCH_1):PAGE171_I104@PURE_QUANTA.Q_RES(CHIPS)':
 C_PATH='@s9s_mb_2u_lib.s9s_mb_2u(sch_1):page171_i104@pure_quanta.q_res(chips)',
 P_PATH='@s9s_mb_2u_lib.s9s_mb_2u(sch_1):page179_i104@pure_quanta.q_res(chips)',
 PATH='I104',
 DRAWING='@S9S_MB_2U_LIB.S9S_MB_2U(SCH_1):PAGE171',
 PHYS_PAGE='179',
 XY='(2200,225)',
 ROT='0',
 VER='1',
 PACK_TYPE='0402LF',
 CDS_LIB='pure_quanta',
 CDS_PART_NAME='Q_RES_0402LF-0,5%,1/16W,CHIP,CA',
 WATTAGE='1/16W',
 TOLERANCE='5%',
 MATERIAL='CHIP',
 VALUE='0',
 PRIM_FILE='./archive_libs/logical/q_res/chips/chips.prt';

PART_NAME
 R1724 'Q_RES_0402LF-0,5%,1/16W,CHIP,CA':;

SECTION_NUMBER 1
 '@S9S_MB_2U_LIB.S9S_MB_2U(SCH_1):PAGE197_I392@PURE_QUANTA.Q_RES(CHIPS)':
 C_PATH='@s9s_mb_2u_lib.s9s_mb_2u(sch_1):page197_i392@pure_quanta.q_res(chips)',
 P_PATH='@s9s_mb_2u_lib.s9s_mb_2u(sch_1):page208_i392@pure_quanta.q_res(chips)',
 PATH='I392',
 DRAWING='@S9S_MB_2U_LIB.S9S_MB_2U(SCH_1):PAGE197',
 PHYS_PAGE='208',
 XY='(-4150,6275)',
 ROT='0',
 VER='1',
 PACK_TYPE='0402LF',
 LOCATION='R1724',
 CDS_LIB='pure_quanta',
 CDS_PART_NAME='Q_RES_0402LF-0,5%,1/16W,CHIP,CA',
 WATTAGE='1/16W',
 TOLERANCE='5%',
 MATERIAL='CHIP',
 VALUE='0',
 PRIM_FILE='./archive_libs/logical/q_res/chips/chips.prt';

PART_NAME
 R1735 'Q_RES_0402LF-100,1%,1/16W,CHIPA':;

SECTION_NUMBER 1
 '@S9S_MB_2U_LIB.S9S_MB_2U(SCH_1):PAGE264_I24@PURE_QUANTA.Q_RES(CHIPS)':
 C_PATH='@s9s_mb_2u_lib.s9s_mb_2u(sch_1):page264_i24@pure_quanta.q_res(chips)',
 P_PATH='@s9s_mb_2u_lib.s9s_mb_2u(sch_1):page278_i24@pure_quanta.q_res(chips)',
 PATH='I24',
 DRAWING='@S9S_MB_2U_LIB.S9S_MB_2U(SCH_1):PAGE264',
 PHYS_PAGE='278',
 XY='(-11350,8575)',
 ROT='0',
 VER='1',
 PACK_TYPE='0402LF',
 LOCATION='R1735',
 CDS_LIB='pure_quanta',
 CDS_PART_NAME='Q_RES_0402LF-100,1%,1/16W,CHIPA',
 WATTAGE='1/16W',
 TOLERANCE='1%',
 MATERIAL='CHIP',
 VALUE='100',
 PRIM_FILE='./archive_libs/logical/q_res/chips/chips.prt';

PART_NAME
 R1736 'Q_RES_0402LF-33.2,1%,1/16W,CHIA':;

SECTION_NUMBER 1
 '@S9S_MB_2U_LIB.S9S_MB_2U(SCH_1):PAGE174_I99@PURE_QUANTA.Q_RES(CHIPS)':
 C_PATH='@s9s_mb_2u_lib.s9s_mb_2u(sch_1):page174_i99@pure_quanta.q_res(chips)',
 P_PATH='@s9s_mb_2u_lib.s9s_mb_2u(sch_1):page182_i99@pure_quanta.q_res(chips)',
 PATH='I99',
 DRAWING='@S9S_MB_2U_LIB.S9S_MB_2U(SCH_1):PAGE174',
 PHYS_PAGE='182',
 XY='(-150,-200)',
 ROT='0',
 VER='1',
 PACK_TYPE='0402LF',
 LOCATION='R1736',
 CDS_LIB='pure_quanta',
 CDS_PART_NAME='Q_RES_0402LF-33.2,1%,1/16W,CHIA',
 WATTAGE='1/16W',
 TOLERANCE='1%',
 MATERIAL='CHIP',
 VALUE='33.2',
 PRIM_FILE='./archive_libs/logical/q_res/chips/chips.prt';

PART_NAME
 R1741 'Q_RES_0402LF-1K,1%,1/16W,CHIP,A':;

SECTION_NUMBER 1
 '@S9S_MB_2U_LIB.S9S_MB_2U(SCH_1):PAGE209_I38@PURE_QUANTA.Q_RES(CHIPS)':
 C_PATH='@s9s_mb_2u_lib.s9s_mb_2u(sch_1):page209_i38@pure_quanta.q_res(chips)',
 P_PATH='@s9s_mb_2u_lib.s9s_mb_2u(sch_1):page220_i38@pure_quanta.q_res(chips)',
 PATH='I38',
 DRAWING='@S9S_MB_2U_LIB.S9S_MB_2U(SCH_1):PAGE209',
 PHYS_PAGE='220',
 XY='(1775,-775)',
 ROT='0',
 VER='1',
 PACK_TYPE='0402LF',
 CDS_LIB='pure_quanta',
 CDS_PART_NAME='Q_RES_0402LF-1K,1%,1/16W,CHIP,A',
 WATTAGE='1/16W',
 TOLERANCE='1%',
 MATERIAL='CHIP',
 VALUE='1K',
 PRIM_FILE='./archive_libs/logical/q_res/chips/chips.prt';

PART_NAME
 R1742 'Q_RES_0402LF-10K,1%,1/16W,EMPTA':;

SECTION_NUMBER 1
 '@S9S_MB_2U_LIB.S9S_MB_2U(SCH_1):PAGE209_I24@PURE_QUANTA.Q_RES(CHIPS)':
 C_PATH='@s9s_mb_2u_lib.s9s_mb_2u(sch_1):page209_i24@pure_quanta.q_res(chips)',
 P_PATH='@s9s_mb_2u_lib.s9s_mb_2u(sch_1):page220_i24@pure_quanta.q_res(chips)',
 PATH='I24',
 DRAWING='@S9S_MB_2U_LIB.S9S_MB_2U(SCH_1):PAGE209',
 PHYS_PAGE='220',
 XY='(1775,-1525)',
 ROT='0',
 VER='1',
 PACK_TYPE='0402LF',
 CDS_LIB='pure_quanta',
 CDS_PART_NAME='Q_RES_0402LF-10K,1%,1/16W,EMPTA',
 WATTAGE='1/16W',
 TOLERANCE='1%',
 MATERIAL='EMPTY',
 VALUE='10K',
 PRIM_FILE='./archive_libs/logical/q_res/chips/chips.prt';

PART_NAME
 R1744 'Q_RES_0402LF-0,5%,1/16W,CHIP,CA':;

SECTION_NUMBER 1
 '@S9S_MB_2U_LIB.S9S_MB_2U(SCH_1):PAGE212_I94@PURE_QUANTA.Q_RES(CHIPS)':
 C_PATH='@s9s_mb_2u_lib.s9s_mb_2u(sch_1):page212_i94@pure_quanta.q_res(chips)',
 P_PATH='@s9s_mb_2u_lib.s9s_mb_2u(sch_1):page223_i94@pure_quanta.q_res(chips)',
 PATH='I94',
 DRAWING='@S9S_MB_2U_LIB.S9S_MB_2U(SCH_1):PAGE212',
 PHYS_PAGE='223',
 XY='(-2800,3775)',
 ROT='0',
 VER='1',
 PACK_TYPE='0402LF',
 CDS_LIB='pure_quanta',
 CDS_PART_NAME='Q_RES_0402LF-0,5%,1/16W,CHIP,CA',
 WATTAGE='1/16W',
 TOLERANCE='5%',
 MATERIAL='CHIP',
 VALUE='0',
 PRIM_FILE='./archive_libs/logical/q_res/chips/chips.prt';

PART_NAME
 R1745 'Q_RES_0402LF-0,5%,1/16W,EMPTY,A':;

SECTION_NUMBER 1
 '@S9S_MB_2U_LIB.S9S_MB_2U(SCH_1):PAGE232_I21@PURE_QUANTA.Q_RES(CHIPS)':
 C_PATH='@s9s_mb_2u_lib.s9s_mb_2u(sch_1):page232_i21@pure_quanta.q_res(chips)',
 P_PATH='@s9s_mb_2u_lib.s9s_mb_2u(sch_1):page244_i21@pure_quanta.q_res(chips)',
 PATH='I21',
 DRAWING='@S9S_MB_2U_LIB.S9S_MB_2U(SCH_1):PAGE232',
 PHYS_PAGE='244',
 XY='(-1600,425)',
 ROT='0',
 VER='1',
 PACK_TYPE='0402LF',
 CDS_LIB='pure_quanta',
 CDS_PART_NAME='Q_RES_0402LF-0,5%,1/16W,EMPTY,A',
 WATTAGE='1/16W',
 TOLERANCE='5%',
 MATERIAL='EMPTY',
 VALUE='0',
 PRIM_FILE='./archive_libs/logical/q_res/chips/chips.prt';

PART_NAME
 R1747 'Q_RES_0805LF-0,5%,1/8W,CHIP,CSA':;

SECTION_NUMBER 1
 '@S9S_MB_2U_LIB.S9S_MB_2U(SCH_1):PAGE243_I2@PURE_QUANTA.Q_RES(CHIPS)':
 C_PATH='@s9s_mb_2u_lib.s9s_mb_2u(sch_1):page243_i2@pure_quanta.q_res(chips)',
 P_PATH='@s9s_mb_2u_lib.s9s_mb_2u(sch_1):page257_i2@pure_quanta.q_res(chips)',
 PATH='I2',
 DRAWING='@S9S_MB_2U_LIB.S9S_MB_2U(SCH_1):PAGE243',
 PHYS_PAGE='257',
 XY='(-4675,13625)',
 ROT='0',
 VER='2',
 PACK_TYPE='0805LF',
 CDS_LIB='pure_quanta',
 CDS_PART_NAME='Q_RES_0805LF-0,5%,1/8W,CHIP,CSA',
 WATTAGE='1/8W',
 TOLERANCE='5%',
 MATERIAL='CHIP',
 VALUE='0',
 PRIM_FILE='./archive_libs/logical/q_res/chips/chips.prt';

PART_NAME
 R1748 'Q_RES_0402LF-0,5%,1/16W,CHIP,CA':;

SECTION_NUMBER 1
 '@S9S_MB_2U_LIB.S9S_MB_2U(SCH_1):PAGE190_I54@PURE_QUANTA.Q_RES(CHIPS)':
 C_PATH='@s9s_mb_2u_lib.s9s_mb_2u(sch_1):page190_i54@pure_quanta.q_res(chips)',
 P_PATH='@s9s_mb_2u_lib.s9s_mb_2u(sch_1):page202_i54@pure_quanta.q_res(chips)',
 PATH='I54',
 DRAWING='@S9S_MB_2U_LIB.S9S_MB_2U(SCH_1):PAGE190',
 PHYS_PAGE='202',
 XY='(2800,2725)',
 ROT='0',
 VER='1',
 PACK_TYPE='0402LF',
 CDS_LIB='pure_quanta',
 CDS_PART_NAME='Q_RES_0402LF-0,5%,1/16W,CHIP,CA',
 WATTAGE='1/16W',
 TOLERANCE='5%',
 MATERIAL='CHIP',
 VALUE='0',
 PRIM_FILE='./archive_libs/logical/q_res/chips/chips.prt';

PART_NAME
 R1749 'Q_RES_0402LF-10K,1%,1/16W,EMPTA':;

SECTION_NUMBER 1
 '@S9S_MB_2U_LIB.S9S_MB_2U(SCH_1):PAGE190_I89@PURE_QUANTA.Q_RES(CHIPS)':
 C_PATH='@s9s_mb_2u_lib.s9s_mb_2u(sch_1):page190_i89@pure_quanta.q_res(chips)',
 P_PATH='@s9s_mb_2u_lib.s9s_mb_2u(sch_1):page202_i89@pure_quanta.q_res(chips)',
 PATH='I89',
 DRAWING='@S9S_MB_2U_LIB.S9S_MB_2U(SCH_1):PAGE190',
 PHYS_PAGE='202',
 XY='(575,1150)',
 ROT='0',
 VER='2',
 PACK_TYPE='0402LF',
 CDS_LIB='pure_quanta',
 CDS_PART_NAME='Q_RES_0402LF-10K,1%,1/16W,EMPTA',
 WATTAGE='1/16W',
 TOLERANCE='1%',
 MATERIAL='EMPTY',
 VALUE='10K',
 PRIM_FILE='./archive_libs/logical/q_res/chips/chips.prt';

PART_NAME
 R1750 'Q_RES_0402LF-1K,1%,1/16W,CHIP,A':;

SECTION_NUMBER 1
 '@S9S_MB_2U_LIB.S9S_MB_2U(SCH_1):PAGE190_I87@PURE_QUANTA.Q_RES(CHIPS)':
 C_PATH='@s9s_mb_2u_lib.s9s_mb_2u(sch_1):page190_i87@pure_quanta.q_res(chips)',
 P_PATH='@s9s_mb_2u_lib.s9s_mb_2u(sch_1):page202_i87@pure_quanta.q_res(chips)',
 PATH='I87',
 DRAWING='@S9S_MB_2U_LIB.S9S_MB_2U(SCH_1):PAGE190',
 PHYS_PAGE='202',
 XY='(3000,1675)',
 ROT='0',
 VER='2',
 PACK_TYPE='0402LF',
 CDS_LIB='pure_quanta',
 CDS_PART_NAME='Q_RES_0402LF-1K,1%,1/16W,CHIP,A',
 WATTAGE='1/16W',
 TOLERANCE='1%',
 MATERIAL='CHIP',
 VALUE='1K',
 PRIM_FILE='./archive_libs/logical/q_res/chips/chips.prt';

PART_NAME
 R1751 'Q_RES_0402LF-33.2,1%,1/16W,CHIA':;

SECTION_NUMBER 1
 '@S9S_MB_2U_LIB.S9S_MB_2U(SCH_1):PAGE211_I81@PURE_QUANTA.Q_RES(CHIPS)':
 C_PATH='@s9s_mb_2u_lib.s9s_mb_2u(sch_1):page211_i81@pure_quanta.q_res(chips)',
 P_PATH='@s9s_mb_2u_lib.s9s_mb_2u(sch_1):page222_i81@pure_quanta.q_res(chips)',
 PATH='I81',
 DRAWING='@S9S_MB_2U_LIB.S9S_MB_2U(SCH_1):PAGE211',
 PHYS_PAGE='222',
 XY='(3000,4200)',
 ROT='0',
 VER='1',
 PACK_TYPE='0402LF',
 CDS_LIB='pure_quanta',
 CDS_PART_NAME='Q_RES_0402LF-33.2,1%,1/16W,CHIA',
 WATTAGE='1/16W',
 TOLERANCE='1%',
 MATERIAL='CHIP',
 VALUE='33.2',
 PRIM_FILE='./archive_libs/logical/q_res/chips/chips.prt';

PART_NAME
 R1752 'Q_RES_0402LF-33.2,1%,1/16W,CHIA':;

SECTION_NUMBER 1
 '@S9S_MB_2U_LIB.S9S_MB_2U(SCH_1):PAGE211_I82@PURE_QUANTA.Q_RES(CHIPS)':
 C_PATH='@s9s_mb_2u_lib.s9s_mb_2u(sch_1):page211_i82@pure_quanta.q_res(chips)',
 P_PATH='@s9s_mb_2u_lib.s9s_mb_2u(sch_1):page222_i82@pure_quanta.q_res(chips)',
 PATH='I82',
 DRAWING='@S9S_MB_2U_LIB.S9S_MB_2U(SCH_1):PAGE211',
 PHYS_PAGE='222',
 XY='(3000,3975)',
 ROT='0',
 VER='1',
 PACK_TYPE='0402LF',
 CDS_LIB='pure_quanta',
 CDS_PART_NAME='Q_RES_0402LF-33.2,1%,1/16W,CHIA',
 WATTAGE='1/16W',
 TOLERANCE='1%',
 MATERIAL='CHIP',
 VALUE='33.2',
 PRIM_FILE='./archive_libs/logical/q_res/chips/chips.prt';

PART_NAME
 R1753 'Q_RES_0402LF-33.2,1%,1/16W,CHIA':;

SECTION_NUMBER 1
 '@S9S_MB_2U_LIB.S9S_MB_2U(SCH_1):PAGE211_I84@PURE_QUANTA.Q_RES(CHIPS)':
 C_PATH='@s9s_mb_2u_lib.s9s_mb_2u(sch_1):page211_i84@pure_quanta.q_res(chips)',
 P_PATH='@s9s_mb_2u_lib.s9s_mb_2u(sch_1):page222_i84@pure_quanta.q_res(chips)',
 PATH='I84',
 DRAWING='@S9S_MB_2U_LIB.S9S_MB_2U(SCH_1):PAGE211',
 PHYS_PAGE='222',
 XY='(3000,3725)',
 ROT='0',
 VER='1',
 PACK_TYPE='0402LF',
 CDS_LIB='pure_quanta',
 CDS_PART_NAME='Q_RES_0402LF-33.2,1%,1/16W,CHIA',
 WATTAGE='1/16W',
 TOLERANCE='1%',
 MATERIAL='CHIP',
 VALUE='33.2',
 PRIM_FILE='./archive_libs/logical/q_res/chips/chips.prt';

PART_NAME
 R1754 'Q_RES_0402LF-33.2,1%,1/16W,CHIA':;

SECTION_NUMBER 1
 '@S9S_MB_2U_LIB.S9S_MB_2U(SCH_1):PAGE211_I88@PURE_QUANTA.Q_RES(CHIPS)':
 C_PATH='@s9s_mb_2u_lib.s9s_mb_2u(sch_1):page211_i88@pure_quanta.q_res(chips)',
 P_PATH='@s9s_mb_2u_lib.s9s_mb_2u(sch_1):page222_i88@pure_quanta.q_res(chips)',
 PATH='I88',
 DRAWING='@S9S_MB_2U_LIB.S9S_MB_2U(SCH_1):PAGE211',
 PHYS_PAGE='222',
 XY='(3000,3500)',
 ROT='0',
 VER='1',
 PACK_TYPE='0402LF',
 CDS_LIB='pure_quanta',
 CDS_PART_NAME='Q_RES_0402LF-33.2,1%,1/16W,CHIA',
 WATTAGE='1/16W',
 TOLERANCE='1%',
 MATERIAL='CHIP',
 VALUE='33.2',
 PRIM_FILE='./archive_libs/logical/q_res/chips/chips.prt';

PART_NAME
 R1755 'Q_RES_0402LF-33.2,1%,1/16W,CHIA':;

SECTION_NUMBER 1
 '@S9S_MB_2U_LIB.S9S_MB_2U(SCH_1):PAGE211_I96@PURE_QUANTA.Q_RES(CHIPS)':
 C_PATH='@s9s_mb_2u_lib.s9s_mb_2u(sch_1):page211_i96@pure_quanta.q_res(chips)',
 P_PATH='@s9s_mb_2u_lib.s9s_mb_2u(sch_1):page222_i96@pure_quanta.q_res(chips)',
 PATH='I96',
 DRAWING='@S9S_MB_2U_LIB.S9S_MB_2U(SCH_1):PAGE211',
 PHYS_PAGE='222',
 XY='(3025,3075)',
 ROT='0',
 VER='1',
 PACK_TYPE='0402LF',
 CDS_LIB='pure_quanta',
 CDS_PART_NAME='Q_RES_0402LF-33.2,1%,1/16W,CHIA',
 WATTAGE='1/16W',
 TOLERANCE='1%',
 MATERIAL='CHIP',
 VALUE='33.2',
 PRIM_FILE='./archive_libs/logical/q_res/chips/chips.prt';

PART_NAME
 R1756 'Q_RES_0402LF-33.2,1%,1/16W,CHIA':;

SECTION_NUMBER 1
 '@S9S_MB_2U_LIB.S9S_MB_2U(SCH_1):PAGE211_I98@PURE_QUANTA.Q_RES(CHIPS)':
 C_PATH='@s9s_mb_2u_lib.s9s_mb_2u(sch_1):page211_i98@pure_quanta.q_res(chips)',
 P_PATH='@s9s_mb_2u_lib.s9s_mb_2u(sch_1):page222_i98@pure_quanta.q_res(chips)',
 PATH='I98',
 DRAWING='@S9S_MB_2U_LIB.S9S_MB_2U(SCH_1):PAGE211',
 PHYS_PAGE='222',
 XY='(3025,2850)',
 ROT='0',
 VER='1',
 PACK_TYPE='0402LF',
 CDS_LIB='pure_quanta',
 CDS_PART_NAME='Q_RES_0402LF-33.2,1%,1/16W,CHIA',
 WATTAGE='1/16W',
 TOLERANCE='1%',
 MATERIAL='CHIP',
 VALUE='33.2',
 PRIM_FILE='./archive_libs/logical/q_res/chips/chips.prt';

PART_NAME
 R1757 'Q_RES_0402LF-33.2,1%,1/16W,CHIA':;

SECTION_NUMBER 1
 '@S9S_MB_2U_LIB.S9S_MB_2U(SCH_1):PAGE211_I99@PURE_QUANTA.Q_RES(CHIPS)':
 C_PATH='@s9s_mb_2u_lib.s9s_mb_2u(sch_1):page211_i99@pure_quanta.q_res(chips)',
 P_PATH='@s9s_mb_2u_lib.s9s_mb_2u(sch_1):page222_i99@pure_quanta.q_res(chips)',
 PATH='I99',
 DRAWING='@S9S_MB_2U_LIB.S9S_MB_2U(SCH_1):PAGE211',
 PHYS_PAGE='222',
 XY='(3025,2600)',
 ROT='0',
 VER='1',
 PACK_TYPE='0402LF',
 CDS_LIB='pure_quanta',
 CDS_PART_NAME='Q_RES_0402LF-33.2,1%,1/16W,CHIA',
 WATTAGE='1/16W',
 TOLERANCE='1%',
 MATERIAL='CHIP',
 VALUE='33.2',
 PRIM_FILE='./archive_libs/logical/q_res/chips/chips.prt';

PART_NAME
 R1758 'Q_RES_0402LF-33.2,1%,1/16W,CHIA':;

SECTION_NUMBER 1
 '@S9S_MB_2U_LIB.S9S_MB_2U(SCH_1):PAGE211_I91@PURE_QUANTA.Q_RES(CHIPS)':
 C_PATH='@s9s_mb_2u_lib.s9s_mb_2u(sch_1):page211_i91@pure_quanta.q_res(chips)',
 P_PATH='@s9s_mb_2u_lib.s9s_mb_2u(sch_1):page222_i91@pure_quanta.q_res(chips)',
 PATH='I91',
 DRAWING='@S9S_MB_2U_LIB.S9S_MB_2U(SCH_1):PAGE211',
 PHYS_PAGE='222',
 XY='(3025,2375)',
 ROT='0',
 VER='1',
 PACK_TYPE='0402LF',
 CDS_LIB='pure_quanta',
 CDS_PART_NAME='Q_RES_0402LF-33.2,1%,1/16W,CHIA',
 WATTAGE='1/16W',
 TOLERANCE='1%',
 MATERIAL='CHIP',
 VALUE='33.2',
 PRIM_FILE='./archive_libs/logical/q_res/chips/chips.prt';

PART_NAME
 R1763 'Q_RES_0402LF-10K,1%,1/16W,EMPTA':;

SECTION_NUMBER 1
 '@S9S_MB_2U_LIB.S9S_MB_2U(SCH_1):PAGE243_I7@PURE_QUANTA.Q_RES(CHIPS)':
 C_PATH='@s9s_mb_2u_lib.s9s_mb_2u(sch_1):page243_i7@pure_quanta.q_res(chips)',
 P_PATH='@s9s_mb_2u_lib.s9s_mb_2u(sch_1):page257_i7@pure_quanta.q_res(chips)',
 PATH='I7',
 DRAWING='@S9S_MB_2U_LIB.S9S_MB_2U(SCH_1):PAGE243',
 PHYS_PAGE='257',
 XY='(-9200,13250)',
 ROT='0',
 VER='2',
 PACK_TYPE='0402LF',
 CDS_LIB='pure_quanta',
 CDS_PART_NAME='Q_RES_0402LF-10K,1%,1/16W,EMPTA',
 WATTAGE='1/16W',
 TOLERANCE='1%',
 MATERIAL='EMPTY',
 VALUE='10K',
 PRIM_FILE='./archive_libs/logical/q_res/chips/chips.prt';

PART_NAME
 R1764 'Q_RES_0402LF-1K,1%,1/16W,EMPTYA':;

SECTION_NUMBER 1
 '@S9S_MB_2U_LIB.S9S_MB_2U(SCH_1):PAGE243_I8@PURE_QUANTA.Q_RES(CHIPS)':
 C_PATH='@s9s_mb_2u_lib.s9s_mb_2u(sch_1):page243_i8@pure_quanta.q_res(chips)',
 P_PATH='@s9s_mb_2u_lib.s9s_mb_2u(sch_1):page257_i8@pure_quanta.q_res(chips)',
 PATH='I8',
 DRAWING='@S9S_MB_2U_LIB.S9S_MB_2U(SCH_1):PAGE243',
 PHYS_PAGE='257',
 XY='(-9200,12650)',
 ROT='0',
 VER='2',
 PACK_TYPE='0402LF',
 CDS_LIB='pure_quanta',
 CDS_PART_NAME='Q_RES_0402LF-1K,1%,1/16W,EMPTYA',
 WATTAGE='1/16W',
 TOLERANCE='1%',
 MATERIAL='EMPTY',
 VALUE='1K',
 PRIM_FILE='./archive_libs/logical/q_res/chips/chips.prt';

PART_NAME
 R1765 'Q_RES_0805LF-0,5%,1/8W,EMPTY,CA':;

SECTION_NUMBER 1
 '@S9S_MB_2U_LIB.S9S_MB_2U(SCH_1):PAGE243_I13@PURE_QUANTA.Q_RES(CHIPS)':
 C_PATH='@s9s_mb_2u_lib.s9s_mb_2u(sch_1):page243_i13@pure_quanta.q_res(chips)',
 P_PATH='@s9s_mb_2u_lib.s9s_mb_2u(sch_1):page257_i13@pure_quanta.q_res(chips)',
 PATH='I13',
 DRAWING='@S9S_MB_2U_LIB.S9S_MB_2U(SCH_1):PAGE243',
 PHYS_PAGE='257',
 XY='(-4675,11800)',
 ROT='0',
 VER='2',
 PACK_TYPE='0805LF',
 CDS_LIB='pure_quanta',
 CDS_PART_NAME='Q_RES_0805LF-0,5%,1/8W,EMPTY,CA',
 WATTAGE='1/8W',
 TOLERANCE='5%',
 MATERIAL='EMPTY',
 VALUE='0',
 PRIM_FILE='./archive_libs/logical/q_res/chips/chips.prt';

PART_NAME
 R1785 'Q_RES_0402LF-4.7K,1%,1/16W,CHIA':;

SECTION_NUMBER 1
 '@S9S_MB_2U_LIB.S9S_MB_2U(SCH_1):PAGE239_I149@PURE_QUANTA.Q_RES(CHIPS)':
 C_PATH='@s9s_mb_2u_lib.s9s_mb_2u(sch_1):page239_i149@pure_quanta.q_res(chips)',
 P_PATH='@s9s_mb_2u_lib.s9s_mb_2u(sch_1):page250_i149@pure_quanta.q_res(chips)',
 PATH='I149',
 DRAWING='@S9S_MB_2U_LIB.S9S_MB_2U(SCH_1):PAGE239',
 PHYS_PAGE='250',
 XY='(-1000,4900)',
 ROT='0',
 VER='2',
 PACK_TYPE='0402LF',
 CDS_LIB='pure_quanta',
 CDS_PART_NAME='Q_RES_0402LF-4.7K,1%,1/16W,CHIA',
 WATTAGE='1/16W',
 TOLERANCE='1%',
 MATERIAL='CHIP',
 VALUE='4.7K',
 PRIM_FILE='./archive_libs/logical/q_res/chips/chips.prt';

PART_NAME
 R1791 'Q_RES_0402LF-9.09K,1%,1/16W,CHA':;

SECTION_NUMBER 1
 '@S9S_MB_2U_LIB.S9S_MB_2U(SCH_1):PAGE239_I163@PURE_QUANTA.Q_RES(CHIPS)':
 C_PATH='@s9s_mb_2u_lib.s9s_mb_2u(sch_1):page239_i163@pure_quanta.q_res(chips)',
 P_PATH='@s9s_mb_2u_lib.s9s_mb_2u(sch_1):page250_i163@pure_quanta.q_res(chips)',
 PATH='I163',
 DRAWING='@S9S_MB_2U_LIB.S9S_MB_2U(SCH_1):PAGE239',
 PHYS_PAGE='250',
 XY='(-1000,2400)',
 ROT='0',
 VER='2',
 PACK_TYPE='0402LF',
 CDS_LIB='pure_quanta',
 CDS_PART_NAME='Q_RES_0402LF-9.09K,1%,1/16W,CHA',
 WATTAGE='1/16W',
 TOLERANCE='1%',
 MATERIAL='CHIP',
 VALUE='9.09K',
 PRIM_FILE='./archive_libs/logical/q_res/chips/chips.prt';

PART_NAME
 R1792 'Q_RES_0402LF-0,5%,1/16W,EMPTY,A':
 ROOM='ADC1_BOM1';

SECTION_NUMBER 1
 '@S9S_MB_2U_LIB.S9S_MB_2U(SCH_1):PAGE239_I20@PURE_QUANTA.Q_RES(CHIPS)':
 C_PATH='@s9s_mb_2u_lib.s9s_mb_2u(sch_1):page239_i20@pure_quanta.q_res(chips)',
 P_PATH='@s9s_mb_2u_lib.s9s_mb_2u(sch_1):page250_i20@pure_quanta.q_res(chips)',
 PATH='I20',
 DRAWING='@S9S_MB_2U_LIB.S9S_MB_2U(SCH_1):PAGE239',
 PHYS_PAGE='250',
 XY='(5525,3150)',
 ROT='0',
 VER='1',
 PACK_TYPE='0402LF',
 CDS_LIB='pure_quanta',
 CDS_PART_NAME='Q_RES_0402LF-0,5%,1/16W,EMPTY,A',
 WATTAGE='1/16W',
 TOLERANCE='5%',
 MATERIAL='EMPTY',
 ROOM='ADC1_BOM1',
 VALUE='0',
 PRIM_FILE='./archive_libs/logical/q_res/chips/chips.prt';

PART_NAME
 R1793 'Q_RES_0402LF-0,5%,1/16W,EMPTY,A':
 ROOM='ADC1_BOM1';

SECTION_NUMBER 1
 '@S9S_MB_2U_LIB.S9S_MB_2U(SCH_1):PAGE239_I19@PURE_QUANTA.Q_RES(CHIPS)':
 C_PATH='@s9s_mb_2u_lib.s9s_mb_2u(sch_1):page239_i19@pure_quanta.q_res(chips)',
 P_PATH='@s9s_mb_2u_lib.s9s_mb_2u(sch_1):page250_i19@pure_quanta.q_res(chips)',
 PATH='I19',
 DRAWING='@S9S_MB_2U_LIB.S9S_MB_2U(SCH_1):PAGE239',
 PHYS_PAGE='250',
 XY='(5525,3100)',
 ROT='0',
 VER='1',
 PACK_TYPE='0402LF',
 CDS_LIB='pure_quanta',
 CDS_PART_NAME='Q_RES_0402LF-0,5%,1/16W,EMPTY,A',
 WATTAGE='1/16W',
 TOLERANCE='5%',
 MATERIAL='EMPTY',
 ROOM='ADC1_BOM1',
 VALUE='0',
 PRIM_FILE='./archive_libs/logical/q_res/chips/chips.prt';

PART_NAME
 R1798 'Q_RES_0402LF-0,5%,1/16W,CHIP,CA':;

SECTION_NUMBER 1
 '@S9S_MB_2U_LIB.S9S_MB_2U(SCH_1):PAGE227_I20@PURE_QUANTA.Q_RES(CHIPS)':
 C_PATH='@s9s_mb_2u_lib.s9s_mb_2u(sch_1):page227_i20@pure_quanta.q_res(chips)',
 P_PATH='@s9s_mb_2u_lib.s9s_mb_2u(sch_1):page240_i20@pure_quanta.q_res(chips)',
 PATH='I20',
 DRAWING='@S9S_MB_2U_LIB.S9S_MB_2U(SCH_1):PAGE227',
 PHYS_PAGE='240',
 XY='(-13325,-1425)',
 ROT='0',
 VER='1',
 PACK_TYPE='0402LF',
 CDS_LIB='pure_quanta',
 CDS_PART_NAME='Q_RES_0402LF-0,5%,1/16W,CHIP,CA',
 WATTAGE='1/16W',
 TOLERANCE='5%',
 MATERIAL='CHIP',
 VALUE='0',
 PRIM_FILE='./archive_libs/logical/q_res/chips/chips.prt';

PART_NAME
 R1799 'Q_RES_0402LF-7.87K,1%,1/16W,CHA':;

SECTION_NUMBER 1
 '@S9S_MB_2U_LIB.S9S_MB_2U(SCH_1):PAGE239_I173@PURE_QUANTA.Q_RES(CHIPS)':
 C_PATH='@s9s_mb_2u_lib.s9s_mb_2u(sch_1):page239_i173@pure_quanta.q_res(chips)',
 P_PATH='@s9s_mb_2u_lib.s9s_mb_2u(sch_1):page250_i173@pure_quanta.q_res(chips)',
 PATH='I173',
 DRAWING='@S9S_MB_2U_LIB.S9S_MB_2U(SCH_1):PAGE239',
 PHYS_PAGE='250',
 XY='(-1025,1650)',
 ROT='0',
 VER='2',
 PACK_TYPE='0402LF',
 CDS_LIB='pure_quanta',
 CDS_PART_NAME='Q_RES_0402LF-7.87K,1%,1/16W,CHA',
 WATTAGE='1/16W',
 TOLERANCE='1%',
 MATERIAL='CHIP',
 VALUE='7.87K',
 PRIM_FILE='./archive_libs/logical/q_res/chips/chips.prt';

PART_NAME
 R1800 'Q_RES_0402LF-1.21K,1%,1/16W,CHA':;

SECTION_NUMBER 1
 '@S9S_MB_2U_LIB.S9S_MB_2U(SCH_1):PAGE239_I174@PURE_QUANTA.Q_RES(CHIPS)':
 C_PATH='@s9s_mb_2u_lib.s9s_mb_2u(sch_1):page239_i174@pure_quanta.q_res(chips)',
 P_PATH='@s9s_mb_2u_lib.s9s_mb_2u(sch_1):page250_i174@pure_quanta.q_res(chips)',
 PATH='I174',
 DRAWING='@S9S_MB_2U_LIB.S9S_MB_2U(SCH_1):PAGE239',
 PHYS_PAGE='250',
 XY='(-1025,1200)',
 ROT='0',
 VER='2',
 PACK_TYPE='0402LF',
 CDS_LIB='pure_quanta',
 CDS_PART_NAME='Q_RES_0402LF-1.21K,1%,1/16W,CHA',
 WATTAGE='1/16W',
 TOLERANCE='1%',
 MATERIAL='CHIP',
 VALUE='1.21K',
 PRIM_FILE='./archive_libs/logical/q_res/chips/chips.prt';

PART_NAME
 R1801 'Q_RES_0402LF-0,5%,1/16W,CHIP,CA':;

SECTION_NUMBER 1
 '@S9S_MB_2U_LIB.S9S_MB_2U(SCH_1):PAGE227_I172@PURE_QUANTA.Q_RES(CHIPS)':
 C_PATH='@s9s_mb_2u_lib.s9s_mb_2u(sch_1):page227_i172@pure_quanta.q_res(chips)',
 P_PATH='@s9s_mb_2u_lib.s9s_mb_2u(sch_1):page240_i172@pure_quanta.q_res(chips)',
 PATH='I172',
 DRAWING='@S9S_MB_2U_LIB.S9S_MB_2U(SCH_1):PAGE227',
 PHYS_PAGE='240',
 XY='(-7625,2250)',
 ROT='0',
 VER='2',
 PACK_TYPE='0402LF',
 CDS_LIB='pure_quanta',
 CDS_PART_NAME='Q_RES_0402LF-0,5%,1/16W,CHIP,CA',
 WATTAGE='1/16W',
 TOLERANCE='5%',
 MATERIAL='CHIP',
 VALUE='0',
 PRIM_FILE='./archive_libs/logical/q_res/chips/chips.prt';

PART_NAME
 R1809 'Q_RES_0402LF-20K,1%,1/16W,CHIPA':;

SECTION_NUMBER 1
 '@S9S_MB_2U_LIB.S9S_MB_2U(SCH_1):PAGE186_I89@PURE_QUANTA.Q_RES(CHIPS)':
 C_PATH='@s9s_mb_2u_lib.s9s_mb_2u(sch_1):page186_i89@pure_quanta.q_res(chips)',
 P_PATH='@s9s_mb_2u_lib.s9s_mb_2u(sch_1):page198_i89@pure_quanta.q_res(chips)',
 PATH='I89',
 DRAWING='@S9S_MB_2U_LIB.S9S_MB_2U(SCH_1):PAGE186',
 PHYS_PAGE='198',
 XY='(-3450,3300)',
 ROT='0',
 VER='2',
 PACK_TYPE='0402LF',
 CDS_LIB='pure_quanta',
 CDS_PART_NAME='Q_RES_0402LF-20K,1%,1/16W,CHIPA',
 WATTAGE='1/16W',
 TOLERANCE='1%',
 MATERIAL='CHIP',
 VALUE='20K',
 PRIM_FILE='./archive_libs/logical/q_res/chips/chips.prt';

PART_NAME
 R1810 'Q_RES_0402LF-1K,1%,1/16W,EMPTYA':;

SECTION_NUMBER 1
 '@S9S_MB_2U_LIB.S9S_MB_2U(SCH_1):PAGE186_I88@PURE_QUANTA.Q_RES(CHIPS)':
 C_PATH='@s9s_mb_2u_lib.s9s_mb_2u(sch_1):page186_i88@pure_quanta.q_res(chips)',
 P_PATH='@s9s_mb_2u_lib.s9s_mb_2u(sch_1):page198_i88@pure_quanta.q_res(chips)',
 PATH='I88',
 DRAWING='@S9S_MB_2U_LIB.S9S_MB_2U(SCH_1):PAGE186',
 PHYS_PAGE='198',
 XY='(-3450,2775)',
 ROT='0',
 VER='2',
 PACK_TYPE='0402LF',
 CDS_LIB='pure_quanta',
 CDS_PART_NAME='Q_RES_0402LF-1K,1%,1/16W,EMPTYA',
 WATTAGE='1/16W',
 TOLERANCE='1%',
 MATERIAL='EMPTY',
 VALUE='1K',
 PRIM_FILE='./archive_libs/logical/q_res/chips/chips.prt';

PART_NAME
 R1811 'Q_RES_0402LF-33.2,1%,1/16W,CHIA':;

SECTION_NUMBER 1
 '@S9S_MB_2U_LIB.S9S_MB_2U(SCH_1):PAGE211_I110@PURE_QUANTA.Q_RES(CHIPS)':
 C_PATH='@s9s_mb_2u_lib.s9s_mb_2u(sch_1):page211_i110@pure_quanta.q_res(chips)',
 P_PATH='@s9s_mb_2u_lib.s9s_mb_2u(sch_1):page222_i110@pure_quanta.q_res(chips)',
 PATH='I110',
 DRAWING='@S9S_MB_2U_LIB.S9S_MB_2U(SCH_1):PAGE211',
 PHYS_PAGE='222',
 XY='(3025,2150)',
 ROT='0',
 VER='1',
 PACK_TYPE='0402LF',
 CDS_LIB='pure_quanta',
 CDS_PART_NAME='Q_RES_0402LF-33.2,1%,1/16W,CHIA',
 WATTAGE='1/16W',
 TOLERANCE='1%',
 MATERIAL='CHIP',
 VALUE='33.2',
 PRIM_FILE='./archive_libs/logical/q_res/chips/chips.prt';

PART_NAME
 R1812 'Q_RES_0402LF-33.2,1%,1/16W,CHIA':;

SECTION_NUMBER 1
 '@S9S_MB_2U_LIB.S9S_MB_2U(SCH_1):PAGE211_I111@PURE_QUANTA.Q_RES(CHIPS)':
 C_PATH='@s9s_mb_2u_lib.s9s_mb_2u(sch_1):page211_i111@pure_quanta.q_res(chips)',
 P_PATH='@s9s_mb_2u_lib.s9s_mb_2u(sch_1):page222_i111@pure_quanta.q_res(chips)',
 PATH='I111',
 DRAWING='@S9S_MB_2U_LIB.S9S_MB_2U(SCH_1):PAGE211',
 PHYS_PAGE='222',
 XY='(3025,1925)',
 ROT='0',
 VER='1',
 PACK_TYPE='0402LF',
 CDS_LIB='pure_quanta',
 CDS_PART_NAME='Q_RES_0402LF-33.2,1%,1/16W,CHIA',
 WATTAGE='1/16W',
 TOLERANCE='1%',
 MATERIAL='CHIP',
 VALUE='33.2',
 PRIM_FILE='./archive_libs/logical/q_res/chips/chips.prt';

PART_NAME
 R1813 'Q_RES_0402LF-10K,1%,1/16W,EMPTA':;

SECTION_NUMBER 1
 '@S9S_MB_2U_LIB.S9S_MB_2U(SCH_1):PAGE226_I79@PURE_QUANTA.Q_RES(CHIPS)':
 C_PATH='@s9s_mb_2u_lib.s9s_mb_2u(sch_1):page226_i79@pure_quanta.q_res(chips)',
 P_PATH='@s9s_mb_2u_lib.s9s_mb_2u(sch_1):page239_i79@pure_quanta.q_res(chips)',
 PATH='I79',
 DRAWING='@S9S_MB_2U_LIB.S9S_MB_2U(SCH_1):PAGE226',
 PHYS_PAGE='239',
 XY='(-14125,-500)',
 ROT='0',
 VER='2',
 PACK_TYPE='0402LF',
 CDS_LIB='pure_quanta',
 CDS_PART_NAME='Q_RES_0402LF-10K,1%,1/16W,EMPTA',
 WATTAGE='1/16W',
 TOLERANCE='1%',
 MATERIAL='EMPTY',
 VALUE='10K',
 PRIM_FILE='./archive_libs/logical/q_res/chips/chips.prt';

PART_NAME
 R1814 'Q_RES_0402LF-1K,1%,1/16W,EMPTYA':;

SECTION_NUMBER 1
 '@S9S_MB_2U_LIB.S9S_MB_2U(SCH_1):PAGE226_I77@PURE_QUANTA.Q_RES(CHIPS)':
 C_PATH='@s9s_mb_2u_lib.s9s_mb_2u(sch_1):page226_i77@pure_quanta.q_res(chips)',
 P_PATH='@s9s_mb_2u_lib.s9s_mb_2u(sch_1):page239_i77@pure_quanta.q_res(chips)',
 PATH='I77',
 DRAWING='@S9S_MB_2U_LIB.S9S_MB_2U(SCH_1):PAGE226',
 PHYS_PAGE='239',
 XY='(-14075,-975)',
 ROT='0',
 VER='2',
 PACK_TYPE='0402LF',
 CDS_LIB='pure_quanta',
 CDS_PART_NAME='Q_RES_0402LF-1K,1%,1/16W,EMPTYA',
 WATTAGE='1/16W',
 TOLERANCE='1%',
 MATERIAL='EMPTY',
 VALUE='1K',
 PRIM_FILE='./archive_libs/logical/q_res/chips/chips.prt';

PART_NAME
 R1815 'Q_RES_0402LF-0,5%,1/16W,CHIP,CA':;

SECTION_NUMBER 1
 '@S9S_MB_2U_LIB.S9S_MB_2U(SCH_1):PAGE227_I26@PURE_QUANTA.Q_RES(CHIPS)':
 C_PATH='@s9s_mb_2u_lib.s9s_mb_2u(sch_1):page227_i26@pure_quanta.q_res(chips)',
 P_PATH='@s9s_mb_2u_lib.s9s_mb_2u(sch_1):page240_i26@pure_quanta.q_res(chips)',
 PATH='I26',
 DRAWING='@S9S_MB_2U_LIB.S9S_MB_2U(SCH_1):PAGE227',
 PHYS_PAGE='240',
 XY='(-13075,-1125)',
 ROT='0',
 VER='1',
 PACK_TYPE='0402LF',
 CDS_LIB='pure_quanta',
 CDS_PART_NAME='Q_RES_0402LF-0,5%,1/16W,CHIP,CA',
 WATTAGE='1/16W',
 TOLERANCE='5%',
 MATERIAL='CHIP',
 VALUE='0',
 PRIM_FILE='./archive_libs/logical/q_res/chips/chips.prt';

PART_NAME
 R1816 'Q_RES_0402LF-0,5%,1/16W,CHIP,CA':;

SECTION_NUMBER 1
 '@S9S_MB_2U_LIB.S9S_MB_2U(SCH_1):PAGE227_I27@PURE_QUANTA.Q_RES(CHIPS)':
 C_PATH='@s9s_mb_2u_lib.s9s_mb_2u(sch_1):page227_i27@pure_quanta.q_res(chips)',
 P_PATH='@s9s_mb_2u_lib.s9s_mb_2u(sch_1):page240_i27@pure_quanta.q_res(chips)',
 PATH='I27',
 DRAWING='@S9S_MB_2U_LIB.S9S_MB_2U(SCH_1):PAGE227',
 PHYS_PAGE='240',
 XY='(-13075,-975)',
 ROT='0',
 VER='1',
 PACK_TYPE='0402LF',
 CDS_LIB='pure_quanta',
 CDS_PART_NAME='Q_RES_0402LF-0,5%,1/16W,CHIP,CA',
 WATTAGE='1/16W',
 TOLERANCE='5%',
 MATERIAL='CHIP',
 VALUE='0',
 PRIM_FILE='./archive_libs/logical/q_res/chips/chips.prt';

PART_NAME
 R1820 'Q_RES_0402LF-10K,1%,1/16W,CHIPA':;

SECTION_NUMBER 1
 '@S9S_MB_2U_LIB.S9S_MB_2U(SCH_1):PAGE191_I35@PURE_QUANTA.Q_RES(CHIPS)':
 C_PATH='@s9s_mb_2u_lib.s9s_mb_2u(sch_1):page191_i35@pure_quanta.q_res(chips)',
 P_PATH='@s9s_mb_2u_lib.s9s_mb_2u(sch_1):page203_i35@pure_quanta.q_res(chips)',
 PATH='I35',
 DRAWING='@S9S_MB_2U_LIB.S9S_MB_2U(SCH_1):PAGE191',
 PHYS_PAGE='203',
 XY='(-2775,3450)',
 ROT='0',
 VER='2',
 PACK_TYPE='0402LF',
 CDS_LIB='pure_quanta',
 CDS_PART_NAME='Q_RES_0402LF-10K,1%,1/16W,CHIPA',
 WATTAGE='1/16W',
 TOLERANCE='1%',
 MATERIAL='CHIP',
 VALUE='10K',
 PRIM_FILE='./archive_libs/logical/q_res/chips/chips.prt';

PART_NAME
 R1821 'Q_RES_0402LF-200,1%,1/16W,CHIPA':;

SECTION_NUMBER 1
 '@S9S_MB_2U_LIB.S9S_MB_2U(SCH_1):PAGE217_I53@PURE_QUANTA.Q_RES(CHIPS)':
 C_PATH='@s9s_mb_2u_lib.s9s_mb_2u(sch_1):page217_i53@pure_quanta.q_res(chips)',
 P_PATH='@s9s_mb_2u_lib.s9s_mb_2u(sch_1):page229_i53@pure_quanta.q_res(chips)',
 PATH='I53',
 DRAWING='@S9S_MB_2U_LIB.S9S_MB_2U(SCH_1):PAGE217',
 PHYS_PAGE='229',
 XY='(-3700,1200)',
 ROT='0',
 VER='1',
 PACK_TYPE='0402LF',
 CDS_LIB='pure_quanta',
 CDS_PART_NAME='Q_RES_0402LF-200,1%,1/16W,CHIPA',
 WATTAGE='1/16W',
 TOLERANCE='1%',
 MATERIAL='CHIP',
 VALUE='200',
 PRIM_FILE='./archive_libs/logical/q_res/chips/chips.prt';

PART_NAME
 R1822 'Q_RES_0402LF-10K,1%,1/16W,CHIPA':;

SECTION_NUMBER 1
 '@S9S_MB_2U_LIB.S9S_MB_2U(SCH_1):PAGE219_I18@PURE_QUANTA.Q_RES(CHIPS)':
 C_PATH='@s9s_mb_2u_lib.s9s_mb_2u(sch_1):page219_i18@pure_quanta.q_res(chips)',
 P_PATH='@s9s_mb_2u_lib.s9s_mb_2u(sch_1):page231_i18@pure_quanta.q_res(chips)',
 PATH='I18',
 DRAWING='@S9S_MB_2U_LIB.S9S_MB_2U(SCH_1):PAGE219',
 PHYS_PAGE='231',
 XY='(-600,3225)',
 ROT='2',
 VER='2',
 PACK_TYPE='0402LF',
 CDS_LIB='pure_quanta',
 CDS_PART_NAME='Q_RES_0402LF-10K,1%,1/16W,CHIPA',
 WATTAGE='1/16W',
 TOLERANCE='1%',
 MATERIAL='CHIP',
 VALUE='10K',
 PRIM_FILE='./archive_libs/logical/q_res/chips/chips.prt';

PART_NAME
 R1823 'Q_RES_0402LF-1K,1%,1/16W,CHIP,A':;

SECTION_NUMBER 1
 '@S9S_MB_2U_LIB.S9S_MB_2U(SCH_1):PAGE311_I4@PURE_QUANTA.Q_RES(CHIPS)':
 C_PATH='@s9s_mb_2u_lib.s9s_mb_2u(sch_1):page311_i4@pure_quanta.q_res(chips)',
 P_PATH='@s9s_mb_2u_lib.s9s_mb_2u(sch_1):page216_i4@pure_quanta.q_res(chips)',
 PATH='I4',
 DRAWING='@S9S_MB_2U_LIB.S9S_MB_2U(SCH_1):PAGE311',
 PHYS_PAGE='216',
 XY='(4175,3350)',
 ROT='0',
 VER='2',
 PACK_TYPE='0402LF',
 CDS_LIB='pure_quanta',
 CDS_PART_NAME='Q_RES_0402LF-1K,1%,1/16W,CHIP,A',
 WATTAGE='1/16W',
 TOLERANCE='1%',
 MATERIAL='CHIP',
 VALUE='1K',
 PRIM_FILE='./archive_libs/logical/q_res/chips/chips.prt';

PART_NAME
 R1824 'Q_RES_0402LF-10K,1%,1/16W,CHIPA':;

SECTION_NUMBER 1
 '@S9S_MB_2U_LIB.S9S_MB_2U(SCH_1):PAGE152_I62@PURE_QUANTA.Q_RES(CHIPS)':
 C_PATH='@s9s_mb_2u_lib.s9s_mb_2u(sch_1):page152_i62@pure_quanta.q_res(chips)',
 P_PATH='@s9s_mb_2u_lib.s9s_mb_2u(sch_1):page155_i62@pure_quanta.q_res(chips)',
 PATH='I62',
 DRAWING='@S9S_MB_2U_LIB.S9S_MB_2U(SCH_1):PAGE152',
 PHYS_PAGE='155',
 XY='(-9850,4475)',
 ROT='2',
 VER='2',
 PACK_TYPE='0402LF',
 CDS_LIB='pure_quanta',
 CDS_PART_NAME='Q_RES_0402LF-10K,1%,1/16W,CHIPA',
 WATTAGE='1/16W',
 TOLERANCE='1%',
 MATERIAL='CHIP',
 VALUE='10K',
 PRIM_FILE='./archive_libs/logical/q_res/chips/chips.prt';

PART_NAME
 R1827 'Q_RES_0402LF-33.2,1%,1/16W,CHIA':;

SECTION_NUMBER 1
 '@S9S_MB_2U_LIB.S9S_MB_2U(SCH_1):PAGE175_I193@PURE_QUANTA.Q_RES(CHIPS)':
 C_PATH='@s9s_mb_2u_lib.s9s_mb_2u(sch_1):page175_i193@pure_quanta.q_res(chips)',
 P_PATH='@s9s_mb_2u_lib.s9s_mb_2u(sch_1):page183_i193@pure_quanta.q_res(chips)',
 PATH='I193',
 DRAWING='@S9S_MB_2U_LIB.S9S_MB_2U(SCH_1):PAGE175',
 PHYS_PAGE='183',
 XY='(2950,775)',
 ROT='0',
 VER='1',
 PACK_TYPE='0402LF',
 CDS_LIB='pure_quanta',
 CDS_PART_NAME='Q_RES_0402LF-33.2,1%,1/16W,CHIA',
 WATTAGE='1/16W',
 TOLERANCE='1%',
 MATERIAL='CHIP',
 VALUE='33.2',
 PRIM_FILE='./archive_libs/logical/q_res/chips/chips.prt';

PART_NAME
 R1828 'Q_RES_0402LF-10K,1%,1/16W,CHIPA':;

SECTION_NUMBER 1
 '@S9S_MB_2U_LIB.S9S_MB_2U(SCH_1):PAGE175_I188@PURE_QUANTA.Q_RES(CHIPS)':
 C_PATH='@s9s_mb_2u_lib.s9s_mb_2u(sch_1):page175_i188@pure_quanta.q_res(chips)',
 P_PATH='@s9s_mb_2u_lib.s9s_mb_2u(sch_1):page183_i188@pure_quanta.q_res(chips)',
 PATH='I188',
 DRAWING='@S9S_MB_2U_LIB.S9S_MB_2U(SCH_1):PAGE175',
 PHYS_PAGE='183',
 XY='(3475,-175)',
 ROT='0',
 VER='1',
 PACK_TYPE='0402LF',
 CDS_LIB='pure_quanta',
 CDS_PART_NAME='Q_RES_0402LF-10K,1%,1/16W,CHIPA',
 WATTAGE='1/16W',
 TOLERANCE='1%',
 MATERIAL='CHIP',
 VALUE='10K',
 PRIM_FILE='./archive_libs/logical/q_res/chips/chips.prt';

PART_NAME
 R1831 'Q_RES_0402LF-0,5%,1/16W,EMPTY,A':;

SECTION_NUMBER 1
 '@S9S_MB_2U_LIB.S9S_MB_2U(SCH_1):PAGE226_I82@PURE_QUANTA.Q_RES(CHIPS)':
 C_PATH='@s9s_mb_2u_lib.s9s_mb_2u(sch_1):page226_i82@pure_quanta.q_res(chips)',
 P_PATH='@s9s_mb_2u_lib.s9s_mb_2u(sch_1):page239_i82@pure_quanta.q_res(chips)',
 PATH='I82',
 DRAWING='@S9S_MB_2U_LIB.S9S_MB_2U(SCH_1):PAGE226',
 PHYS_PAGE='239',
 XY='(-8650,1400)',
 ROT='0',
 VER='1',
 PACK_TYPE='0402LF',
 CDS_LIB='pure_quanta',
 CDS_PART_NAME='Q_RES_0402LF-0,5%,1/16W,EMPTY,A',
 WATTAGE='1/16W',
 TOLERANCE='5%',
 MATERIAL='EMPTY',
 VALUE='0',
 PRIM_FILE='./archive_libs/logical/q_res/chips/chips.prt';

PART_NAME
 R1832 'Q_RES_0402LF-0,5%,1/16W,EMPTY,A':;

SECTION_NUMBER 1
 '@S9S_MB_2U_LIB.S9S_MB_2U(SCH_1):PAGE226_I80@PURE_QUANTA.Q_RES(CHIPS)':
 C_PATH='@s9s_mb_2u_lib.s9s_mb_2u(sch_1):page226_i80@pure_quanta.q_res(chips)',
 P_PATH='@s9s_mb_2u_lib.s9s_mb_2u(sch_1):page239_i80@pure_quanta.q_res(chips)',
 PATH='I80',
 DRAWING='@S9S_MB_2U_LIB.S9S_MB_2U(SCH_1):PAGE226',
 PHYS_PAGE='239',
 XY='(-8625,2925)',
 ROT='0',
 VER='1',
 PACK_TYPE='0402LF',
 CDS_LIB='pure_quanta',
 CDS_PART_NAME='Q_RES_0402LF-0,5%,1/16W,EMPTY,A',
 WATTAGE='1/16W',
 TOLERANCE='5%',
 MATERIAL='EMPTY',
 VALUE='0',
 PRIM_FILE='./archive_libs/logical/q_res/chips/chips.prt';

PART_NAME
 R1833 'Q_RES_0402LF-0,5%,1/16W,EMPTY,A':;

SECTION_NUMBER 1
 '@S9S_MB_2U_LIB.S9S_MB_2U(SCH_1):PAGE313_I167@PURE_QUANTA.Q_RES(CHIPS)':
 C_PATH='@s9s_mb_2u_lib.s9s_mb_2u(sch_1):page313_i167@pure_quanta.q_res(chips)',
 P_PATH='@s9s_mb_2u_lib.s9s_mb_2u(sch_1):page214_i167@pure_quanta.q_res(chips)',
 PATH='I167',
 DRAWING='@S9S_MB_2U_LIB.S9S_MB_2U(SCH_1):PAGE313',
 PHYS_PAGE='214',
 XY='(2675,-2850)',
 ROT='0',
 VER='1',
 PACK_TYPE='0402LF',
 CDS_LIB='pure_quanta',
 CDS_PART_NAME='Q_RES_0402LF-0,5%,1/16W,EMPTY,A',
 WATTAGE='1/16W',
 TOLERANCE='5%',
 MATERIAL='EMPTY',
 VALUE='0',
 PRIM_FILE='./archive_libs/logical/q_res/chips/chips.prt';

PART_NAME
 R1837 'Q_RES_4P_12-0.001,1%,3W,SMLF,CA':;

SECTION_NUMBER 1
 '@S9S_MB_2U_LIB.S9S_MB_2U(SCH_1):PAGE240_I3@PURE_QUANTA.Q_RES_4P_12(CHIPS)':
 C_PATH='@s9s_mb_2u_lib.s9s_mb_2u(sch_1):page240_i3@pure_quanta.q_res_4p_12(chip~
s)',
 P_PATH='@s9s_mb_2u_lib.s9s_mb_2u(sch_1):page251_i3@pure_quanta.q_res_4p_12(chip~
s)',
 PATH='I3',
 DRAWING='@S9S_MB_2U_LIB.S9S_MB_2U(SCH_1):PAGE240',
 PHYS_PAGE='251',
 XY='(-2375,-3975)',
 ROT='1',
 VER='1',
 LOCATION='R1837',
 CDS_LIB='pure_quanta',
 CDS_PART_NAME='Q_RES_4P_12-0.001,1%,3W,SMLF,CA',
 PART_TYPE='SMLF',
 WATTAGE='3W',
 TOLERANCE='1%',
 MATERIAL='CHIP',
 VALUE='0.001',
 PRIM_FILE='./archive_libs/logical/q_res_4p_12/chips/chips.prt';

PART_NAME
 R1838 'Q_RES_4P_12-0.001,1%,3W,SMLF,CA':;

SECTION_NUMBER 1
 '@S9S_MB_2U_LIB.S9S_MB_2U(SCH_1):PAGE240_I11@PURE_QUANTA.Q_RES_4P_12(CHIPS)':
 C_PATH='@s9s_mb_2u_lib.s9s_mb_2u(sch_1):page240_i11@pure_quanta.q_res_4p_12(chi~
ps)',
 P_PATH='@s9s_mb_2u_lib.s9s_mb_2u(sch_1):page251_i11@pure_quanta.q_res_4p_12(chi~
ps)',
 PATH='I11',
 DRAWING='@S9S_MB_2U_LIB.S9S_MB_2U(SCH_1):PAGE240',
 PHYS_PAGE='251',
 XY='(-2400,-2525)',
 ROT='1',
 VER='1',
 LOCATION='R1838',
 CDS_LIB='pure_quanta',
 CDS_PART_NAME='Q_RES_4P_12-0.001,1%,3W,SMLF,CA',
 PART_TYPE='SMLF',
 WATTAGE='3W',
 TOLERANCE='1%',
 MATERIAL='CHIP',
 VALUE='0.001',
 PRIM_FILE='./archive_libs/logical/q_res_4p_12/chips/chips.prt';

PART_NAME
 R1839 'Q_RES_0402LF-0,5%,1/16W,EMPTY,A':;

SECTION_NUMBER 1
 '@S9S_MB_2U_LIB.S9S_MB_2U(SCH_1):PAGE177_I85@PURE_QUANTA.Q_RES(CHIPS)':
 C_PATH='@s9s_mb_2u_lib.s9s_mb_2u(sch_1):page177_i85@pure_quanta.q_res(chips)',
 P_PATH='@s9s_mb_2u_lib.s9s_mb_2u(sch_1):page185_i85@pure_quanta.q_res(chips)',
 PATH='I85',
 DRAWING='@S9S_MB_2U_LIB.S9S_MB_2U(SCH_1):PAGE177',
 PHYS_PAGE='185',
 XY='(-350,-25)',
 ROT='0',
 VER='1',
 PACK_TYPE='0402LF',
 CDS_LIB='pure_quanta',
 CDS_PART_NAME='Q_RES_0402LF-0,5%,1/16W,EMPTY,A',
 WATTAGE='1/16W',
 TOLERANCE='5%',
 MATERIAL='EMPTY',
 VALUE='0',
 PRIM_FILE='./archive_libs/logical/q_res/chips/chips.prt';

PART_NAME
 R1840 'Q_RES_0402LF-0,5%,1/16W,EMPTY,A':;

SECTION_NUMBER 1
 '@S9S_MB_2U_LIB.S9S_MB_2U(SCH_1):PAGE177_I89@PURE_QUANTA.Q_RES(CHIPS)':
 C_PATH='@s9s_mb_2u_lib.s9s_mb_2u(sch_1):page177_i89@pure_quanta.q_res(chips)',
 P_PATH='@s9s_mb_2u_lib.s9s_mb_2u(sch_1):page185_i89@pure_quanta.q_res(chips)',
 PATH='I89',
 DRAWING='@S9S_MB_2U_LIB.S9S_MB_2U(SCH_1):PAGE177',
 PHYS_PAGE='185',
 XY='(-350,-925)',
 ROT='0',
 VER='1',
 PACK_TYPE='0402LF',
 CDS_LIB='pure_quanta',
 CDS_PART_NAME='Q_RES_0402LF-0,5%,1/16W,EMPTY,A',
 WATTAGE='1/16W',
 TOLERANCE='5%',
 MATERIAL='EMPTY',
 VALUE='0',
 PRIM_FILE='./archive_libs/logical/q_res/chips/chips.prt';

PART_NAME
 R1841 'Q_RES_0402LF-10K,1%,1/16W,CHIPA':;

SECTION_NUMBER 1
 '@S9S_MB_2U_LIB.S9S_MB_2U(SCH_1):PAGE207_I275@PURE_QUANTA.Q_RES(CHIPS)':
 C_PATH='@s9s_mb_2u_lib.s9s_mb_2u(sch_1):page207_i275@pure_quanta.q_res(chips)',
 P_PATH='@s9s_mb_2u_lib.s9s_mb_2u(sch_1):page218_i275@pure_quanta.q_res(chips)',
 PATH='I275',
 DRAWING='@S9S_MB_2U_LIB.S9S_MB_2U(SCH_1):PAGE207',
 PHYS_PAGE='218',
 XY='(-4625,1625)',
 ROT='0',
 VER='2',
 PACK_TYPE='0402LF',
 CDS_LIB='pure_quanta',
 CDS_PART_NAME='Q_RES_0402LF-10K,1%,1/16W,CHIPA',
 WATTAGE='1/16W',
 TOLERANCE='1%',
 MATERIAL='CHIP',
 VALUE='10K',
 PRIM_FILE='./archive_libs/logical/q_res/chips/chips.prt';

PART_NAME
 R1843 'Q_RES_0402LF-33.2,1%,1/16W,CHIA':;

SECTION_NUMBER 1
 '@S9S_MB_2U_LIB.S9S_MB_2U(SCH_1):PAGE211_I122@PURE_QUANTA.Q_RES(CHIPS)':
 C_PATH='@s9s_mb_2u_lib.s9s_mb_2u(sch_1):page211_i122@pure_quanta.q_res(chips)',
 P_PATH='@s9s_mb_2u_lib.s9s_mb_2u(sch_1):page222_i122@pure_quanta.q_res(chips)',
 PATH='I122',
 DRAWING='@S9S_MB_2U_LIB.S9S_MB_2U(SCH_1):PAGE211',
 PHYS_PAGE='222',
 XY='(3000,-375)',
 ROT='0',
 VER='1',
 PACK_TYPE='0402LF',
 CDS_LIB='pure_quanta',
 CDS_PART_NAME='Q_RES_0402LF-33.2,1%,1/16W,CHIA',
 WATTAGE='1/16W',
 TOLERANCE='1%',
 MATERIAL='CHIP',
 VALUE='33.2',
 PRIM_FILE='./archive_libs/logical/q_res/chips/chips.prt';

PART_NAME
 R1844 'Q_RES_0402LF-33.2,1%,1/16W,CHIA':;

SECTION_NUMBER 1
 '@S9S_MB_2U_LIB.S9S_MB_2U(SCH_1):PAGE211_I123@PURE_QUANTA.Q_RES(CHIPS)':
 C_PATH='@s9s_mb_2u_lib.s9s_mb_2u(sch_1):page211_i123@pure_quanta.q_res(chips)',
 P_PATH='@s9s_mb_2u_lib.s9s_mb_2u(sch_1):page222_i123@pure_quanta.q_res(chips)',
 PATH='I123',
 DRAWING='@S9S_MB_2U_LIB.S9S_MB_2U(SCH_1):PAGE211',
 PHYS_PAGE='222',
 XY='(3000,-600)',
 ROT='0',
 VER='1',
 PACK_TYPE='0402LF',
 CDS_LIB='pure_quanta',
 CDS_PART_NAME='Q_RES_0402LF-33.2,1%,1/16W,CHIA',
 WATTAGE='1/16W',
 TOLERANCE='1%',
 MATERIAL='CHIP',
 VALUE='33.2',
 PRIM_FILE='./archive_libs/logical/q_res/chips/chips.prt';

PART_NAME
 R1853 'Q_RES_0402LF-0,5%,1/16W,CHIP,CA':;

SECTION_NUMBER 1
 '@S9S_MB_2U_LIB.S9S_MB_2U(SCH_1):PAGE314_I138@PURE_QUANTA.Q_RES(CHIPS)':
 C_PATH='@s9s_mb_2u_lib.s9s_mb_2u(sch_1):page314_i138@pure_quanta.q_res(chips)',
 P_PATH='@s9s_mb_2u_lib.s9s_mb_2u(sch_1):page213_i138@pure_quanta.q_res(chips)',
 PATH='I138',
 DRAWING='@S9S_MB_2U_LIB.S9S_MB_2U(SCH_1):PAGE314',
 PHYS_PAGE='213',
 XY='(2725,575)',
 ROT='0',
 VER='1',
 PACK_TYPE='0402LF',
 CDS_LIB='pure_quanta',
 CDS_PART_NAME='Q_RES_0402LF-0,5%,1/16W,CHIP,CA',
 WATTAGE='1/16W',
 TOLERANCE='5%',
 MATERIAL='CHIP',
 VALUE='0',
 PRIM_FILE='./archive_libs/logical/q_res/chips/chips.prt';

PART_NAME
 R1854 'Q_RES_0402LF-10K,1%,1/16W,CHIPA':;

SECTION_NUMBER 1
 '@S9S_MB_2U_LIB.S9S_MB_2U(SCH_1):PAGE229_I2@PURE_QUANTA.Q_RES(CHIPS)':
 C_PATH='@s9s_mb_2u_lib.s9s_mb_2u(sch_1):page229_i2@pure_quanta.q_res(chips)',
 P_PATH='@s9s_mb_2u_lib.s9s_mb_2u(sch_1):page242_i2@pure_quanta.q_res(chips)',
 PATH='I2',
 DRAWING='@S9S_MB_2U_LIB.S9S_MB_2U(SCH_1):PAGE229',
 PHYS_PAGE='242',
 XY='(-3350,0)',
 ROT='2',
 VER='2',
 PACK_TYPE='0402LF',
 CDS_LIB='pure_quanta',
 CDS_PART_NAME='Q_RES_0402LF-10K,1%,1/16W,CHIPA',
 WATTAGE='1/16W',
 TOLERANCE='1%',
 MATERIAL='CHIP',
 VALUE='10K',
 PRIM_FILE='./archive_libs/logical/q_res/chips/chips.prt';

PART_NAME
 R1856 'Q_RES_0402LF-100,1%,1/16W,CHIPA':;

SECTION_NUMBER 1
 '@S9S_MB_2U_LIB.S9S_MB_2U(SCH_1):PAGE229_I3@PURE_QUANTA.Q_RES(CHIPS)':
 C_PATH='@s9s_mb_2u_lib.s9s_mb_2u(sch_1):page229_i3@pure_quanta.q_res(chips)',
 P_PATH='@s9s_mb_2u_lib.s9s_mb_2u(sch_1):page242_i3@pure_quanta.q_res(chips)',
 PATH='I3',
 DRAWING='@S9S_MB_2U_LIB.S9S_MB_2U(SCH_1):PAGE229',
 PHYS_PAGE='242',
 XY='(-2400,-225)',
 ROT='0',
 VER='1',
 PACK_TYPE='0402LF',
 CDS_LIB='pure_quanta',
 CDS_PART_NAME='Q_RES_0402LF-100,1%,1/16W,CHIPA',
 WATTAGE='1/16W',
 TOLERANCE='1%',
 MATERIAL='CHIP',
 VALUE='100',
 PRIM_FILE='./archive_libs/logical/q_res/chips/chips.prt';

PART_NAME
 R1857 'Q_RES_0402LF-10K,1%,1/16W,CHIPA':;

SECTION_NUMBER 1
 '@S9S_MB_2U_LIB.S9S_MB_2U(SCH_1):PAGE229_I18@PURE_QUANTA.Q_RES(CHIPS)':
 C_PATH='@s9s_mb_2u_lib.s9s_mb_2u(sch_1):page229_i18@pure_quanta.q_res(chips)',
 P_PATH='@s9s_mb_2u_lib.s9s_mb_2u(sch_1):page242_i18@pure_quanta.q_res(chips)',
 PATH='I18',
 DRAWING='@S9S_MB_2U_LIB.S9S_MB_2U(SCH_1):PAGE229',
 PHYS_PAGE='242',
 XY='(-3125,1150)',
 ROT='0',
 VER='2',
 PACK_TYPE='0402LF',
 CDS_LIB='pure_quanta',
 CDS_PART_NAME='Q_RES_0402LF-10K,1%,1/16W,CHIPA',
 WATTAGE='1/16W',
 TOLERANCE='1%',
 MATERIAL='CHIP',
 VALUE='10K',
 PRIM_FILE='./archive_libs/logical/q_res/chips/chips.prt';

PART_NAME
 R1868 'Q_RES_0402LF-10,1%,1/16W,CHIP,A':;

SECTION_NUMBER 1
 '@S9S_MB_2U_LIB.S9S_MB_2U(SCH_1):PAGE190_I96@PURE_QUANTA.Q_RES(CHIPS)':
 C_PATH='@s9s_mb_2u_lib.s9s_mb_2u(sch_1):page190_i96@pure_quanta.q_res(chips)',
 P_PATH='@s9s_mb_2u_lib.s9s_mb_2u(sch_1):page202_i96@pure_quanta.q_res(chips)',
 PATH='I96',
 DRAWING='@S9S_MB_2U_LIB.S9S_MB_2U(SCH_1):PAGE190',
 PHYS_PAGE='202',
 XY='(-650,-50)',
 ROT='0',
 VER='1',
 PACK_TYPE='0402LF',
 LOCATION='R1868',
 CDS_LIB='pure_quanta',
 CDS_PART_NAME='Q_RES_0402LF-10,1%,1/16W,CHIP,A',
 WATTAGE='1/16W',
 TOLERANCE='1%',
 MATERIAL='CHIP',
 VALUE='10',
 PRIM_FILE='./archive_libs/logical/q_res/chips/chips.prt';

PART_NAME
 R1869 'Q_RES_0402LF-10,1%,1/16W,CHIP,A':;

SECTION_NUMBER 1
 '@S9S_MB_2U_LIB.S9S_MB_2U(SCH_1):PAGE190_I97@PURE_QUANTA.Q_RES(CHIPS)':
 C_PATH='@s9s_mb_2u_lib.s9s_mb_2u(sch_1):page190_i97@pure_quanta.q_res(chips)',
 P_PATH='@s9s_mb_2u_lib.s9s_mb_2u(sch_1):page202_i97@pure_quanta.q_res(chips)',
 PATH='I97',
 DRAWING='@S9S_MB_2U_LIB.S9S_MB_2U(SCH_1):PAGE190',
 PHYS_PAGE='202',
 XY='(-650,-100)',
 ROT='0',
 VER='1',
 PACK_TYPE='0402LF',
 LOCATION='R1869',
 CDS_LIB='pure_quanta',
 CDS_PART_NAME='Q_RES_0402LF-10,1%,1/16W,CHIP,A',
 WATTAGE='1/16W',
 TOLERANCE='1%',
 MATERIAL='CHIP',
 VALUE='10',
 PRIM_FILE='./archive_libs/logical/q_res/chips/chips.prt';

PART_NAME
 R1870 'Q_RES_0402LF-10,1%,1/16W,CHIP,A':;

SECTION_NUMBER 1
 '@S9S_MB_2U_LIB.S9S_MB_2U(SCH_1):PAGE190_I98@PURE_QUANTA.Q_RES(CHIPS)':
 C_PATH='@s9s_mb_2u_lib.s9s_mb_2u(sch_1):page190_i98@pure_quanta.q_res(chips)',
 P_PATH='@s9s_mb_2u_lib.s9s_mb_2u(sch_1):page202_i98@pure_quanta.q_res(chips)',
 PATH='I98',
 DRAWING='@S9S_MB_2U_LIB.S9S_MB_2U(SCH_1):PAGE190',
 PHYS_PAGE='202',
 XY='(-650,-150)',
 ROT='0',
 VER='1',
 PACK_TYPE='0402LF',
 LOCATION='R1870',
 CDS_LIB='pure_quanta',
 CDS_PART_NAME='Q_RES_0402LF-10,1%,1/16W,CHIP,A',
 WATTAGE='1/16W',
 TOLERANCE='1%',
 MATERIAL='CHIP',
 VALUE='10',
 PRIM_FILE='./archive_libs/logical/q_res/chips/chips.prt';

PART_NAME
 R1871 'Q_RES_0402LF-10,1%,1/16W,CHIP,A':;

SECTION_NUMBER 1
 '@S9S_MB_2U_LIB.S9S_MB_2U(SCH_1):PAGE190_I99@PURE_QUANTA.Q_RES(CHIPS)':
 C_PATH='@s9s_mb_2u_lib.s9s_mb_2u(sch_1):page190_i99@pure_quanta.q_res(chips)',
 P_PATH='@s9s_mb_2u_lib.s9s_mb_2u(sch_1):page202_i99@pure_quanta.q_res(chips)',
 PATH='I99',
 DRAWING='@S9S_MB_2U_LIB.S9S_MB_2U(SCH_1):PAGE190',
 PHYS_PAGE='202',
 XY='(-650,-200)',
 ROT='0',
 VER='1',
 PACK_TYPE='0402LF',
 LOCATION='R1871',
 CDS_LIB='pure_quanta',
 CDS_PART_NAME='Q_RES_0402LF-10,1%,1/16W,CHIP,A',
 WATTAGE='1/16W',
 TOLERANCE='1%',
 MATERIAL='CHIP',
 VALUE='10',
 PRIM_FILE='./archive_libs/logical/q_res/chips/chips.prt';

PART_NAME
 R1872 'Q_RES_0402LF-10,1%,1/16W,CHIP,A':;

SECTION_NUMBER 1
 '@S9S_MB_2U_LIB.S9S_MB_2U(SCH_1):PAGE190_I100@PURE_QUANTA.Q_RES(CHIPS)':
 C_PATH='@s9s_mb_2u_lib.s9s_mb_2u(sch_1):page190_i100@pure_quanta.q_res(chips)',
 P_PATH='@s9s_mb_2u_lib.s9s_mb_2u(sch_1):page202_i100@pure_quanta.q_res(chips)',
 PATH='I100',
 DRAWING='@S9S_MB_2U_LIB.S9S_MB_2U(SCH_1):PAGE190',
 PHYS_PAGE='202',
 XY='(-650,-250)',
 ROT='0',
 VER='1',
 PACK_TYPE='0402LF',
 LOCATION='R1872',
 CDS_LIB='pure_quanta',
 CDS_PART_NAME='Q_RES_0402LF-10,1%,1/16W,CHIP,A',
 WATTAGE='1/16W',
 TOLERANCE='1%',
 MATERIAL='CHIP',
 VALUE='10',
 PRIM_FILE='./archive_libs/logical/q_res/chips/chips.prt';

PART_NAME
 R1895 'Q_RES_0402LF-100,1%,1/16W,CHIPA':;

SECTION_NUMBER 1
 '@S9S_MB_2U_LIB.S9S_MB_2U(SCH_1):PAGE150_I149@PURE_QUANTA.Q_RES(CHIPS)':
 C_PATH='@s9s_mb_2u_lib.s9s_mb_2u(sch_1):page150_i149@pure_quanta.q_res(chips)',
 P_PATH='@s9s_mb_2u_lib.s9s_mb_2u(sch_1):page153_i149@pure_quanta.q_res(chips)',
 PATH='I149',
 DRAWING='@S9S_MB_2U_LIB.S9S_MB_2U(SCH_1):PAGE150',
 PHYS_PAGE='153',
 XY='(3100,5600)',
 ROT='0',
 VER='2',
 PACK_TYPE='0402LF',
 CDS_LIB='pure_quanta',
 CDS_PART_NAME='Q_RES_0402LF-100,1%,1/16W,CHIPA',
 WATTAGE='1/16W',
 TOLERANCE='1%',
 MATERIAL='CHIP',
 VALUE='100',
 PRIM_FILE='./archive_libs/logical/q_res/chips/chips.prt';

PART_NAME
 R1896 'Q_RES_0402LF-100,1%,1/16W,CHIPA':;

SECTION_NUMBER 1
 '@S9S_MB_2U_LIB.S9S_MB_2U(SCH_1):PAGE151_I43@PURE_QUANTA.Q_RES(CHIPS)':
 C_PATH='@s9s_mb_2u_lib.s9s_mb_2u(sch_1):page151_i43@pure_quanta.q_res(chips)',
 P_PATH='@s9s_mb_2u_lib.s9s_mb_2u(sch_1):page154_i43@pure_quanta.q_res(chips)',
 PATH='I43',
 DRAWING='@S9S_MB_2U_LIB.S9S_MB_2U(SCH_1):PAGE151',
 PHYS_PAGE='154',
 XY='(475,1825)',
 ROT='0',
 VER='2',
 PACK_TYPE='0402LF',
 CDS_LIB='pure_quanta',
 CDS_PART_NAME='Q_RES_0402LF-100,1%,1/16W,CHIPA',
 WATTAGE='1/16W',
 TOLERANCE='1%',
 MATERIAL='CHIP',
 VALUE='100',
 PRIM_FILE='./archive_libs/logical/q_res/chips/chips.prt';

PART_NAME
 R1897 'Q_RES_0402LF-100,1%,1/16W,CHIPA':;

SECTION_NUMBER 1
 '@S9S_MB_2U_LIB.S9S_MB_2U(SCH_1):PAGE151_I50@PURE_QUANTA.Q_RES(CHIPS)':
 C_PATH='@s9s_mb_2u_lib.s9s_mb_2u(sch_1):page151_i50@pure_quanta.q_res(chips)',
 P_PATH='@s9s_mb_2u_lib.s9s_mb_2u(sch_1):page154_i50@pure_quanta.q_res(chips)',
 PATH='I50',
 DRAWING='@S9S_MB_2U_LIB.S9S_MB_2U(SCH_1):PAGE151',
 PHYS_PAGE='154',
 XY='(725,1825)',
 ROT='0',
 VER='2',
 PACK_TYPE='0402LF',
 CDS_LIB='pure_quanta',
 CDS_PART_NAME='Q_RES_0402LF-100,1%,1/16W,CHIPA',
 WATTAGE='1/16W',
 TOLERANCE='1%',
 MATERIAL='CHIP',
 VALUE='100',
 PRIM_FILE='./archive_libs/logical/q_res/chips/chips.prt';

PART_NAME
 R1898 'Q_RES_0402LF-100,1%,1/16W,CHIPA':;

SECTION_NUMBER 1
 '@S9S_MB_2U_LIB.S9S_MB_2U(SCH_1):PAGE151_I52@PURE_QUANTA.Q_RES(CHIPS)':
 C_PATH='@s9s_mb_2u_lib.s9s_mb_2u(sch_1):page151_i52@pure_quanta.q_res(chips)',
 P_PATH='@s9s_mb_2u_lib.s9s_mb_2u(sch_1):page154_i52@pure_quanta.q_res(chips)',
 PATH='I52',
 DRAWING='@S9S_MB_2U_LIB.S9S_MB_2U(SCH_1):PAGE151',
 PHYS_PAGE='154',
 XY='(975,1825)',
 ROT='0',
 VER='2',
 PACK_TYPE='0402LF',
 CDS_LIB='pure_quanta',
 CDS_PART_NAME='Q_RES_0402LF-100,1%,1/16W,CHIPA',
 WATTAGE='1/16W',
 TOLERANCE='1%',
 MATERIAL='CHIP',
 VALUE='100',
 PRIM_FILE='./archive_libs/logical/q_res/chips/chips.prt';

PART_NAME
 R1905 'Q_RES_0402LF-1K,1%,1/16W,CHIP,A':;

SECTION_NUMBER 1
 '@S9S_MB_2U_LIB.S9S_MB_2U(SCH_1):PAGE153_I13@PURE_QUANTA.Q_RES(CHIPS)':
 C_PATH='@s9s_mb_2u_lib.s9s_mb_2u(sch_1):page153_i13@pure_quanta.q_res(chips)',
 P_PATH='@s9s_mb_2u_lib.s9s_mb_2u(sch_1):page156_i13@pure_quanta.q_res(chips)',
 PATH='I13',
 DRAWING='@S9S_MB_2U_LIB.S9S_MB_2U(SCH_1):PAGE153',
 PHYS_PAGE='156',
 XY='(3800,9725)',
 ROT='0',
 VER='2',
 PACK_TYPE='0402LF',
 LOCATION='R1905',
 CDS_LIB='pure_quanta',
 CDS_PART_NAME='Q_RES_0402LF-1K,1%,1/16W,CHIP,A',
 WATTAGE='1/16W',
 TOLERANCE='1%',
 MATERIAL='CHIP',
 VALUE='1K',
 PRIM_FILE='./archive_libs/logical/q_res/chips/chips.prt';

PART_NAME
 R1906 'Q_RES_0402LF-1K,1%,1/16W,CHIP,A':;

SECTION_NUMBER 1
 '@S9S_MB_2U_LIB.S9S_MB_2U(SCH_1):PAGE153_I7@PURE_QUANTA.Q_RES(CHIPS)':
 C_PATH='@s9s_mb_2u_lib.s9s_mb_2u(sch_1):page153_i7@pure_quanta.q_res(chips)',
 P_PATH='@s9s_mb_2u_lib.s9s_mb_2u(sch_1):page156_i7@pure_quanta.q_res(chips)',
 PATH='I7',
 DRAWING='@S9S_MB_2U_LIB.S9S_MB_2U(SCH_1):PAGE153',
 PHYS_PAGE='156',
 XY='(3800,8825)',
 ROT='0',
 VER='2',
 PACK_TYPE='0402LF',
 LOCATION='R1906',
 CDS_LIB='pure_quanta',
 CDS_PART_NAME='Q_RES_0402LF-1K,1%,1/16W,CHIP,A',
 WATTAGE='1/16W',
 TOLERANCE='1%',
 MATERIAL='CHIP',
 VALUE='1K',
 PRIM_FILE='./archive_libs/logical/q_res/chips/chips.prt';

PART_NAME
 R1907 'Q_RES_0402LF-1K,1%,1/16W,CHIP,A':;

SECTION_NUMBER 1
 '@S9S_MB_2U_LIB.S9S_MB_2U(SCH_1):PAGE153_I25@PURE_QUANTA.Q_RES(CHIPS)':
 C_PATH='@s9s_mb_2u_lib.s9s_mb_2u(sch_1):page153_i25@pure_quanta.q_res(chips)',
 P_PATH='@s9s_mb_2u_lib.s9s_mb_2u(sch_1):page156_i25@pure_quanta.q_res(chips)',
 PATH='I25',
 DRAWING='@S9S_MB_2U_LIB.S9S_MB_2U(SCH_1):PAGE153',
 PHYS_PAGE='156',
 XY='(4025,9725)',
 ROT='0',
 VER='2',
 PACK_TYPE='0402LF',
 LOCATION='R1907',
 CDS_LIB='pure_quanta',
 CDS_PART_NAME='Q_RES_0402LF-1K,1%,1/16W,CHIP,A',
 WATTAGE='1/16W',
 TOLERANCE='1%',
 MATERIAL='CHIP',
 VALUE='1K',
 PRIM_FILE='./archive_libs/logical/q_res/chips/chips.prt';

PART_NAME
 R1908 'Q_RES_0402LF-1K,1%,1/16W,CHIP,A':;

SECTION_NUMBER 1
 '@S9S_MB_2U_LIB.S9S_MB_2U(SCH_1):PAGE153_I22@PURE_QUANTA.Q_RES(CHIPS)':
 C_PATH='@s9s_mb_2u_lib.s9s_mb_2u(sch_1):page153_i22@pure_quanta.q_res(chips)',
 P_PATH='@s9s_mb_2u_lib.s9s_mb_2u(sch_1):page156_i22@pure_quanta.q_res(chips)',
 PATH='I22',
 DRAWING='@S9S_MB_2U_LIB.S9S_MB_2U(SCH_1):PAGE153',
 PHYS_PAGE='156',
 XY='(4025,8825)',
 ROT='0',
 VER='2',
 PACK_TYPE='0402LF',
 LOCATION='R1908',
 CDS_LIB='pure_quanta',
 CDS_PART_NAME='Q_RES_0402LF-1K,1%,1/16W,CHIP,A',
 WATTAGE='1/16W',
 TOLERANCE='1%',
 MATERIAL='CHIP',
 VALUE='1K',
 PRIM_FILE='./archive_libs/logical/q_res/chips/chips.prt';

PART_NAME
 R1919 'Q_RES_0402LF-33.2,1%,1/16W,CHIA':;

SECTION_NUMBER 1
 '@S9S_MB_2U_LIB.S9S_MB_2U(SCH_1):PAGE211_I127@PURE_QUANTA.Q_RES(CHIPS)':
 C_PATH='@s9s_mb_2u_lib.s9s_mb_2u(sch_1):page211_i127@pure_quanta.q_res(chips)',
 P_PATH='@s9s_mb_2u_lib.s9s_mb_2u(sch_1):page222_i127@pure_quanta.q_res(chips)',
 PATH='I127',
 DRAWING='@S9S_MB_2U_LIB.S9S_MB_2U(SCH_1):PAGE211',
 PHYS_PAGE='222',
 XY='(-1625,350)',
 ROT='0',
 VER='1',
 PACK_TYPE='0402LF',
 CDS_LIB='pure_quanta',
 CDS_PART_NAME='Q_RES_0402LF-33.2,1%,1/16W,CHIA',
 WATTAGE='1/16W',
 TOLERANCE='1%',
 MATERIAL='CHIP',
 VALUE='33.2',
 PRIM_FILE='./archive_libs/logical/q_res/chips/chips.prt';

PART_NAME
 R1921 'Q_RES_0402LF-33.2,1%,1/16W,CHIA':;

SECTION_NUMBER 1
 '@S9S_MB_2U_LIB.S9S_MB_2U(SCH_1):PAGE154_I132@PURE_QUANTA.Q_RES(CHIPS)':
 C_PATH='@s9s_mb_2u_lib.s9s_mb_2u(sch_1):page154_i132@pure_quanta.q_res(chips)',
 P_PATH='@s9s_mb_2u_lib.s9s_mb_2u(sch_1):page158_i132@pure_quanta.q_res(chips)',
 PATH='I132',
 DRAWING='@S9S_MB_2U_LIB.S9S_MB_2U(SCH_1):PAGE154',
 PHYS_PAGE='158',
 XY='(-2800,8200)',
 ROT='0',
 VER='1',
 PACK_TYPE='0402LF',
 CDS_LIB='pure_quanta',
 CDS_PART_NAME='Q_RES_0402LF-33.2,1%,1/16W,CHIA',
 WATTAGE='1/16W',
 TOLERANCE='1%',
 MATERIAL='CHIP',
 VALUE='33.2',
 PRIM_FILE='./archive_libs/logical/q_res/chips/chips.prt';

PART_NAME
 R1929 'Q_RES_0402LF-10K,1%,1/16W,CHIPA':;

SECTION_NUMBER 1
 '@S9S_MB_2U_LIB.S9S_MB_2U(SCH_1):PAGE150_I37@PURE_QUANTA.Q_RES(CHIPS)':
 C_PATH='@s9s_mb_2u_lib.s9s_mb_2u(sch_1):page150_i37@pure_quanta.q_res(chips)',
 P_PATH='@s9s_mb_2u_lib.s9s_mb_2u(sch_1):page153_i37@pure_quanta.q_res(chips)',
 PATH='I37',
 DRAWING='@S9S_MB_2U_LIB.S9S_MB_2U(SCH_1):PAGE150',
 PHYS_PAGE='153',
 XY='(-4250,4725)',
 ROT='0',
 VER='1',
 PACK_TYPE='0402LF',
 CDS_LIB='pure_quanta',
 CDS_PART_NAME='Q_RES_0402LF-10K,1%,1/16W,CHIPA',
 WATTAGE='1/16W',
 TOLERANCE='1%',
 MATERIAL='CHIP',
 VALUE='10K',
 PRIM_FILE='./archive_libs/logical/q_res/chips/chips.prt';

PART_NAME
 R1930 'Q_RES_0402LF-10K,1%,1/16W,CHIPA':;

SECTION_NUMBER 1
 '@S9S_MB_2U_LIB.S9S_MB_2U(SCH_1):PAGE150_I36@PURE_QUANTA.Q_RES(CHIPS)':
 C_PATH='@s9s_mb_2u_lib.s9s_mb_2u(sch_1):page150_i36@pure_quanta.q_res(chips)',
 P_PATH='@s9s_mb_2u_lib.s9s_mb_2u(sch_1):page153_i36@pure_quanta.q_res(chips)',
 PATH='I36',
 DRAWING='@S9S_MB_2U_LIB.S9S_MB_2U(SCH_1):PAGE150',
 PHYS_PAGE='153',
 XY='(-4250,4625)',
 ROT='0',
 VER='1',
 PACK_TYPE='0402LF',
 CDS_LIB='pure_quanta',
 CDS_PART_NAME='Q_RES_0402LF-10K,1%,1/16W,CHIPA',
 WATTAGE='1/16W',
 TOLERANCE='1%',
 MATERIAL='CHIP',
 VALUE='10K',
 PRIM_FILE='./archive_libs/logical/q_res/chips/chips.prt';

PART_NAME
 R1932 'Q_RES_0402LF-33.2,1%,1/16W,CHIA':;

SECTION_NUMBER 1
 '@S9S_MB_2U_LIB.S9S_MB_2U(SCH_1):PAGE14_I109@PURE_QUANTA.Q_RES(CHIPS)':
 C_PATH='@s9s_mb_2u_lib.s9s_mb_2u(sch_1):page14_i109@pure_quanta.q_res(chips)',
 P_PATH='@s9s_mb_2u_lib.s9s_mb_2u(sch_1):page14_i109@pure_quanta.q_res(chips)',
 PATH='I109',
 DRAWING='@S9S_MB_2U_LIB.S9S_MB_2U(SCH_1):PAGE14',
 PHYS_PAGE='14',
 XY='(-3075,4300)',
 ROT='0',
 VER='1',
 PACK_TYPE='0402LF',
 CDS_LIB='pure_quanta',
 CDS_PART_NAME='Q_RES_0402LF-33.2,1%,1/16W,CHIA',
 WATTAGE='1/16W',
 TOLERANCE='1%',
 MATERIAL='CHIP',
 VALUE='33.2',
 PRIM_FILE='./archive_libs/logical/q_res/chips/chips.prt';

PART_NAME
 R1933 'Q_RES_0402LF-33.2,1%,1/16W,CHIA':;

SECTION_NUMBER 1
 '@S9S_MB_2U_LIB.S9S_MB_2U(SCH_1):PAGE14_I110@PURE_QUANTA.Q_RES(CHIPS)':
 C_PATH='@s9s_mb_2u_lib.s9s_mb_2u(sch_1):page14_i110@pure_quanta.q_res(chips)',
 P_PATH='@s9s_mb_2u_lib.s9s_mb_2u(sch_1):page14_i110@pure_quanta.q_res(chips)',
 PATH='I110',
 DRAWING='@S9S_MB_2U_LIB.S9S_MB_2U(SCH_1):PAGE14',
 PHYS_PAGE='14',
 XY='(-3075,4250)',
 ROT='0',
 VER='1',
 PACK_TYPE='0402LF',
 CDS_LIB='pure_quanta',
 CDS_PART_NAME='Q_RES_0402LF-33.2,1%,1/16W,CHIA',
 WATTAGE='1/16W',
 TOLERANCE='1%',
 MATERIAL='CHIP',
 VALUE='33.2',
 PRIM_FILE='./archive_libs/logical/q_res/chips/chips.prt';

PART_NAME
 R1934 'Q_RES_0402LF-33.2,1%,1/16W,CHIA':;

SECTION_NUMBER 1
 '@S9S_MB_2U_LIB.S9S_MB_2U(SCH_1):PAGE45_I81@PURE_QUANTA.Q_RES(CHIPS)':
 C_PATH='@s9s_mb_2u_lib.s9s_mb_2u(sch_1):page45_i81@pure_quanta.q_res(chips)',
 P_PATH='@s9s_mb_2u_lib.s9s_mb_2u(sch_1):page45_i81@pure_quanta.q_res(chips)',
 PATH='I81',
 DRAWING='@S9S_MB_2U_LIB.S9S_MB_2U(SCH_1):PAGE45',
 PHYS_PAGE='45',
 XY='(-8475,-875)',
 ROT='0',
 VER='1',
 PACK_TYPE='0402LF',
 CDS_LIB='pure_quanta',
 CDS_PART_NAME='Q_RES_0402LF-33.2,1%,1/16W,CHIA',
 WATTAGE='1/16W',
 TOLERANCE='1%',
 MATERIAL='CHIP',
 VALUE='33.2',
 PRIM_FILE='./archive_libs/logical/q_res/chips/chips.prt';

PART_NAME
 R1935 'Q_RES_0402LF-33.2,1%,1/16W,CHIA':;

SECTION_NUMBER 1
 '@S9S_MB_2U_LIB.S9S_MB_2U(SCH_1):PAGE45_I82@PURE_QUANTA.Q_RES(CHIPS)':
 C_PATH='@s9s_mb_2u_lib.s9s_mb_2u(sch_1):page45_i82@pure_quanta.q_res(chips)',
 P_PATH='@s9s_mb_2u_lib.s9s_mb_2u(sch_1):page45_i82@pure_quanta.q_res(chips)',
 PATH='I82',
 DRAWING='@S9S_MB_2U_LIB.S9S_MB_2U(SCH_1):PAGE45',
 PHYS_PAGE='45',
 XY='(-8475,-925)',
 ROT='0',
 VER='1',
 PACK_TYPE='0402LF',
 CDS_LIB='pure_quanta',
 CDS_PART_NAME='Q_RES_0402LF-33.2,1%,1/16W,CHIA',
 WATTAGE='1/16W',
 TOLERANCE='1%',
 MATERIAL='CHIP',
 VALUE='33.2',
 PRIM_FILE='./archive_libs/logical/q_res/chips/chips.prt';

PART_NAME
 R1944 'Q_RES_0402LF-0,5%,1/16W,CHIP,CA':;

SECTION_NUMBER 1
 '@S9S_MB_2U_LIB.S9S_MB_2U(SCH_1):PAGE312_I170@PURE_QUANTA.Q_RES(CHIPS)':
 C_PATH='@s9s_mb_2u_lib.s9s_mb_2u(sch_1):page312_i170@pure_quanta.q_res(chips)',
 P_PATH='@s9s_mb_2u_lib.s9s_mb_2u(sch_1):page215_i170@pure_quanta.q_res(chips)',
 PATH='I170',
 DRAWING='@S9S_MB_2U_LIB.S9S_MB_2U(SCH_1):PAGE312',
 PHYS_PAGE='215',
 XY='(-575,-1025)',
 ROT='0',
 VER='1',
 PACK_TYPE='0402LF',
 CDS_LIB='pure_quanta',
 CDS_PART_NAME='Q_RES_0402LF-0,5%,1/16W,CHIP,CA',
 WATTAGE='1/16W',
 TOLERANCE='5%',
 MATERIAL='CHIP',
 VALUE='0',
 PRIM_FILE='./archive_libs/logical/q_res/chips/chips.prt';

PART_NAME
 R1950 'Q_RES_0402LF-0,5%,1/16W,CHIP,CA':;

SECTION_NUMBER 1
 '@S9S_MB_2U_LIB.S9S_MB_2U(SCH_1):PAGE232_I20@PURE_QUANTA.Q_RES(CHIPS)':
 C_PATH='@s9s_mb_2u_lib.s9s_mb_2u(sch_1):page232_i20@pure_quanta.q_res(chips)',
 P_PATH='@s9s_mb_2u_lib.s9s_mb_2u(sch_1):page244_i20@pure_quanta.q_res(chips)',
 PATH='I20',
 DRAWING='@S9S_MB_2U_LIB.S9S_MB_2U(SCH_1):PAGE232',
 PHYS_PAGE='244',
 XY='(-1600,175)',
 ROT='0',
 VER='1',
 PACK_TYPE='0402LF',
 CDS_LIB='pure_quanta',
 CDS_PART_NAME='Q_RES_0402LF-0,5%,1/16W,CHIP,CA',
 WATTAGE='1/16W',
 TOLERANCE='5%',
 MATERIAL='CHIP',
 VALUE='0',
 PRIM_FILE='./archive_libs/logical/q_res/chips/chips.prt';

PART_NAME
 R1955 'Q_RES_0402LF-10K,1%,1/16W,CHIPA':;

SECTION_NUMBER 1
 '@S9S_MB_2U_LIB.S9S_MB_2U(SCH_1):PAGE192_I72@PURE_QUANTA.Q_RES(CHIPS)':
 C_PATH='@s9s_mb_2u_lib.s9s_mb_2u(sch_1):page192_i72@pure_quanta.q_res(chips)',
 P_PATH='@s9s_mb_2u_lib.s9s_mb_2u(sch_1):page204_i72@pure_quanta.q_res(chips)',
 PATH='I72',
 DRAWING='@S9S_MB_2U_LIB.S9S_MB_2U(SCH_1):PAGE192',
 PHYS_PAGE='204',
 XY='(1150,2625)',
 ROT='0',
 VER='1',
 PACK_TYPE='0402LF',
 CDS_LIB='pure_quanta',
 CDS_PART_NAME='Q_RES_0402LF-10K,1%,1/16W,CHIPA',
 WATTAGE='1/16W',
 TOLERANCE='1%',
 MATERIAL='CHIP',
 VALUE='10K',
 PRIM_FILE='./archive_libs/logical/q_res/chips/chips.prt';

PART_NAME
 R1958 'Q_RES_0402LF-10K,1%,1/16W,CHIPA':;

SECTION_NUMBER 1
 '@S9S_MB_2U_LIB.S9S_MB_2U(SCH_1):PAGE197_I303@PURE_QUANTA.Q_RES(CHIPS)':
 C_PATH='@s9s_mb_2u_lib.s9s_mb_2u(sch_1):page197_i303@pure_quanta.q_res(chips)',
 P_PATH='@s9s_mb_2u_lib.s9s_mb_2u(sch_1):page208_i303@pure_quanta.q_res(chips)',
 PATH='I303',
 DRAWING='@S9S_MB_2U_LIB.S9S_MB_2U(SCH_1):PAGE197',
 PHYS_PAGE='208',
 XY='(-4575,6750)',
 ROT='2',
 VER='2',
 PACK_TYPE='0402LF',
 CDS_LIB='pure_quanta',
 CDS_PART_NAME='Q_RES_0402LF-10K,1%,1/16W,CHIPA',
 WATTAGE='1/16W',
 TOLERANCE='1%',
 MATERIAL='CHIP',
 VALUE='10K',
 PRIM_FILE='./archive_libs/logical/q_res/chips/chips.prt';

PART_NAME
 R1959 'Q_RES_0402LF-0,5%,1/16W,CHIP,CA':;

SECTION_NUMBER 1
 '@S9S_MB_2U_LIB.S9S_MB_2U(SCH_1):PAGE14_I115@PURE_QUANTA.Q_RES(CHIPS)':
 C_PATH='@s9s_mb_2u_lib.s9s_mb_2u(sch_1):page14_i115@pure_quanta.q_res(chips)',
 P_PATH='@s9s_mb_2u_lib.s9s_mb_2u(sch_1):page14_i115@pure_quanta.q_res(chips)',
 PATH='I115',
 DRAWING='@S9S_MB_2U_LIB.S9S_MB_2U(SCH_1):PAGE14',
 PHYS_PAGE='14',
 XY='(-1600,1425)',
 ROT='0',
 VER='1',
 PACK_TYPE='0402LF',
 CDS_LIB='pure_quanta',
 CDS_PART_NAME='Q_RES_0402LF-0,5%,1/16W,CHIP,CA',
 WATTAGE='1/16W',
 TOLERANCE='5%',
 MATERIAL='CHIP',
 VALUE='0',
 PRIM_FILE='./archive_libs/logical/q_res/chips/chips.prt';

PART_NAME
 R1960 'Q_RES_0402LF-0,5%,1/16W,CHIP,CA':;

SECTION_NUMBER 1
 '@S9S_MB_2U_LIB.S9S_MB_2U(SCH_1):PAGE14_I117@PURE_QUANTA.Q_RES(CHIPS)':
 C_PATH='@s9s_mb_2u_lib.s9s_mb_2u(sch_1):page14_i117@pure_quanta.q_res(chips)',
 P_PATH='@s9s_mb_2u_lib.s9s_mb_2u(sch_1):page14_i117@pure_quanta.q_res(chips)',
 PATH='I117',
 DRAWING='@S9S_MB_2U_LIB.S9S_MB_2U(SCH_1):PAGE14',
 PHYS_PAGE='14',
 XY='(-1600,750)',
 ROT='0',
 VER='1',
 PACK_TYPE='0402LF',
 CDS_LIB='pure_quanta',
 CDS_PART_NAME='Q_RES_0402LF-0,5%,1/16W,CHIP,CA',
 WATTAGE='1/16W',
 TOLERANCE='5%',
 MATERIAL='CHIP',
 VALUE='0',
 PRIM_FILE='./archive_libs/logical/q_res/chips/chips.prt';

PART_NAME
 R1961 'Q_RES_0402LF-10K,1%,1/16W,CHIPA':;

SECTION_NUMBER 1
 '@S9S_MB_2U_LIB.S9S_MB_2U(SCH_1):PAGE190_I70@PURE_QUANTA.Q_RES(CHIPS)':
 C_PATH='@s9s_mb_2u_lib.s9s_mb_2u(sch_1):page190_i70@pure_quanta.q_res(chips)',
 P_PATH='@s9s_mb_2u_lib.s9s_mb_2u(sch_1):page202_i70@pure_quanta.q_res(chips)',
 PATH='I70',
 DRAWING='@S9S_MB_2U_LIB.S9S_MB_2U(SCH_1):PAGE190',
 PHYS_PAGE='202',
 XY='(-800,550)',
 ROT='2',
 VER='2',
 PACK_TYPE='0402LF',
 CDS_LIB='pure_quanta',
 CDS_PART_NAME='Q_RES_0402LF-10K,1%,1/16W,CHIPA',
 WATTAGE='1/16W',
 TOLERANCE='1%',
 MATERIAL='CHIP',
 VALUE='10K',
 PRIM_FILE='./archive_libs/logical/q_res/chips/chips.prt';

PART_NAME
 R1962 'Q_RES_0402LF-20K,1%,1/16W,EMPTA':;

SECTION_NUMBER 1
 '@S9S_MB_2U_LIB.S9S_MB_2U(SCH_1):PAGE186_I90@PURE_QUANTA.Q_RES(CHIPS)':
 C_PATH='@s9s_mb_2u_lib.s9s_mb_2u(sch_1):page186_i90@pure_quanta.q_res(chips)',
 P_PATH='@s9s_mb_2u_lib.s9s_mb_2u(sch_1):page198_i90@pure_quanta.q_res(chips)',
 PATH='I90',
 DRAWING='@S9S_MB_2U_LIB.S9S_MB_2U(SCH_1):PAGE186',
 PHYS_PAGE='198',
 XY='(2825,2800)',
 ROT='0',
 VER='2',
 PACK_TYPE='0402LF',
 CDS_LIB='pure_quanta',
 CDS_PART_NAME='Q_RES_0402LF-20K,1%,1/16W,EMPTA',
 WATTAGE='1/16W',
 TOLERANCE='1%',
 MATERIAL='EMPTY',
 VALUE='20K',
 PRIM_FILE='./archive_libs/logical/q_res/chips/chips.prt';

PART_NAME
 R1995 'Q_RES_0402LF-33.2,1%,1/16W,CHIA':;

SECTION_NUMBER 1
 '@S9S_MB_2U_LIB.S9S_MB_2U(SCH_1):PAGE212_I86@PURE_QUANTA.Q_RES(CHIPS)':
 C_PATH='@s9s_mb_2u_lib.s9s_mb_2u(sch_1):page212_i86@pure_quanta.q_res(chips)',
 P_PATH='@s9s_mb_2u_lib.s9s_mb_2u(sch_1):page223_i86@pure_quanta.q_res(chips)',
 PATH='I86',
 DRAWING='@S9S_MB_2U_LIB.S9S_MB_2U(SCH_1):PAGE212',
 PHYS_PAGE='223',
 XY='(-2800,3350)',
 ROT='0',
 VER='1',
 PACK_TYPE='0402LF',
 CDS_LIB='pure_quanta',
 CDS_PART_NAME='Q_RES_0402LF-33.2,1%,1/16W,CHIA',
 WATTAGE='1/16W',
 TOLERANCE='1%',
 MATERIAL='CHIP',
 VALUE='33.2',
 PRIM_FILE='./archive_libs/logical/q_res/chips/chips.prt';

PART_NAME
 R1996 'Q_RES_0402LF-33.2,1%,1/16W,CHIA':;

SECTION_NUMBER 1
 '@S9S_MB_2U_LIB.S9S_MB_2U(SCH_1):PAGE212_I87@PURE_QUANTA.Q_RES(CHIPS)':
 C_PATH='@s9s_mb_2u_lib.s9s_mb_2u(sch_1):page212_i87@pure_quanta.q_res(chips)',
 P_PATH='@s9s_mb_2u_lib.s9s_mb_2u(sch_1):page223_i87@pure_quanta.q_res(chips)',
 PATH='I87',
 DRAWING='@S9S_MB_2U_LIB.S9S_MB_2U(SCH_1):PAGE212',
 PHYS_PAGE='223',
 XY='(-2800,3150)',
 ROT='0',
 VER='1',
 PACK_TYPE='0402LF',
 CDS_LIB='pure_quanta',
 CDS_PART_NAME='Q_RES_0402LF-33.2,1%,1/16W,CHIA',
 WATTAGE='1/16W',
 TOLERANCE='1%',
 MATERIAL='CHIP',
 VALUE='33.2',
 PRIM_FILE='./archive_libs/logical/q_res/chips/chips.prt';

PART_NAME
 R2071 'Q_RES_0402LF-0,5%,1/16W,EMPTY,A':;

SECTION_NUMBER 1
 '@S9S_MB_2U_LIB.S9S_MB_2U(SCH_1):PAGE314_I137@PURE_QUANTA.Q_RES(CHIPS)':
 C_PATH='@s9s_mb_2u_lib.s9s_mb_2u(sch_1):page314_i137@pure_quanta.q_res(chips)',
 P_PATH='@s9s_mb_2u_lib.s9s_mb_2u(sch_1):page213_i137@pure_quanta.q_res(chips)',
 PATH='I137',
 DRAWING='@S9S_MB_2U_LIB.S9S_MB_2U(SCH_1):PAGE314',
 PHYS_PAGE='213',
 XY='(2725,450)',
 ROT='0',
 VER='1',
 PACK_TYPE='0402LF',
 CDS_LIB='pure_quanta',
 CDS_PART_NAME='Q_RES_0402LF-0,5%,1/16W,EMPTY,A',
 WATTAGE='1/16W',
 TOLERANCE='5%',
 MATERIAL='EMPTY',
 VALUE='0',
 PRIM_FILE='./archive_libs/logical/q_res/chips/chips.prt';

PART_NAME
 R2113 'Q_RES_0402LF-33.2,1%,1/16W,CHIA':;

SECTION_NUMBER 1
 '@S9S_MB_2U_LIB.S9S_MB_2U(SCH_1):PAGE182_I344@PURE_QUANTA.Q_RES(CHIPS)':
 C_PATH='@s9s_mb_2u_lib.s9s_mb_2u(sch_1):page182_i344@pure_quanta.q_res(chips)',
 P_PATH='@s9s_mb_2u_lib.s9s_mb_2u(sch_1):page190_i344@pure_quanta.q_res(chips)',
 PATH='I344',
 DRAWING='@S9S_MB_2U_LIB.S9S_MB_2U(SCH_1):PAGE182',
 PHYS_PAGE='190',
 XY='(11150,-450)',
 ROT='0',
 VER='1',
 PACK_TYPE='0402LF',
 LOCATION='R2113',
 CDS_LIB='pure_quanta',
 CDS_PART_NAME='Q_RES_0402LF-33.2,1%,1/16W,CHIA',
 WATTAGE='1/16W',
 TOLERANCE='1%',
 MATERIAL='CHIP',
 VALUE='33.2',
 PRIM_FILE='./archive_libs/logical/q_res/chips/chips.prt';

PART_NAME
 R2114 'Q_RES_0402LF-0,5%,1/16W,CHIP,CA':;

SECTION_NUMBER 1
 '@S9S_MB_2U_LIB.S9S_MB_2U(SCH_1):PAGE297_I302@PURE_QUANTA.Q_RES(CHIPS)':
 C_PATH='@s9s_mb_2u_lib.s9s_mb_2u(sch_1):page297_i302@pure_quanta.q_res(chips)',
 P_PATH='@s9s_mb_2u_lib.s9s_mb_2u(sch_1):page191_i302@pure_quanta.q_res(chips)',
 PATH='I302',
 DRAWING='@S9S_MB_2U_LIB.S9S_MB_2U(SCH_1):PAGE297',
 PHYS_PAGE='191',
 XY='(1750,-650)',
 ROT='0',
 VER='1',
 PACK_TYPE='0402LF',
 CDS_LIB='pure_quanta',
 CDS_PART_NAME='Q_RES_0402LF-0,5%,1/16W,CHIP,CA',
 WATTAGE='1/16W',
 TOLERANCE='5%',
 MATERIAL='CHIP',
 VALUE='0',
 PRIM_FILE='./archive_libs/logical/q_res/chips/chips.prt';

PART_NAME
 R2121 'Q_RES_0402LF-4.7K,5%,1/16W,CHIA':;

SECTION_NUMBER 1
 '@S9S_MB_2U_LIB.S9S_MB_2U(SCH_1):PAGE182_I337@PURE_QUANTA.Q_RES(CHIPS)':
 C_PATH='@s9s_mb_2u_lib.s9s_mb_2u(sch_1):page182_i337@pure_quanta.q_res(chips)',
 P_PATH='@s9s_mb_2u_lib.s9s_mb_2u(sch_1):page190_i337@pure_quanta.q_res(chips)',
 PATH='I337',
 DRAWING='@S9S_MB_2U_LIB.S9S_MB_2U(SCH_1):PAGE182',
 PHYS_PAGE='190',
 XY='(10725,-250)',
 ROT='0',
 VER='2',
 PACK_TYPE='0402LF',
 CDS_LIB='pure_quanta',
 CDS_PART_NAME='Q_RES_0402LF-4.7K,5%,1/16W,CHIA',
 WATTAGE='1/16W',
 TOLERANCE='5%',
 MATERIAL='CHIP',
 VALUE='4.7K',
 PRIM_FILE='./archive_libs/logical/q_res/chips/chips.prt';

PART_NAME
 R2125 'Q_RES_0402LF-4.7K,5%,1/16W,CHIA':;

SECTION_NUMBER 1
 '@S9S_MB_2U_LIB.S9S_MB_2U(SCH_1):PAGE297_I296@PURE_QUANTA.Q_RES(CHIPS)':
 C_PATH='@s9s_mb_2u_lib.s9s_mb_2u(sch_1):page297_i296@pure_quanta.q_res(chips)',
 P_PATH='@s9s_mb_2u_lib.s9s_mb_2u(sch_1):page191_i296@pure_quanta.q_res(chips)',
 PATH='I296',
 DRAWING='@S9S_MB_2U_LIB.S9S_MB_2U(SCH_1):PAGE297',
 PHYS_PAGE='191',
 XY='(3050,-200)',
 ROT='0',
 VER='2',
 PACK_TYPE='0402LF',
 CDS_LIB='pure_quanta',
 CDS_PART_NAME='Q_RES_0402LF-4.7K,5%,1/16W,CHIA',
 WATTAGE='1/16W',
 TOLERANCE='5%',
 MATERIAL='CHIP',
 VALUE='4.7K',
 PRIM_FILE='./archive_libs/logical/q_res/chips/chips.prt';

PART_NAME
 R2132 'Q_RES_0402LF-0,5%,1/16W,EMPTY,A':;

SECTION_NUMBER 1
 '@S9S_MB_2U_LIB.S9S_MB_2U(SCH_1):PAGE190_I91@PURE_QUANTA.Q_RES(CHIPS)':
 C_PATH='@s9s_mb_2u_lib.s9s_mb_2u(sch_1):page190_i91@pure_quanta.q_res(chips)',
 P_PATH='@s9s_mb_2u_lib.s9s_mb_2u(sch_1):page202_i91@pure_quanta.q_res(chips)',
 PATH='I91',
 DRAWING='@S9S_MB_2U_LIB.S9S_MB_2U(SCH_1):PAGE190',
 PHYS_PAGE='202',
 XY='(-100,1075)',
 ROT='0',
 VER='1',
 PACK_TYPE='0402LF',
 CDS_LIB='pure_quanta',
 CDS_PART_NAME='Q_RES_0402LF-0,5%,1/16W,EMPTY,A',
 WATTAGE='1/16W',
 TOLERANCE='5%',
 MATERIAL='EMPTY',
 VALUE='0',
 PRIM_FILE='./archive_libs/logical/q_res/chips/chips.prt';

PART_NAME
 R2133 'Q_RES_0402LF-1K,1%,1/16W,CHIP,A':;

SECTION_NUMBER 1
 '@S9S_MB_2U_LIB.S9S_MB_2U(SCH_1):PAGE189_I86@PURE_QUANTA.Q_RES(CHIPS)':
 C_PATH='@s9s_mb_2u_lib.s9s_mb_2u(sch_1):page189_i86@pure_quanta.q_res(chips)',
 P_PATH='@s9s_mb_2u_lib.s9s_mb_2u(sch_1):page201_i86@pure_quanta.q_res(chips)',
 PATH='I86',
 DRAWING='@S9S_MB_2U_LIB.S9S_MB_2U(SCH_1):PAGE189',
 PHYS_PAGE='201',
 XY='(-350,3700)',
 ROT='0',
 VER='1',
 PACK_TYPE='0402LF',
 CDS_LIB='pure_quanta',
 CDS_PART_NAME='Q_RES_0402LF-1K,1%,1/16W,CHIP,A',
 WATTAGE='1/16W',
 TOLERANCE='1%',
 MATERIAL='CHIP',
 VALUE='1K',
 PRIM_FILE='./archive_libs/logical/q_res/chips/chips.prt';

PART_NAME
 R2134 'Q_RES_0402LF-10K,1%,1/16W,CHIPA':;

SECTION_NUMBER 1
 '@S9S_MB_2U_LIB.S9S_MB_2U(SCH_1):PAGE189_I109@PURE_QUANTA.Q_RES(CHIPS)':
 C_PATH='@s9s_mb_2u_lib.s9s_mb_2u(sch_1):page189_i109@pure_quanta.q_res(chips)',
 P_PATH='@s9s_mb_2u_lib.s9s_mb_2u(sch_1):page201_i109@pure_quanta.q_res(chips)',
 PATH='I109',
 DRAWING='@S9S_MB_2U_LIB.S9S_MB_2U(SCH_1):PAGE189',
 PHYS_PAGE='201',
 XY='(2575,3025)',
 ROT='0',
 VER='2',
 PACK_TYPE='0402LF',
 CDS_LIB='pure_quanta',
 CDS_PART_NAME='Q_RES_0402LF-10K,1%,1/16W,CHIPA',
 WATTAGE='1/16W',
 TOLERANCE='1%',
 MATERIAL='CHIP',
 VALUE='10K',
 PRIM_FILE='./archive_libs/logical/q_res/chips/chips.prt';

PART_NAME
 R2155 'Q_RES_0402LF-0,5%,1/16W,CHIP,CA':;

SECTION_NUMBER 1
 '@S9S_MB_2U_LIB.S9S_MB_2U(SCH_1):PAGE312_I177@PURE_QUANTA.Q_RES(CHIPS)':
 C_PATH='@s9s_mb_2u_lib.s9s_mb_2u(sch_1):page312_i177@pure_quanta.q_res(chips)',
 P_PATH='@s9s_mb_2u_lib.s9s_mb_2u(sch_1):page215_i177@pure_quanta.q_res(chips)',
 PATH='I177',
 DRAWING='@S9S_MB_2U_LIB.S9S_MB_2U(SCH_1):PAGE312',
 PHYS_PAGE='215',
 XY='(-575,-1400)',
 ROT='0',
 VER='1',
 PACK_TYPE='0402LF',
 CDS_LIB='pure_quanta',
 CDS_PART_NAME='Q_RES_0402LF-0,5%,1/16W,CHIP,CA',
 WATTAGE='1/16W',
 TOLERANCE='5%',
 MATERIAL='CHIP',
 VALUE='0',
 PRIM_FILE='./archive_libs/logical/q_res/chips/chips.prt';

PART_NAME
 R2204 'Q_RES_0402LF-2.2K,5%,1/16W,EMPA':;

SECTION_NUMBER 1
 '@S9S_MB_2U_LIB.S9S_MB_2U(SCH_1):PAGE219_I57@PURE_QUANTA.Q_RES(CHIPS)':
 C_PATH='@s9s_mb_2u_lib.s9s_mb_2u(sch_1):page219_i57@pure_quanta.q_res(chips)',
 P_PATH='@s9s_mb_2u_lib.s9s_mb_2u(sch_1):page231_i57@pure_quanta.q_res(chips)',
 PATH='I57',
 DRAWING='@S9S_MB_2U_LIB.S9S_MB_2U(SCH_1):PAGE219',
 PHYS_PAGE='231',
 XY='(3850,1025)',
 ROT='0',
 VER='1',
 PACK_TYPE='0402LF',
 CDS_LIB='pure_quanta',
 CDS_PART_NAME='Q_RES_0402LF-2.2K,5%,1/16W,EMPA',
 WATTAGE='1/16W',
 TOLERANCE='5%',
 MATERIAL='EMPTY',
 VALUE='2.2K',
 PRIM_FILE='./archive_libs/logical/q_res/chips/chips.prt';

PART_NAME
 R2205 'Q_RES_0402LF-2.2K,5%,1/16W,EMPA':;

SECTION_NUMBER 1
 '@S9S_MB_2U_LIB.S9S_MB_2U(SCH_1):PAGE219_I56@PURE_QUANTA.Q_RES(CHIPS)':
 C_PATH='@s9s_mb_2u_lib.s9s_mb_2u(sch_1):page219_i56@pure_quanta.q_res(chips)',
 P_PATH='@s9s_mb_2u_lib.s9s_mb_2u(sch_1):page231_i56@pure_quanta.q_res(chips)',
 PATH='I56',
 DRAWING='@S9S_MB_2U_LIB.S9S_MB_2U(SCH_1):PAGE219',
 PHYS_PAGE='231',
 XY='(3850,975)',
 ROT='0',
 VER='1',
 PACK_TYPE='0402LF',
 CDS_LIB='pure_quanta',
 CDS_PART_NAME='Q_RES_0402LF-2.2K,5%,1/16W,EMPA',
 WATTAGE='1/16W',
 TOLERANCE='5%',
 MATERIAL='EMPTY',
 VALUE='2.2K',
 PRIM_FILE='./archive_libs/logical/q_res/chips/chips.prt';

PART_NAME
 R2208 'Q_RES_0402LF-0,5%,1/16W,CHIP,CA':;

SECTION_NUMBER 1
 '@S9S_MB_2U_LIB.S9S_MB_2U(SCH_1):PAGE224_I62@PURE_QUANTA.Q_RES(CHIPS)':
 C_PATH='@s9s_mb_2u_lib.s9s_mb_2u(sch_1):page224_i62@pure_quanta.q_res(chips)',
 P_PATH='@s9s_mb_2u_lib.s9s_mb_2u(sch_1):page236_i62@pure_quanta.q_res(chips)',
 PATH='I62',
 DRAWING='@S9S_MB_2U_LIB.S9S_MB_2U(SCH_1):PAGE224',
 PHYS_PAGE='236',
 XY='(1475,8850)',
 ROT='0',
 VER='1',
 PACK_TYPE='0402LF',
 CDS_LIB='pure_quanta',
 CDS_PART_NAME='Q_RES_0402LF-0,5%,1/16W,CHIP,CA',
 WATTAGE='1/16W',
 TOLERANCE='5%',
 MATERIAL='CHIP',
 VALUE='0',
 PRIM_FILE='./archive_libs/logical/q_res/chips/chips.prt';

PART_NAME
 R2209 'Q_RES_0402LF-0,5%,1/16W,CHIP,CA':;

SECTION_NUMBER 1
 '@S9S_MB_2U_LIB.S9S_MB_2U(SCH_1):PAGE224_I63@PURE_QUANTA.Q_RES(CHIPS)':
 C_PATH='@s9s_mb_2u_lib.s9s_mb_2u(sch_1):page224_i63@pure_quanta.q_res(chips)',
 P_PATH='@s9s_mb_2u_lib.s9s_mb_2u(sch_1):page236_i63@pure_quanta.q_res(chips)',
 PATH='I63',
 DRAWING='@S9S_MB_2U_LIB.S9S_MB_2U(SCH_1):PAGE224',
 PHYS_PAGE='236',
 XY='(1475,8900)',
 ROT='0',
 VER='1',
 PACK_TYPE='0402LF',
 CDS_LIB='pure_quanta',
 CDS_PART_NAME='Q_RES_0402LF-0,5%,1/16W,CHIP,CA',
 WATTAGE='1/16W',
 TOLERANCE='5%',
 MATERIAL='CHIP',
 VALUE='0',
 PRIM_FILE='./archive_libs/logical/q_res/chips/chips.prt';

PART_NAME
 R2210 'Q_RES_0402LF-0,5%,1/16W,CHIP,CA':;

SECTION_NUMBER 1
 '@S9S_MB_2U_LIB.S9S_MB_2U(SCH_1):PAGE224_I64@PURE_QUANTA.Q_RES(CHIPS)':
 C_PATH='@s9s_mb_2u_lib.s9s_mb_2u(sch_1):page224_i64@pure_quanta.q_res(chips)',
 P_PATH='@s9s_mb_2u_lib.s9s_mb_2u(sch_1):page236_i64@pure_quanta.q_res(chips)',
 PATH='I64',
 DRAWING='@S9S_MB_2U_LIB.S9S_MB_2U(SCH_1):PAGE224',
 PHYS_PAGE='236',
 XY='(1475,8550)',
 ROT='0',
 VER='1',
 PACK_TYPE='0402LF',
 CDS_LIB='pure_quanta',
 CDS_PART_NAME='Q_RES_0402LF-0,5%,1/16W,CHIP,CA',
 WATTAGE='1/16W',
 TOLERANCE='5%',
 MATERIAL='CHIP',
 VALUE='0',
 PRIM_FILE='./archive_libs/logical/q_res/chips/chips.prt';

PART_NAME
 R2211 'Q_RES_0402LF-0,5%,1/16W,CHIP,CA':;

SECTION_NUMBER 1
 '@S9S_MB_2U_LIB.S9S_MB_2U(SCH_1):PAGE224_I65@PURE_QUANTA.Q_RES(CHIPS)':
 C_PATH='@s9s_mb_2u_lib.s9s_mb_2u(sch_1):page224_i65@pure_quanta.q_res(chips)',
 P_PATH='@s9s_mb_2u_lib.s9s_mb_2u(sch_1):page236_i65@pure_quanta.q_res(chips)',
 PATH='I65',
 DRAWING='@S9S_MB_2U_LIB.S9S_MB_2U(SCH_1):PAGE224',
 PHYS_PAGE='236',
 XY='(1475,8600)',
 ROT='0',
 VER='1',
 PACK_TYPE='0402LF',
 CDS_LIB='pure_quanta',
 CDS_PART_NAME='Q_RES_0402LF-0,5%,1/16W,CHIP,CA',
 WATTAGE='1/16W',
 TOLERANCE='5%',
 MATERIAL='CHIP',
 VALUE='0',
 PRIM_FILE='./archive_libs/logical/q_res/chips/chips.prt';

PART_NAME
 R2212 'Q_RES_0402LF-2.2K,5%,1/16W,EMPA':;

SECTION_NUMBER 1
 '@S9S_MB_2U_LIB.S9S_MB_2U(SCH_1):PAGE228_I202@PURE_QUANTA.Q_RES(CHIPS)':
 C_PATH='@s9s_mb_2u_lib.s9s_mb_2u(sch_1):page228_i202@pure_quanta.q_res(chips)',
 P_PATH='@s9s_mb_2u_lib.s9s_mb_2u(sch_1):page241_i202@pure_quanta.q_res(chips)',
 PATH='I202',
 DRAWING='@S9S_MB_2U_LIB.S9S_MB_2U(SCH_1):PAGE228',
 PHYS_PAGE='241',
 XY='(5000,4075)',
 ROT='0',
 VER='1',
 PACK_TYPE='0402LF',
 CDS_LIB='pure_quanta',
 CDS_PART_NAME='Q_RES_0402LF-2.2K,5%,1/16W,EMPA',
 WATTAGE='1/16W',
 TOLERANCE='5%',
 MATERIAL='EMPTY',
 VALUE='2.2K',
 PRIM_FILE='./archive_libs/logical/q_res/chips/chips.prt';

PART_NAME
 R2213 'Q_RES_0402LF-2.2K,5%,1/16W,EMPA':;

SECTION_NUMBER 1
 '@S9S_MB_2U_LIB.S9S_MB_2U(SCH_1):PAGE228_I203@PURE_QUANTA.Q_RES(CHIPS)':
 C_PATH='@s9s_mb_2u_lib.s9s_mb_2u(sch_1):page228_i203@pure_quanta.q_res(chips)',
 P_PATH='@s9s_mb_2u_lib.s9s_mb_2u(sch_1):page241_i203@pure_quanta.q_res(chips)',
 PATH='I203',
 DRAWING='@S9S_MB_2U_LIB.S9S_MB_2U(SCH_1):PAGE228',
 PHYS_PAGE='241',
 XY='(5000,4025)',
 ROT='0',
 VER='1',
 PACK_TYPE='0402LF',
 CDS_LIB='pure_quanta',
 CDS_PART_NAME='Q_RES_0402LF-2.2K,5%,1/16W,EMPA',
 WATTAGE='1/16W',
 TOLERANCE='5%',
 MATERIAL='EMPTY',
 VALUE='2.2K',
 PRIM_FILE='./archive_libs/logical/q_res/chips/chips.prt';

PART_NAME
 R2219 'Q_RES_0402LF-26.7K,1%,1/16W,CHA':;

SECTION_NUMBER 1
 '@S9S_MB_2U_LIB.S9S_MB_2U(SCH_1):PAGE326_I100@PURE_QUANTA.Q_RES(CHIPS)':
 C_PATH='@s9s_mb_2u_lib.s9s_mb_2u(sch_1):page326_i100@pure_quanta.q_res(chips)',
 P_PATH='@s9s_mb_2u_lib.s9s_mb_2u(sch_1):page306_i100@pure_quanta.q_res(chips)',
 PATH='I100',
 DRAWING='@S9S_MB_2U_LIB.S9S_MB_2U(SCH_1):PAGE326',
 PHYS_PAGE='306',
 XY='(-525,275)',
 ROT='0',
 VER='2',
 PACK_TYPE='0402LF',
 LOCATION='R2219',
 CDS_LIB='pure_quanta',
 CDS_PART_NAME='Q_RES_0402LF-26.7K,1%,1/16W,CHA',
 WATTAGE='1/16W',
 TOLERANCE='1%',
 MATERIAL='CHIP',
 VALUE='26.7K',
 PRIM_FILE='./archive_libs/logical/q_res/chips/chips.prt';

PART_NAME
 R2221 'Q_RES_0402LF-26.7K,1%,1/16W,CHA':;

SECTION_NUMBER 1
 '@S9S_MB_2U_LIB.S9S_MB_2U(SCH_1):PAGE326_I20@PURE_QUANTA.Q_RES(CHIPS)':
 C_PATH='@s9s_mb_2u_lib.s9s_mb_2u(sch_1):page326_i20@pure_quanta.q_res(chips)',
 P_PATH='@s9s_mb_2u_lib.s9s_mb_2u(sch_1):page306_i20@pure_quanta.q_res(chips)',
 PATH='I20',
 DRAWING='@S9S_MB_2U_LIB.S9S_MB_2U(SCH_1):PAGE326',
 PHYS_PAGE='306',
 XY='(75,275)',
 ROT='0',
 VER='2',
 PACK_TYPE='0402LF',
 LOCATION='R2221',
 CDS_LIB='pure_quanta',
 CDS_PART_NAME='Q_RES_0402LF-26.7K,1%,1/16W,CHA',
 WATTAGE='1/16W',
 TOLERANCE='1%',
 MATERIAL='CHIP',
 VALUE='26.7K',
 PRIM_FILE='./archive_libs/logical/q_res/chips/chips.prt';

PART_NAME
 R2222 'Q_RES_0402LF-1K,1%,1/16W,CHIP,A':;

SECTION_NUMBER 1
 '@S9S_MB_2U_LIB.S9S_MB_2U(SCH_1):PAGE326_I17@PURE_QUANTA.Q_RES(CHIPS)':
 C_PATH='@s9s_mb_2u_lib.s9s_mb_2u(sch_1):page326_i17@pure_quanta.q_res(chips)',
 P_PATH='@s9s_mb_2u_lib.s9s_mb_2u(sch_1):page306_i17@pure_quanta.q_res(chips)',
 PATH='I17',
 DRAWING='@S9S_MB_2U_LIB.S9S_MB_2U(SCH_1):PAGE326',
 PHYS_PAGE='306',
 XY='(75,-475)',
 ROT='0',
 VER='2',
 PACK_TYPE='0402LF',
 LOCATION='R2222',
 CDS_LIB='pure_quanta',
 CDS_PART_NAME='Q_RES_0402LF-1K,1%,1/16W,CHIP,A',
 WATTAGE='1/16W',
 TOLERANCE='1%',
 MATERIAL='CHIP',
 VALUE='1K',
 PRIM_FILE='./archive_libs/logical/q_res/chips/chips.prt';

PART_NAME
 R2227 'Q_RES_0402LF-1K,1%,1/16W,CHIP,A':;

SECTION_NUMBER 1
 '@S9S_MB_2U_LIB.S9S_MB_2U(SCH_1):PAGE326_I101@PURE_QUANTA.Q_RES(CHIPS)':
 C_PATH='@s9s_mb_2u_lib.s9s_mb_2u(sch_1):page326_i101@pure_quanta.q_res(chips)',
 P_PATH='@s9s_mb_2u_lib.s9s_mb_2u(sch_1):page306_i101@pure_quanta.q_res(chips)',
 PATH='I101',
 DRAWING='@S9S_MB_2U_LIB.S9S_MB_2U(SCH_1):PAGE326',
 PHYS_PAGE='306',
 XY='(-525,-475)',
 ROT='0',
 VER='2',
 PACK_TYPE='0402LF',
 LOCATION='R2227',
 CDS_LIB='pure_quanta',
 CDS_PART_NAME='Q_RES_0402LF-1K,1%,1/16W,CHIP,A',
 WATTAGE='1/16W',
 TOLERANCE='1%',
 MATERIAL='CHIP',
 VALUE='1K',
 PRIM_FILE='./archive_libs/logical/q_res/chips/chips.prt';

PART_NAME
 R2230 'Q_RES_0402LF-10K,1%,1/16W,CHIPA':;

SECTION_NUMBER 1
 '@S9S_MB_2U_LIB.S9S_MB_2U(SCH_1):PAGE326_I39@PURE_QUANTA.Q_RES(CHIPS)':
 C_PATH='@s9s_mb_2u_lib.s9s_mb_2u(sch_1):page326_i39@pure_quanta.q_res(chips)',
 P_PATH='@s9s_mb_2u_lib.s9s_mb_2u(sch_1):page306_i39@pure_quanta.q_res(chips)',
 PATH='I39',
 DRAWING='@S9S_MB_2U_LIB.S9S_MB_2U(SCH_1):PAGE326',
 PHYS_PAGE='306',
 XY='(2400,250)',
 ROT='0',
 VER='2',
 PACK_TYPE='0402LF',
 LOCATION='R2230',
 CDS_LIB='pure_quanta',
 CDS_PART_NAME='Q_RES_0402LF-10K,1%,1/16W,CHIPA',
 WATTAGE='1/16W',
 TOLERANCE='1%',
 MATERIAL='CHIP',
 VALUE='10K',
 PRIM_FILE='./archive_libs/logical/q_res/chips/chips.prt';

PART_NAME
 R2232 'Q_RES_0402LF-10K,1%,1/16W,CHIPA':;

SECTION_NUMBER 1
 '@S9S_MB_2U_LIB.S9S_MB_2U(SCH_1):PAGE184_I75@PURE_QUANTA.Q_RES(CHIPS)':
 C_PATH='@s9s_mb_2u_lib.s9s_mb_2u(sch_1):page184_i75@pure_quanta.q_res(chips)',
 P_PATH='@s9s_mb_2u_lib.s9s_mb_2u(sch_1):page195_i75@pure_quanta.q_res(chips)',
 PATH='I75',
 DRAWING='@S9S_MB_2U_LIB.S9S_MB_2U(SCH_1):PAGE184',
 PHYS_PAGE='195',
 XY='(2425,5150)',
 ROT='0',
 VER='2',
 PACK_TYPE='0402LF',
 CDS_LIB='pure_quanta',
 CDS_PART_NAME='Q_RES_0402LF-10K,1%,1/16W,CHIPA',
 WATTAGE='1/16W',
 TOLERANCE='1%',
 MATERIAL='CHIP',
 VALUE='10K',
 PRIM_FILE='./archive_libs/logical/q_res/chips/chips.prt';

PART_NAME
 R2233 'Q_RES_0402LF-10K,1%,1/16W,CHIPA':;

SECTION_NUMBER 1
 '@S9S_MB_2U_LIB.S9S_MB_2U(SCH_1):PAGE326_I41@PURE_QUANTA.Q_RES(CHIPS)':
 C_PATH='@s9s_mb_2u_lib.s9s_mb_2u(sch_1):page326_i41@pure_quanta.q_res(chips)',
 P_PATH='@s9s_mb_2u_lib.s9s_mb_2u(sch_1):page306_i41@pure_quanta.q_res(chips)',
 PATH='I41',
 DRAWING='@S9S_MB_2U_LIB.S9S_MB_2U(SCH_1):PAGE326',
 PHYS_PAGE='306',
 XY='(2675,250)',
 ROT='0',
 VER='2',
 PACK_TYPE='0402LF',
 LOCATION='R2233',
 CDS_LIB='pure_quanta',
 CDS_PART_NAME='Q_RES_0402LF-10K,1%,1/16W,CHIPA',
 WATTAGE='1/16W',
 TOLERANCE='1%',
 MATERIAL='CHIP',
 VALUE='10K',
 PRIM_FILE='./archive_libs/logical/q_res/chips/chips.prt';

PART_NAME
 R2234 'Q_RES_0402LF-10K,1%,1/16W,EMPTA':;

SECTION_NUMBER 1
 '@S9S_MB_2U_LIB.S9S_MB_2U(SCH_1):PAGE184_I12@PURE_QUANTA.Q_RES(CHIPS)':
 C_PATH='@s9s_mb_2u_lib.s9s_mb_2u(sch_1):page184_i12@pure_quanta.q_res(chips)',
 P_PATH='@s9s_mb_2u_lib.s9s_mb_2u(sch_1):page195_i12@pure_quanta.q_res(chips)',
 PATH='I12',
 DRAWING='@S9S_MB_2U_LIB.S9S_MB_2U(SCH_1):PAGE184',
 PHYS_PAGE='195',
 XY='(-1225,5225)',
 ROT='0',
 VER='2',
 PACK_TYPE='0402LF',
 CDS_LIB='pure_quanta',
 CDS_PART_NAME='Q_RES_0402LF-10K,1%,1/16W,EMPTA',
 WATTAGE='1/16W',
 TOLERANCE='1%',
 MATERIAL='EMPTY',
 VALUE='10K',
 PRIM_FILE='./archive_libs/logical/q_res/chips/chips.prt';

PART_NAME
 R2235 'Q_RES_0402LF-1K,1%,1/16W,CHIP,A':;

SECTION_NUMBER 1
 '@S9S_MB_2U_LIB.S9S_MB_2U(SCH_1):PAGE184_I9@PURE_QUANTA.Q_RES(CHIPS)':
 C_PATH='@s9s_mb_2u_lib.s9s_mb_2u(sch_1):page184_i9@pure_quanta.q_res(chips)',
 P_PATH='@s9s_mb_2u_lib.s9s_mb_2u(sch_1):page195_i9@pure_quanta.q_res(chips)',
 PATH='I9',
 DRAWING='@S9S_MB_2U_LIB.S9S_MB_2U(SCH_1):PAGE184',
 PHYS_PAGE='195',
 XY='(-1225,4400)',
 ROT='0',
 VER='2',
 PACK_TYPE='0402LF',
 CDS_LIB='pure_quanta',
 CDS_PART_NAME='Q_RES_0402LF-1K,1%,1/16W,CHIP,A',
 WATTAGE='1/16W',
 TOLERANCE='1%',
 MATERIAL='CHIP',
 VALUE='1K',
 PRIM_FILE='./archive_libs/logical/q_res/chips/chips.prt';

PART_NAME
 R2236 'Q_RES_0402LF-100K,1%,1/16W,EMPA':;

SECTION_NUMBER 1
 '@S9S_MB_2U_LIB.S9S_MB_2U(SCH_1):PAGE326_I7@PURE_QUANTA.Q_RES(CHIPS)':
 C_PATH='@s9s_mb_2u_lib.s9s_mb_2u(sch_1):page326_i7@pure_quanta.q_res(chips)',
 P_PATH='@s9s_mb_2u_lib.s9s_mb_2u(sch_1):page306_i7@pure_quanta.q_res(chips)',
 PATH='I7',
 DRAWING='@S9S_MB_2U_LIB.S9S_MB_2U(SCH_1):PAGE326',
 PHYS_PAGE='306',
 XY='(-2575,-875)',
 ROT='0',
 VER='2',
 PACK_TYPE='0402LF',
 LOCATION='R2236',
 CDS_LIB='pure_quanta',
 CDS_PART_NAME='Q_RES_0402LF-100K,1%,1/16W,EMPA',
 WATTAGE='1/16W',
 TOLERANCE='1%',
 MATERIAL='EMPTY',
 VALUE='100K',
 PRIM_FILE='./archive_libs/logical/q_res/chips/chips.prt';

PART_NAME
 R2238 'Q_RES_0402LF-4.99K,1%,1/16W,EMA':;

SECTION_NUMBER 1
 '@S9S_MB_2U_LIB.S9S_MB_2U(SCH_1):PAGE326_I2@PURE_QUANTA.Q_RES(CHIPS)':
 C_PATH='@s9s_mb_2u_lib.s9s_mb_2u(sch_1):page326_i2@pure_quanta.q_res(chips)',
 P_PATH='@s9s_mb_2u_lib.s9s_mb_2u(sch_1):page306_i2@pure_quanta.q_res(chips)',
 PATH='I2',
 DRAWING='@S9S_MB_2U_LIB.S9S_MB_2U(SCH_1):PAGE326',
 PHYS_PAGE='306',
 XY='(-2575,-1275)',
 ROT='0',
 VER='2',
 PACK_TYPE='0402LF',
 CDS_LIB='pure_quanta',
 CDS_PART_NAME='Q_RES_0402LF-4.99K,1%,1/16W,EMA',
 WATTAGE='1/16W',
 TOLERANCE='1%',
 MATERIAL='EMPTY',
 VALUE='4.99K',
 PRIM_FILE='./archive_libs/logical/q_res/chips/chips.prt';

PART_NAME
 R2240 'Q_RES_0402LF-10K,1%,1/16W,EMPTA':;

SECTION_NUMBER 1
 '@S9S_MB_2U_LIB.S9S_MB_2U(SCH_1):PAGE184_I49@PURE_QUANTA.Q_RES(CHIPS)':
 C_PATH='@s9s_mb_2u_lib.s9s_mb_2u(sch_1):page184_i49@pure_quanta.q_res(chips)',
 P_PATH='@s9s_mb_2u_lib.s9s_mb_2u(sch_1):page195_i49@pure_quanta.q_res(chips)',
 PATH='I49',
 DRAWING='@S9S_MB_2U_LIB.S9S_MB_2U(SCH_1):PAGE184',
 PHYS_PAGE='195',
 XY='(-400,5225)',
 ROT='0',
 VER='2',
 PACK_TYPE='0402LF',
 CDS_LIB='pure_quanta',
 CDS_PART_NAME='Q_RES_0402LF-10K,1%,1/16W,EMPTA',
 WATTAGE='1/16W',
 TOLERANCE='1%',
 MATERIAL='EMPTY',
 VALUE='10K',
 PRIM_FILE='./archive_libs/logical/q_res/chips/chips.prt';

PART_NAME
 R2241 'Q_RES_0402LF-1K,1%,1/16W,CHIP,A':;

SECTION_NUMBER 1
 '@S9S_MB_2U_LIB.S9S_MB_2U(SCH_1):PAGE184_I28@PURE_QUANTA.Q_RES(CHIPS)':
 C_PATH='@s9s_mb_2u_lib.s9s_mb_2u(sch_1):page184_i28@pure_quanta.q_res(chips)',
 P_PATH='@s9s_mb_2u_lib.s9s_mb_2u(sch_1):page195_i28@pure_quanta.q_res(chips)',
 PATH='I28',
 DRAWING='@S9S_MB_2U_LIB.S9S_MB_2U(SCH_1):PAGE184',
 PHYS_PAGE='195',
 XY='(-400,4400)',
 ROT='0',
 VER='2',
 PACK_TYPE='0402LF',
 CDS_LIB='pure_quanta',
 CDS_PART_NAME='Q_RES_0402LF-1K,1%,1/16W,CHIP,A',
 WATTAGE='1/16W',
 TOLERANCE='1%',
 MATERIAL='CHIP',
 VALUE='1K',
 PRIM_FILE='./archive_libs/logical/q_res/chips/chips.prt';

PART_NAME
 R2242 'Q_RES_0402LF-10K,1%,1/16W,EMPTA':;

SECTION_NUMBER 1
 '@S9S_MB_2U_LIB.S9S_MB_2U(SCH_1):PAGE184_I50@PURE_QUANTA.Q_RES(CHIPS)':
 C_PATH='@s9s_mb_2u_lib.s9s_mb_2u(sch_1):page184_i50@pure_quanta.q_res(chips)',
 P_PATH='@s9s_mb_2u_lib.s9s_mb_2u(sch_1):page195_i50@pure_quanta.q_res(chips)',
 PATH='I50',
 DRAWING='@S9S_MB_2U_LIB.S9S_MB_2U(SCH_1):PAGE184',
 PHYS_PAGE='195',
 XY='(-125,5225)',
 ROT='0',
 VER='2',
 PACK_TYPE='0402LF',
 CDS_LIB='pure_quanta',
 CDS_PART_NAME='Q_RES_0402LF-10K,1%,1/16W,EMPTA',
 WATTAGE='1/16W',
 TOLERANCE='1%',
 MATERIAL='EMPTY',
 VALUE='10K',
 PRIM_FILE='./archive_libs/logical/q_res/chips/chips.prt';

PART_NAME
 R2243 'Q_RES_0402LF-1K,1%,1/16W,CHIP,A':;

SECTION_NUMBER 1
 '@S9S_MB_2U_LIB.S9S_MB_2U(SCH_1):PAGE184_I30@PURE_QUANTA.Q_RES(CHIPS)':
 C_PATH='@s9s_mb_2u_lib.s9s_mb_2u(sch_1):page184_i30@pure_quanta.q_res(chips)',
 P_PATH='@s9s_mb_2u_lib.s9s_mb_2u(sch_1):page195_i30@pure_quanta.q_res(chips)',
 PATH='I30',
 DRAWING='@S9S_MB_2U_LIB.S9S_MB_2U(SCH_1):PAGE184',
 PHYS_PAGE='195',
 XY='(-125,4400)',
 ROT='0',
 VER='2',
 PACK_TYPE='0402LF',
 CDS_LIB='pure_quanta',
 CDS_PART_NAME='Q_RES_0402LF-1K,1%,1/16W,CHIP,A',
 WATTAGE='1/16W',
 TOLERANCE='1%',
 MATERIAL='CHIP',
 VALUE='1K',
 PRIM_FILE='./archive_libs/logical/q_res/chips/chips.prt';

PART_NAME
 R2244 'Q_RES_0402LF-10K,1%,1/16W,CHIPA':;

SECTION_NUMBER 1
 '@S9S_MB_2U_LIB.S9S_MB_2U(SCH_1):PAGE209_I39@PURE_QUANTA.Q_RES(CHIPS)':
 C_PATH='@s9s_mb_2u_lib.s9s_mb_2u(sch_1):page209_i39@pure_quanta.q_res(chips)',
 P_PATH='@s9s_mb_2u_lib.s9s_mb_2u(sch_1):page220_i39@pure_quanta.q_res(chips)',
 PATH='I39',
 DRAWING='@S9S_MB_2U_LIB.S9S_MB_2U(SCH_1):PAGE209',
 PHYS_PAGE='220',
 XY='(1775,-475)',
 ROT='0',
 VER='1',
 PACK_TYPE='0402LF',
 CDS_LIB='pure_quanta',
 CDS_PART_NAME='Q_RES_0402LF-10K,1%,1/16W,CHIPA',
 WATTAGE='1/16W',
 TOLERANCE='1%',
 MATERIAL='CHIP',
 VALUE='10K',
 PRIM_FILE='./archive_libs/logical/q_res/chips/chips.prt';

PART_NAME
 R2252 'Q_RES_0402LF-100K,1%,1/16W,EMPA':;

SECTION_NUMBER 1
 '@S9S_MB_2U_LIB.S9S_MB_2U(SCH_1):PAGE185_I42@PURE_QUANTA.Q_RES(CHIPS)':
 C_PATH='@s9s_mb_2u_lib.s9s_mb_2u(sch_1):page185_i42@pure_quanta.q_res(chips)',
 P_PATH='@s9s_mb_2u_lib.s9s_mb_2u(sch_1):page197_i42@pure_quanta.q_res(chips)',
 PATH='I42',
 DRAWING='@S9S_MB_2U_LIB.S9S_MB_2U(SCH_1):PAGE185',
 PHYS_PAGE='197',
 XY='(-4675,3825)',
 ROT='0',
 VER='2',
 PACK_TYPE='0402LF',
 CDS_LIB='pure_quanta',
 CDS_PART_NAME='Q_RES_0402LF-100K,1%,1/16W,EMPA',
 WATTAGE='1/16W',
 TOLERANCE='1%',
 MATERIAL='EMPTY',
 VALUE='100K',
 PRIM_FILE='./archive_libs/logical/q_res/chips/chips.prt';

PART_NAME
 R2253 'Q_RES_0402LF-4.75K,1%,1/16W,CHA':;

SECTION_NUMBER 1
 '@S9S_MB_2U_LIB.S9S_MB_2U(SCH_1):PAGE185_I39@PURE_QUANTA.Q_RES(CHIPS)':
 C_PATH='@s9s_mb_2u_lib.s9s_mb_2u(sch_1):page185_i39@pure_quanta.q_res(chips)',
 P_PATH='@s9s_mb_2u_lib.s9s_mb_2u(sch_1):page197_i39@pure_quanta.q_res(chips)',
 PATH='I39',
 DRAWING='@S9S_MB_2U_LIB.S9S_MB_2U(SCH_1):PAGE185',
 PHYS_PAGE='197',
 XY='(-4625,4350)',
 ROT='0',
 VER='2',
 PACK_TYPE='0402LF',
 CDS_LIB='pure_quanta',
 CDS_PART_NAME='Q_RES_0402LF-4.75K,1%,1/16W,CHA',
 WATTAGE='1/16W',
 TOLERANCE='1%',
 MATERIAL='CHIP',
 VALUE='4.75K',
 PRIM_FILE='./archive_libs/logical/q_res/chips/chips.prt';

PART_NAME
 R2255 'Q_RES_0402LF-0,5%,1/16W,CHIP,CA':;

SECTION_NUMBER 1
 '@S9S_MB_2U_LIB.S9S_MB_2U(SCH_1):PAGE185_I41@PURE_QUANTA.Q_RES(CHIPS)':
 C_PATH='@s9s_mb_2u_lib.s9s_mb_2u(sch_1):page185_i41@pure_quanta.q_res(chips)',
 P_PATH='@s9s_mb_2u_lib.s9s_mb_2u(sch_1):page197_i41@pure_quanta.q_res(chips)',
 PATH='I41',
 DRAWING='@S9S_MB_2U_LIB.S9S_MB_2U(SCH_1):PAGE185',
 PHYS_PAGE='197',
 XY='(-3675,4075)',
 ROT='0',
 VER='1',
 PACK_TYPE='0402LF',
 CDS_LIB='pure_quanta',
 CDS_PART_NAME='Q_RES_0402LF-0,5%,1/16W,CHIP,CA',
 WATTAGE='1/16W',
 TOLERANCE='5%',
 MATERIAL='CHIP',
 VALUE='0',
 PRIM_FILE='./archive_libs/logical/q_res/chips/chips.prt';

PART_NAME
 R2256 'Q_RES_0402LF-0,5%,1/16W,EMPTY,A':;

SECTION_NUMBER 1
 '@S9S_MB_2U_LIB.S9S_MB_2U(SCH_1):PAGE227_I167@PURE_QUANTA.Q_RES(CHIPS)':
 C_PATH='@s9s_mb_2u_lib.s9s_mb_2u(sch_1):page227_i167@pure_quanta.q_res(chips)',
 P_PATH='@s9s_mb_2u_lib.s9s_mb_2u(sch_1):page240_i167@pure_quanta.q_res(chips)',
 PATH='I167',
 DRAWING='@S9S_MB_2U_LIB.S9S_MB_2U(SCH_1):PAGE227',
 PHYS_PAGE='240',
 XY='(-8175,1825)',
 ROT='0',
 VER='1',
 PACK_TYPE='0402LF',
 CDS_LIB='pure_quanta',
 CDS_PART_NAME='Q_RES_0402LF-0,5%,1/16W,EMPTY,A',
 WATTAGE='1/16W',
 TOLERANCE='5%',
 MATERIAL='EMPTY',
 VALUE='0',
 PRIM_FILE='./archive_libs/logical/q_res/chips/chips.prt';

PART_NAME
 R2257 'Q_RES_0402LF-0,5%,1/16W,EMPTY,A':;

SECTION_NUMBER 1
 '@S9S_MB_2U_LIB.S9S_MB_2U(SCH_1):PAGE227_I164@PURE_QUANTA.Q_RES(CHIPS)':
 C_PATH='@s9s_mb_2u_lib.s9s_mb_2u(sch_1):page227_i164@pure_quanta.q_res(chips)',
 P_PATH='@s9s_mb_2u_lib.s9s_mb_2u(sch_1):page240_i164@pure_quanta.q_res(chips)',
 PATH='I164',
 DRAWING='@S9S_MB_2U_LIB.S9S_MB_2U(SCH_1):PAGE227',
 PHYS_PAGE='240',
 XY='(-8175,1775)',
 ROT='0',
 VER='1',
 PACK_TYPE='0402LF',
 CDS_LIB='pure_quanta',
 CDS_PART_NAME='Q_RES_0402LF-0,5%,1/16W,EMPTY,A',
 WATTAGE='1/16W',
 TOLERANCE='5%',
 MATERIAL='EMPTY',
 VALUE='0',
 PRIM_FILE='./archive_libs/logical/q_res/chips/chips.prt';

PART_NAME
 R2268 'Q_RES_0402LF-0,5%,1/16W,CHIP,CA':;

SECTION_NUMBER 1
 '@S9S_MB_2U_LIB.S9S_MB_2U(SCH_1):PAGE219_I41@PURE_QUANTA.Q_RES(CHIPS)':
 C_PATH='@s9s_mb_2u_lib.s9s_mb_2u(sch_1):page219_i41@pure_quanta.q_res(chips)',
 P_PATH='@s9s_mb_2u_lib.s9s_mb_2u(sch_1):page231_i41@pure_quanta.q_res(chips)',
 PATH='I41',
 DRAWING='@S9S_MB_2U_LIB.S9S_MB_2U(SCH_1):PAGE219',
 PHYS_PAGE='231',
 XY='(500,2875)',
 ROT='0',
 VER='1',
 PACK_TYPE='0402LF',
 CDS_LIB='pure_quanta',
 CDS_PART_NAME='Q_RES_0402LF-0,5%,1/16W,CHIP,CA',
 WATTAGE='1/16W',
 TOLERANCE='5%',
 MATERIAL='CHIP',
 VALUE='0',
 PRIM_FILE='./archive_libs/logical/q_res/chips/chips.prt';

PART_NAME
 R2282 'Q_RES_0402LF-10K,1%,1/16W,CHIPA':;

SECTION_NUMBER 1
 '@S9S_MB_2U_LIB.S9S_MB_2U(SCH_1):PAGE297_I169@PURE_QUANTA.Q_RES(CHIPS)':
 C_PATH='@s9s_mb_2u_lib.s9s_mb_2u(sch_1):page297_i169@pure_quanta.q_res(chips)',
 P_PATH='@s9s_mb_2u_lib.s9s_mb_2u(sch_1):page191_i169@pure_quanta.q_res(chips)',
 PATH='I169',
 DRAWING='@S9S_MB_2U_LIB.S9S_MB_2U(SCH_1):PAGE297',
 PHYS_PAGE='191',
 XY='(2675,1800)',
 ROT='0',
 VER='2',
 PACK_TYPE='0402LF',
 CDS_LIB='pure_quanta',
 CDS_PART_NAME='Q_RES_0402LF-10K,1%,1/16W,CHIPA',
 WATTAGE='1/16W',
 TOLERANCE='1%',
 MATERIAL='CHIP',
 VALUE='10K',
 PRIM_FILE='./archive_libs/logical/q_res/chips/chips.prt';

PART_NAME
 R2287 'Q_RES_0402LF-10K,1%,1/16W,CHIPA':;

SECTION_NUMBER 1
 '@S9S_MB_2U_LIB.S9S_MB_2U(SCH_1):PAGE297_I313@PURE_QUANTA.Q_RES(CHIPS)':
 C_PATH='@s9s_mb_2u_lib.s9s_mb_2u(sch_1):page297_i313@pure_quanta.q_res(chips)',
 P_PATH='@s9s_mb_2u_lib.s9s_mb_2u(sch_1):page191_i313@pure_quanta.q_res(chips)',
 PATH='I313',
 DRAWING='@S9S_MB_2U_LIB.S9S_MB_2U(SCH_1):PAGE297',
 PHYS_PAGE='191',
 XY='(3775,4650)',
 ROT='0',
 VER='2',
 PACK_TYPE='0402LF',
 LOCATION='R2287',
 CDS_LIB='pure_quanta',
 CDS_PART_NAME='Q_RES_0402LF-10K,1%,1/16W,CHIPA',
 WATTAGE='1/16W',
 TOLERANCE='1%',
 MATERIAL='CHIP',
 VALUE='10K',
 PRIM_FILE='./archive_libs/logical/q_res/chips/chips.prt';

PART_NAME
 R2296 'Q_RES_0402LF-1K,1%,1/16W,CHIP,A':;

SECTION_NUMBER 1
 '@S9S_MB_2U_LIB.S9S_MB_2U(SCH_1):PAGE297_I293@PURE_QUANTA.Q_RES(CHIPS)':
 C_PATH='@s9s_mb_2u_lib.s9s_mb_2u(sch_1):page297_i293@pure_quanta.q_res(chips)',
 P_PATH='@s9s_mb_2u_lib.s9s_mb_2u(sch_1):page191_i293@pure_quanta.q_res(chips)',
 PATH='I293',
 DRAWING='@S9S_MB_2U_LIB.S9S_MB_2U(SCH_1):PAGE297',
 PHYS_PAGE='191',
 XY='(-3475,2950)',
 ROT='0',
 VER='2',
 PACK_TYPE='0402LF',
 LOCATION='R2296',
 CDS_LIB='pure_quanta',
 CDS_PART_NAME='Q_RES_0402LF-1K,1%,1/16W,CHIP,A',
 WATTAGE='1/16W',
 TOLERANCE='1%',
 MATERIAL='CHIP',
 VALUE='1K',
 PRIM_FILE='./archive_libs/logical/q_res/chips/chips.prt';

PART_NAME
 R2304 'Q_RES_0402LF-10K,1%,1/16W,CHIPA':;

SECTION_NUMBER 1
 '@S9S_MB_2U_LIB.S9S_MB_2U(SCH_1):PAGE297_I159@PURE_QUANTA.Q_RES(CHIPS)':
 C_PATH='@s9s_mb_2u_lib.s9s_mb_2u(sch_1):page297_i159@pure_quanta.q_res(chips)',
 P_PATH='@s9s_mb_2u_lib.s9s_mb_2u(sch_1):page191_i159@pure_quanta.q_res(chips)',
 PATH='I159',
 DRAWING='@S9S_MB_2U_LIB.S9S_MB_2U(SCH_1):PAGE297',
 PHYS_PAGE='191',
 XY='(1800,1525)',
 ROT='2',
 VER='2',
 PACK_TYPE='0402LF',
 CDS_LIB='pure_quanta',
 CDS_PART_NAME='Q_RES_0402LF-10K,1%,1/16W,CHIPA',
 WATTAGE='1/16W',
 TOLERANCE='1%',
 MATERIAL='CHIP',
 VALUE='10K',
 PRIM_FILE='./archive_libs/logical/q_res/chips/chips.prt';

PART_NAME
 R2308 'Q_RES_0402LF-10K,1%,1/16W,EMPTA':;

SECTION_NUMBER 1
 '@S9S_MB_2U_LIB.S9S_MB_2U(SCH_1):PAGE224_I84@PURE_QUANTA.Q_RES(CHIPS)':
 C_PATH='@s9s_mb_2u_lib.s9s_mb_2u(sch_1):page224_i84@pure_quanta.q_res(chips)',
 P_PATH='@s9s_mb_2u_lib.s9s_mb_2u(sch_1):page236_i84@pure_quanta.q_res(chips)',
 PATH='I84',
 DRAWING='@S9S_MB_2U_LIB.S9S_MB_2U(SCH_1):PAGE224',
 PHYS_PAGE='236',
 XY='(-4350,8100)',
 ROT='0',
 VER='2',
 PACK_TYPE='0402LF',
 CDS_LIB='pure_quanta',
 CDS_PART_NAME='Q_RES_0402LF-10K,1%,1/16W,EMPTA',
 WATTAGE='1/16W',
 TOLERANCE='1%',
 MATERIAL='EMPTY',
 VALUE='10K',
 PRIM_FILE='./archive_libs/logical/q_res/chips/chips.prt';

PART_NAME
 R2309 'Q_RES_0402LF-1K,1%,1/16W,CHIP,A':;

SECTION_NUMBER 1
 '@S9S_MB_2U_LIB.S9S_MB_2U(SCH_1):PAGE224_I85@PURE_QUANTA.Q_RES(CHIPS)':
 C_PATH='@s9s_mb_2u_lib.s9s_mb_2u(sch_1):page224_i85@pure_quanta.q_res(chips)',
 P_PATH='@s9s_mb_2u_lib.s9s_mb_2u(sch_1):page236_i85@pure_quanta.q_res(chips)',
 PATH='I85',
 DRAWING='@S9S_MB_2U_LIB.S9S_MB_2U(SCH_1):PAGE224',
 PHYS_PAGE='236',
 XY='(-4350,7450)',
 ROT='0',
 VER='2',
 PACK_TYPE='0402LF',
 CDS_LIB='pure_quanta',
 CDS_PART_NAME='Q_RES_0402LF-1K,1%,1/16W,CHIP,A',
 WATTAGE='1/16W',
 TOLERANCE='1%',
 MATERIAL='CHIP',
 VALUE='1K',
 PRIM_FILE='./archive_libs/logical/q_res/chips/chips.prt';

PART_NAME
 R2310 'Q_RES_0402LF-10K,1%,1/16W,EMPTA':;

SECTION_NUMBER 1
 '@S9S_MB_2U_LIB.S9S_MB_2U(SCH_1):PAGE224_I83@PURE_QUANTA.Q_RES(CHIPS)':
 C_PATH='@s9s_mb_2u_lib.s9s_mb_2u(sch_1):page224_i83@pure_quanta.q_res(chips)',
 P_PATH='@s9s_mb_2u_lib.s9s_mb_2u(sch_1):page236_i83@pure_quanta.q_res(chips)',
 PATH='I83',
 DRAWING='@S9S_MB_2U_LIB.S9S_MB_2U(SCH_1):PAGE224',
 PHYS_PAGE='236',
 XY='(-4100,8100)',
 ROT='0',
 VER='2',
 PACK_TYPE='0402LF',
 CDS_LIB='pure_quanta',
 CDS_PART_NAME='Q_RES_0402LF-10K,1%,1/16W,EMPTA',
 WATTAGE='1/16W',
 TOLERANCE='1%',
 MATERIAL='EMPTY',
 VALUE='10K',
 PRIM_FILE='./archive_libs/logical/q_res/chips/chips.prt';

PART_NAME
 R2311 'Q_RES_0402LF-1K,1%,1/16W,CHIP,A':;

SECTION_NUMBER 1
 '@S9S_MB_2U_LIB.S9S_MB_2U(SCH_1):PAGE224_I86@PURE_QUANTA.Q_RES(CHIPS)':
 C_PATH='@s9s_mb_2u_lib.s9s_mb_2u(sch_1):page224_i86@pure_quanta.q_res(chips)',
 P_PATH='@s9s_mb_2u_lib.s9s_mb_2u(sch_1):page236_i86@pure_quanta.q_res(chips)',
 PATH='I86',
 DRAWING='@S9S_MB_2U_LIB.S9S_MB_2U(SCH_1):PAGE224',
 PHYS_PAGE='236',
 XY='(-4100,7450)',
 ROT='0',
 VER='2',
 PACK_TYPE='0402LF',
 CDS_LIB='pure_quanta',
 CDS_PART_NAME='Q_RES_0402LF-1K,1%,1/16W,CHIP,A',
 WATTAGE='1/16W',
 TOLERANCE='1%',
 MATERIAL='CHIP',
 VALUE='1K',
 PRIM_FILE='./archive_libs/logical/q_res/chips/chips.prt';

PART_NAME
 R2312 'Q_RES_0402LF-10K,1%,1/16W,CHIPA':;

SECTION_NUMBER 1
 '@S9S_MB_2U_LIB.S9S_MB_2U(SCH_1):PAGE224_I101@PURE_QUANTA.Q_RES(CHIPS)':
 C_PATH='@s9s_mb_2u_lib.s9s_mb_2u(sch_1):page224_i101@pure_quanta.q_res(chips)',
 P_PATH='@s9s_mb_2u_lib.s9s_mb_2u(sch_1):page236_i101@pure_quanta.q_res(chips)',
 PATH='I101',
 DRAWING='@S9S_MB_2U_LIB.S9S_MB_2U(SCH_1):PAGE224',
 PHYS_PAGE='236',
 XY='(-2800,9150)',
 ROT='0',
 VER='2',
 PACK_TYPE='0402LF',
 CDS_LIB='pure_quanta',
 CDS_PART_NAME='Q_RES_0402LF-10K,1%,1/16W,CHIPA',
 WATTAGE='1/16W',
 TOLERANCE='1%',
 MATERIAL='CHIP',
 VALUE='10K',
 PRIM_FILE='./archive_libs/logical/q_res/chips/chips.prt';

PART_NAME
 R2313 'Q_RES_0402LF-0,5%,1/16W,CHIP,CA':;

SECTION_NUMBER 1
 '@S9S_MB_2U_LIB.S9S_MB_2U(SCH_1):PAGE224_I97@PURE_QUANTA.Q_RES(CHIPS)':
 C_PATH='@s9s_mb_2u_lib.s9s_mb_2u(sch_1):page224_i97@pure_quanta.q_res(chips)',
 P_PATH='@s9s_mb_2u_lib.s9s_mb_2u(sch_1):page236_i97@pure_quanta.q_res(chips)',
 PATH='I97',
 DRAWING='@S9S_MB_2U_LIB.S9S_MB_2U(SCH_1):PAGE224',
 PHYS_PAGE='236',
 XY='(-1925,8700)',
 ROT='0',
 VER='1',
 PACK_TYPE='0402LF',
 CDS_LIB='pure_quanta',
 CDS_PART_NAME='Q_RES_0402LF-0,5%,1/16W,CHIP,CA',
 WATTAGE='1/16W',
 TOLERANCE='5%',
 MATERIAL='CHIP',
 VALUE='0',
 PRIM_FILE='./archive_libs/logical/q_res/chips/chips.prt';

PART_NAME
 R2315 'Q_RES_0402LF-10K,1%,1/16W,CHIPA':;

SECTION_NUMBER 1
 '@S9S_MB_2U_LIB.S9S_MB_2U(SCH_1):PAGE224_I103@PURE_QUANTA.Q_RES(CHIPS)':
 C_PATH='@s9s_mb_2u_lib.s9s_mb_2u(sch_1):page224_i103@pure_quanta.q_res(chips)',
 P_PATH='@s9s_mb_2u_lib.s9s_mb_2u(sch_1):page236_i103@pure_quanta.q_res(chips)',
 PATH='I103',
 DRAWING='@S9S_MB_2U_LIB.S9S_MB_2U(SCH_1):PAGE224',
 PHYS_PAGE='236',
 XY='(3275,9200)',
 ROT='0',
 VER='2',
 PACK_TYPE='0402LF',
 CDS_LIB='pure_quanta',
 CDS_PART_NAME='Q_RES_0402LF-10K,1%,1/16W,CHIPA',
 WATTAGE='1/16W',
 TOLERANCE='1%',
 MATERIAL='CHIP',
 VALUE='10K',
 PRIM_FILE='./archive_libs/logical/q_res/chips/chips.prt';

PART_NAME
 R2316 'Q_RES_0402LF-0,5%,1/16W,CHIP,CA':;

SECTION_NUMBER 1
 '@S9S_MB_2U_LIB.S9S_MB_2U(SCH_1):PAGE244_I28@PURE_QUANTA.Q_RES(CHIPS)':
 C_PATH='@s9s_mb_2u_lib.s9s_mb_2u(sch_1):page244_i28@pure_quanta.q_res(chips)',
 P_PATH='@s9s_mb_2u_lib.s9s_mb_2u(sch_1):page258_i28@pure_quanta.q_res(chips)',
 PATH='I28',
 DRAWING='@S9S_MB_2U_LIB.S9S_MB_2U(SCH_1):PAGE244',
 PHYS_PAGE='258',
 XY='(-2725,6700)',
 ROT='0',
 VER='1',
 PACK_TYPE='0402LF',
 LOCATION='R2316',
 CDS_LIB='pure_quanta',
 CDS_PART_NAME='Q_RES_0402LF-0,5%,1/16W,CHIP,CA',
 WATTAGE='1/16W',
 TOLERANCE='5%',
 MATERIAL='CHIP',
 VALUE='0',
 PRIM_FILE='./archive_libs/logical/q_res/chips/chips.prt';

PART_NAME
 R2317 'Q_RES_0402LF-10K,1%,1/16W,CHIPA':;

SECTION_NUMBER 1
 '@S9S_MB_2U_LIB.S9S_MB_2U(SCH_1):PAGE297_I264@PURE_QUANTA.Q_RES(CHIPS)':
 C_PATH='@s9s_mb_2u_lib.s9s_mb_2u(sch_1):page297_i264@pure_quanta.q_res(chips)',
 P_PATH='@s9s_mb_2u_lib.s9s_mb_2u(sch_1):page191_i264@pure_quanta.q_res(chips)',
 PATH='I264',
 DRAWING='@S9S_MB_2U_LIB.S9S_MB_2U(SCH_1):PAGE297',
 PHYS_PAGE='191',
 XY='(-1925,4525)',
 ROT='0',
 VER='2',
 PACK_TYPE='0402LF',
 LOCATION='R2317',
 CDS_LIB='pure_quanta',
 CDS_PART_NAME='Q_RES_0402LF-10K,1%,1/16W,CHIPA',
 WATTAGE='1/16W',
 TOLERANCE='1%',
 MATERIAL='CHIP',
 VALUE='10K',
 PRIM_FILE='./archive_libs/logical/q_res/chips/chips.prt';

PART_NAME
 R2322 'Q_RES_0402LF-49.9,1%,1/16W,EMPA':;

SECTION_NUMBER 1
 '@S9S_MB_2U_LIB.S9S_MB_2U(SCH_1):PAGE260_I36@PURE_QUANTA.Q_RES(CHIPS)':
 C_PATH='@s9s_mb_2u_lib.s9s_mb_2u(sch_1):page260_i36@pure_quanta.q_res(chips)',
 P_PATH='@s9s_mb_2u_lib.s9s_mb_2u(sch_1):page274_i36@pure_quanta.q_res(chips)',
 PATH='I36',
 DRAWING='@S9S_MB_2U_LIB.S9S_MB_2U(SCH_1):PAGE260',
 PHYS_PAGE='274',
 XY='(-10375,7325)',
 ROT='0',
 VER='1',
 PACK_TYPE='0402LF',
 LOCATION='R2322',
 CDS_LIB='pure_quanta',
 CDS_PART_NAME='Q_RES_0402LF-49.9,1%,1/16W,EMPA',
 WATTAGE='1/16W',
 TOLERANCE='1%',
 MATERIAL='EMPTY',
 VALUE='49.9',
 PRIM_FILE='./archive_libs/logical/q_res/chips/chips.prt';

PART_NAME
 R2330 'Q_RES_0402LF-0,5%,1/16W,EMPTY,A':;

SECTION_NUMBER 1
 '@S9S_MB_2U_LIB.S9S_MB_2U(SCH_1):PAGE326_I33@PURE_QUANTA.Q_RES(CHIPS)':
 C_PATH='@s9s_mb_2u_lib.s9s_mb_2u(sch_1):page326_i33@pure_quanta.q_res(chips)',
 P_PATH='@s9s_mb_2u_lib.s9s_mb_2u(sch_1):page306_i33@pure_quanta.q_res(chips)',
 PATH='I33',
 DRAWING='@S9S_MB_2U_LIB.S9S_MB_2U(SCH_1):PAGE326',
 PHYS_PAGE='306',
 XY='(925,-1375)',
 ROT='0',
 VER='1',
 PACK_TYPE='0402LF',
 LOCATION='R2330',
 CDS_LIB='pure_quanta',
 CDS_PART_NAME='Q_RES_0402LF-0,5%,1/16W,EMPTY,A',
 WATTAGE='1/16W',
 TOLERANCE='5%',
 MATERIAL='EMPTY',
 VALUE='0',
 PRIM_FILE='./archive_libs/logical/q_res/chips/chips.prt';

PART_NAME
 R2332 'Q_RES_0402LF-2K,1%,1/16W,CHIP,A':;

SECTION_NUMBER 1
 '@S9S_MB_2U_LIB.S9S_MB_2U(SCH_1):PAGE267_I14@PURE_QUANTA.Q_RES(CHIPS)':
 C_PATH='@s9s_mb_2u_lib.s9s_mb_2u(sch_1):page267_i14@pure_quanta.q_res(chips)',
 P_PATH='@s9s_mb_2u_lib.s9s_mb_2u(sch_1):page281_i14@pure_quanta.q_res(chips)',
 PATH='I14',
 DRAWING='@S9S_MB_2U_LIB.S9S_MB_2U(SCH_1):PAGE267',
 PHYS_PAGE='281',
 XY='(-10275,3400)',
 ROT='0',
 VER='2',
 PACK_TYPE='0402LF',
 LOCATION='R2332',
 CDS_LIB='pure_quanta',
 CDS_PART_NAME='Q_RES_0402LF-2K,1%,1/16W,CHIP,A',
 WATTAGE='1/16W',
 TOLERANCE='1%',
 MATERIAL='CHIP',
 VALUE='2K',
 PRIM_FILE='./archive_libs/logical/q_res/chips/chips.prt';

PART_NAME
 R2338 'Q_RES_0402LF-10K,1%,1/16W,EMPTA':;

SECTION_NUMBER 1
 '@S9S_MB_2U_LIB.S9S_MB_2U(SCH_1):PAGE268_I5@PURE_QUANTA.Q_RES(CHIPS)':
 C_PATH='@s9s_mb_2u_lib.s9s_mb_2u(sch_1):page268_i5@pure_quanta.q_res(chips)',
 P_PATH='@s9s_mb_2u_lib.s9s_mb_2u(sch_1):page282_i5@pure_quanta.q_res(chips)',
 PATH='I5',
 DRAWING='@S9S_MB_2U_LIB.S9S_MB_2U(SCH_1):PAGE268',
 PHYS_PAGE='282',
 XY='(-9600,10050)',
 ROT='0',
 VER='1',
 PACK_TYPE='0402LF',
 LOCATION='R2338',
 CDS_LIB='pure_quanta',
 CDS_PART_NAME='Q_RES_0402LF-10K,1%,1/16W,EMPTA',
 WATTAGE='1/16W',
 TOLERANCE='1%',
 MATERIAL='EMPTY',
 VALUE='10K',
 PRIM_FILE='./archive_libs/logical/q_res/chips/chips.prt';

PART_NAME
 R2339 'Q_RES_0402LF-22,5%,1/16W,CHIP,A':;

SECTION_NUMBER 1
 '@S9S_MB_2U_LIB.S9S_MB_2U(SCH_1):PAGE207_I268@PURE_QUANTA.Q_RES(CHIPS)':
 C_PATH='@s9s_mb_2u_lib.s9s_mb_2u(sch_1):page207_i268@pure_quanta.q_res(chips)',
 P_PATH='@s9s_mb_2u_lib.s9s_mb_2u(sch_1):page218_i268@pure_quanta.q_res(chips)',
 PATH='I268',
 DRAWING='@S9S_MB_2U_LIB.S9S_MB_2U(SCH_1):PAGE207',
 PHYS_PAGE='218',
 XY='(-50,950)',
 ROT='0',
 VER='1',
 PACK_TYPE='0402LF',
 CDS_LIB='pure_quanta',
 CDS_PART_NAME='Q_RES_0402LF-22,5%,1/16W,CHIP,A',
 WATTAGE='1/16W',
 TOLERANCE='5%',
 MATERIAL='CHIP',
 VALUE='22',
 PRIM_FILE='./archive_libs/logical/q_res/chips/chips.prt';

PART_NAME
 R2342 'Q_RES_0402LF-10K,1%,1/16W,CHIPA':;

SECTION_NUMBER 1
 '@S9S_MB_2U_LIB.S9S_MB_2U(SCH_1):PAGE192_I75@PURE_QUANTA.Q_RES(CHIPS)':
 C_PATH='@s9s_mb_2u_lib.s9s_mb_2u(sch_1):page192_i75@pure_quanta.q_res(chips)',
 P_PATH='@s9s_mb_2u_lib.s9s_mb_2u(sch_1):page204_i75@pure_quanta.q_res(chips)',
 PATH='I75',
 DRAWING='@S9S_MB_2U_LIB.S9S_MB_2U(SCH_1):PAGE192',
 PHYS_PAGE='204',
 XY='(-4950,925)',
 ROT='0',
 VER='1',
 PACK_TYPE='0402LF',
 CDS_LIB='pure_quanta',
 CDS_PART_NAME='Q_RES_0402LF-10K,1%,1/16W,CHIPA',
 WATTAGE='1/16W',
 TOLERANCE='1%',
 MATERIAL='CHIP',
 VALUE='10K',
 PRIM_FILE='./archive_libs/logical/q_res/chips/chips.prt';

PART_NAME
 R2343 'Q_RES_0402LF-10K,1%,1/16W,EMPTA':;

SECTION_NUMBER 1
 '@S9S_MB_2U_LIB.S9S_MB_2U(SCH_1):PAGE314_I41@PURE_QUANTA.Q_RES(CHIPS)':
 C_PATH='@s9s_mb_2u_lib.s9s_mb_2u(sch_1):page314_i41@pure_quanta.q_res(chips)',
 P_PATH='@s9s_mb_2u_lib.s9s_mb_2u(sch_1):page213_i41@pure_quanta.q_res(chips)',
 PATH='I41',
 DRAWING='@S9S_MB_2U_LIB.S9S_MB_2U(SCH_1):PAGE314',
 PHYS_PAGE='213',
 XY='(-3375,850)',
 ROT='0',
 VER='2',
 PACK_TYPE='0402LF',
 CDS_LIB='pure_quanta',
 CDS_PART_NAME='Q_RES_0402LF-10K,1%,1/16W,EMPTA',
 WATTAGE='1/16W',
 TOLERANCE='1%',
 MATERIAL='EMPTY',
 VALUE='10K',
 PRIM_FILE='./archive_libs/logical/q_res/chips/chips.prt';

PART_NAME
 R2344 'Q_RES_0402LF-4.7K,5%,1/16W,CHIA':;

SECTION_NUMBER 1
 '@S9S_MB_2U_LIB.S9S_MB_2U(SCH_1):PAGE314_I45@PURE_QUANTA.Q_RES(CHIPS)':
 C_PATH='@s9s_mb_2u_lib.s9s_mb_2u(sch_1):page314_i45@pure_quanta.q_res(chips)',
 P_PATH='@s9s_mb_2u_lib.s9s_mb_2u(sch_1):page213_i45@pure_quanta.q_res(chips)',
 PATH='I45',
 DRAWING='@S9S_MB_2U_LIB.S9S_MB_2U(SCH_1):PAGE314',
 PHYS_PAGE='213',
 XY='(-2400,1050)',
 ROT='0',
 VER='2',
 PACK_TYPE='0402LF',
 CDS_LIB='pure_quanta',
 CDS_PART_NAME='Q_RES_0402LF-4.7K,5%,1/16W,CHIA',
 WATTAGE='1/16W',
 TOLERANCE='5%',
 MATERIAL='CHIP',
 VALUE='4.7K',
 PRIM_FILE='./archive_libs/logical/q_res/chips/chips.prt';

PART_NAME
 R2345 'Q_RES_0402LF-49.9,1%,1/16W,EMPA':;

SECTION_NUMBER 1
 '@S9S_MB_2U_LIB.S9S_MB_2U(SCH_1):PAGE278_I15@PURE_QUANTA.Q_RES(CHIPS)':
 C_PATH='@s9s_mb_2u_lib.s9s_mb_2u(sch_1):page278_i15@pure_quanta.q_res(chips)',
 P_PATH='@s9s_mb_2u_lib.s9s_mb_2u(sch_1):page292_i15@pure_quanta.q_res(chips)',
 PATH='I15',
 DRAWING='@S9S_MB_2U_LIB.S9S_MB_2U(SCH_1):PAGE278',
 PHYS_PAGE='292',
 XY='(-100,8900)',
 ROT='0',
 VER='1',
 PACK_TYPE='0402LF',
 LOCATION='R2345',
 CDS_LIB='pure_quanta',
 CDS_PART_NAME='Q_RES_0402LF-49.9,1%,1/16W,EMPA',
 WATTAGE='1/16W',
 TOLERANCE='1%',
 MATERIAL='EMPTY',
 VALUE='49.9',
 PRIM_FILE='./archive_libs/logical/q_res/chips/chips.prt';

PART_NAME
 R2346 'Q_RES_0402LF-4.7K,5%,1/16W,CHIA':;

SECTION_NUMBER 1
 '@S9S_MB_2U_LIB.S9S_MB_2U(SCH_1):PAGE314_I51@PURE_QUANTA.Q_RES(CHIPS)':
 C_PATH='@s9s_mb_2u_lib.s9s_mb_2u(sch_1):page314_i51@pure_quanta.q_res(chips)',
 P_PATH='@s9s_mb_2u_lib.s9s_mb_2u(sch_1):page213_i51@pure_quanta.q_res(chips)',
 PATH='I51',
 DRAWING='@S9S_MB_2U_LIB.S9S_MB_2U(SCH_1):PAGE314',
 PHYS_PAGE='213',
 XY='(-1250,1050)',
 ROT='0',
 VER='2',
 PACK_TYPE='0402LF',
 CDS_LIB='pure_quanta',
 CDS_PART_NAME='Q_RES_0402LF-4.7K,5%,1/16W,CHIA',
 WATTAGE='1/16W',
 TOLERANCE='5%',
 MATERIAL='CHIP',
 VALUE='4.7K',
 PRIM_FILE='./archive_libs/logical/q_res/chips/chips.prt';

PART_NAME
 R2347 'Q_RES_0402LF-0,5%,1/16W,CHIP,CA':;

SECTION_NUMBER 1
 '@S9S_MB_2U_LIB.S9S_MB_2U(SCH_1):PAGE312_I183@PURE_QUANTA.Q_RES(CHIPS)':
 C_PATH='@s9s_mb_2u_lib.s9s_mb_2u(sch_1):page312_i183@pure_quanta.q_res(chips)',
 P_PATH='@s9s_mb_2u_lib.s9s_mb_2u(sch_1):page215_i183@pure_quanta.q_res(chips)',
 PATH='I183',
 DRAWING='@S9S_MB_2U_LIB.S9S_MB_2U(SCH_1):PAGE312',
 PHYS_PAGE='215',
 XY='(-4550,-1325)',
 ROT='0',
 VER='1',
 PACK_TYPE='0402LF',
 CDS_LIB='pure_quanta',
 CDS_PART_NAME='Q_RES_0402LF-0,5%,1/16W,CHIP,CA',
 WATTAGE='1/16W',
 TOLERANCE='5%',
 MATERIAL='CHIP',
 VALUE='0',
 PRIM_FILE='./archive_libs/logical/q_res/chips/chips.prt';

PART_NAME
 R2348 'Q_RES_0402LF-0,5%,1/16W,CHIP,CA':;

SECTION_NUMBER 1
 '@S9S_MB_2U_LIB.S9S_MB_2U(SCH_1):PAGE312_I184@PURE_QUANTA.Q_RES(CHIPS)':
 C_PATH='@s9s_mb_2u_lib.s9s_mb_2u(sch_1):page312_i184@pure_quanta.q_res(chips)',
 P_PATH='@s9s_mb_2u_lib.s9s_mb_2u(sch_1):page215_i184@pure_quanta.q_res(chips)',
 PATH='I184',
 DRAWING='@S9S_MB_2U_LIB.S9S_MB_2U(SCH_1):PAGE312',
 PHYS_PAGE='215',
 XY='(-4550,-1525)',
 ROT='0',
 VER='1',
 PACK_TYPE='0402LF',
 CDS_LIB='pure_quanta',
 CDS_PART_NAME='Q_RES_0402LF-0,5%,1/16W,CHIP,CA',
 WATTAGE='1/16W',
 TOLERANCE='5%',
 MATERIAL='CHIP',
 VALUE='0',
 PRIM_FILE='./archive_libs/logical/q_res/chips/chips.prt';

PART_NAME
 R2350 'Q_RES_0402LF-0,5%,1/16W,CHIP,CA':;

SECTION_NUMBER 1
 '@S9S_MB_2U_LIB.S9S_MB_2U(SCH_1):PAGE297_I157@PURE_QUANTA.Q_RES(CHIPS)':
 C_PATH='@s9s_mb_2u_lib.s9s_mb_2u(sch_1):page297_i157@pure_quanta.q_res(chips)',
 P_PATH='@s9s_mb_2u_lib.s9s_mb_2u(sch_1):page191_i157@pure_quanta.q_res(chips)',
 PATH='I157',
 DRAWING='@S9S_MB_2U_LIB.S9S_MB_2U(SCH_1):PAGE297',
 PHYS_PAGE='191',
 XY='(2275,825)',
 ROT='0',
 VER='1',
 PACK_TYPE='0402LF',
 CDS_LIB='pure_quanta',
 CDS_PART_NAME='Q_RES_0402LF-0,5%,1/16W,CHIP,CA',
 WATTAGE='1/16W',
 TOLERANCE='5%',
 MATERIAL='CHIP',
 VALUE='0',
 PRIM_FILE='./archive_libs/logical/q_res/chips/chips.prt';

PART_NAME
 R2354 'Q_RES_0402LF-100,1%,1/16W,EMPTA':;

SECTION_NUMBER 1
 '@S9S_MB_2U_LIB.S9S_MB_2U(SCH_1):PAGE278_I14@PURE_QUANTA.Q_RES(CHIPS)':
 C_PATH='@s9s_mb_2u_lib.s9s_mb_2u(sch_1):page278_i14@pure_quanta.q_res(chips)',
 P_PATH='@s9s_mb_2u_lib.s9s_mb_2u(sch_1):page292_i14@pure_quanta.q_res(chips)',
 PATH='I14',
 DRAWING='@S9S_MB_2U_LIB.S9S_MB_2U(SCH_1):PAGE278',
 PHYS_PAGE='292',
 XY='(-100,8800)',
 ROT='0',
 VER='1',
 PACK_TYPE='0402LF',
 LOCATION='R2354',
 CDS_LIB='pure_quanta',
 CDS_PART_NAME='Q_RES_0402LF-100,1%,1/16W,EMPTA',
 WATTAGE='1/16W',
 TOLERANCE='1%',
 MATERIAL='EMPTY',
 VALUE='100',
 PRIM_FILE='./archive_libs/logical/q_res/chips/chips.prt';

PART_NAME
 R2355 'Q_RES_0402LF-4.7K,5%,1/16W,EMPA':;

SECTION_NUMBER 1
 '@S9S_MB_2U_LIB.S9S_MB_2U(SCH_1):PAGE213_I7@PURE_QUANTA.Q_RES(CHIPS)':
 C_PATH='@s9s_mb_2u_lib.s9s_mb_2u(sch_1):page213_i7@pure_quanta.q_res(chips)',
 P_PATH='@s9s_mb_2u_lib.s9s_mb_2u(sch_1):page224_i7@pure_quanta.q_res(chips)',
 PATH='I7',
 DRAWING='@S9S_MB_2U_LIB.S9S_MB_2U(SCH_1):PAGE213',
 PHYS_PAGE='224',
 XY='(-6225,5250)',
 ROT='2',
 VER='2',
 PACK_TYPE='0402LF',
 CDS_LIB='pure_quanta',
 CDS_PART_NAME='Q_RES_0402LF-4.7K,5%,1/16W,EMPA',
 WATTAGE='1/16W',
 TOLERANCE='5%',
 MATERIAL='EMPTY',
 VALUE='4.7K',
 PRIM_FILE='./archive_libs/logical/q_res/chips/chips.prt';

PART_NAME
 R2356 'Q_RES_0402LF-10K,1%,1/16W,CHIPA':;

SECTION_NUMBER 1
 '@S9S_MB_2U_LIB.S9S_MB_2U(SCH_1):PAGE244_I27@PURE_QUANTA.Q_RES(CHIPS)':
 C_PATH='@s9s_mb_2u_lib.s9s_mb_2u(sch_1):page244_i27@pure_quanta.q_res(chips)',
 P_PATH='@s9s_mb_2u_lib.s9s_mb_2u(sch_1):page258_i27@pure_quanta.q_res(chips)',
 PATH='I27',
 DRAWING='@S9S_MB_2U_LIB.S9S_MB_2U(SCH_1):PAGE244',
 PHYS_PAGE='258',
 XY='(-3300,7075)',
 ROT='0',
 VER='2',
 PACK_TYPE='0402LF',
 LOCATION='R2356',
 SEC='1',
 CDS_LIB='pure_quanta',
 CDS_PART_NAME='Q_RES_0402LF-10K,1%,1/16W,CHIPA',
 SEC_TYPE='0402LF',
 WATTAGE='1/16W',
 TOLERANCE='1%',
 MATERIAL='CHIP',
 VALUE='10K',
 PRIM_FILE='./archive_libs/logical/q_res/chips/chips.prt';

PART_NAME
 R2357 'Q_RES_0402LF-10K,1%,1/16W,CHIPA':;

SECTION_NUMBER 1
 '@S9S_MB_2U_LIB.S9S_MB_2U(SCH_1):PAGE248_I32@PURE_QUANTA.Q_RES(CHIPS)':
 C_PATH='@s9s_mb_2u_lib.s9s_mb_2u(sch_1):page248_i32@pure_quanta.q_res(chips)',
 P_PATH='@s9s_mb_2u_lib.s9s_mb_2u(sch_1):page262_i32@pure_quanta.q_res(chips)',
 PATH='I32',
 DRAWING='@S9S_MB_2U_LIB.S9S_MB_2U(SCH_1):PAGE248',
 BOM_COST='VR_PCH',
 PHYS_PAGE='262',
 XY='(450,525)',
 ROT='0',
 VER='2',
 PACK_TYPE='0402LF',
 LOCATION='R2357',
 CDS_LIB='pure_quanta',
 CDS_PART_NAME='Q_RES_0402LF-10K,1%,1/16W,CHIPA',
 WATTAGE='1/16W',
 TOLERANCE='1%',
 MATERIAL='CHIP',
 VALUE='10K',
 PRIM_FILE='./archive_libs/logical/q_res/chips/chips.prt';

PART_NAME
 R2358 'Q_RES_0402LF-0,5%,1/16W,CHIP,CA':;

SECTION_NUMBER 1
 '@S9S_MB_2U_LIB.S9S_MB_2U(SCH_1):PAGE249_I17@PURE_QUANTA.Q_RES(CHIPS)':
 C_PATH='@s9s_mb_2u_lib.s9s_mb_2u(sch_1):page249_i17@pure_quanta.q_res(chips)',
 P_PATH='@s9s_mb_2u_lib.s9s_mb_2u(sch_1):page263_i17@pure_quanta.q_res(chips)',
 PATH='I17',
 DRAWING='@S9S_MB_2U_LIB.S9S_MB_2U(SCH_1):PAGE249',
 PHYS_PAGE='263',
 XY='(-5000,6250)',
 ROT='0',
 VER='1',
 PACK_TYPE='0402LF',
 LOCATION='R2358',
 CDS_LIB='pure_quanta',
 CDS_PART_NAME='Q_RES_0402LF-0,5%,1/16W,CHIP,CA',
 WATTAGE='1/16W',
 TOLERANCE='5%',
 MATERIAL='CHIP',
 VALUE='0',
 PRIM_FILE='./archive_libs/logical/q_res/chips/chips.prt';

PART_NAME
 R2359 'Q_RES_0402LF-10K,1%,1/16W,CHIPA':;

SECTION_NUMBER 1
 '@S9S_MB_2U_LIB.S9S_MB_2U(SCH_1):PAGE249_I31@PURE_QUANTA.Q_RES(CHIPS)':
 C_PATH='@s9s_mb_2u_lib.s9s_mb_2u(sch_1):page249_i31@pure_quanta.q_res(chips)',
 P_PATH='@s9s_mb_2u_lib.s9s_mb_2u(sch_1):page263_i31@pure_quanta.q_res(chips)',
 PATH='I31',
 DRAWING='@S9S_MB_2U_LIB.S9S_MB_2U(SCH_1):PAGE249',
 BOM_COST='VR_PCH',
 PHYS_PAGE='263',
 XY='(-1875,7125)',
 ROT='0',
 VER='2',
 PACK_TYPE='0402LF',
 LOCATION='R2359',
 CDS_LIB='pure_quanta',
 CDS_PART_NAME='Q_RES_0402LF-10K,1%,1/16W,CHIPA',
 WATTAGE='1/16W',
 TOLERANCE='1%',
 MATERIAL='CHIP',
 VALUE='10K',
 PRIM_FILE='./archive_libs/logical/q_res/chips/chips.prt';

PART_NAME
 R2360 'Q_RES_0402LF-0,5%,1/16W,CHIP,CA':;

SECTION_NUMBER 1
 '@S9S_MB_2U_LIB.S9S_MB_2U(SCH_1):PAGE249_I34@PURE_QUANTA.Q_RES(CHIPS)':
 C_PATH='@s9s_mb_2u_lib.s9s_mb_2u(sch_1):page249_i34@pure_quanta.q_res(chips)',
 P_PATH='@s9s_mb_2u_lib.s9s_mb_2u(sch_1):page263_i34@pure_quanta.q_res(chips)',
 PATH='I34',
 DRAWING='@S9S_MB_2U_LIB.S9S_MB_2U(SCH_1):PAGE249',
 PHYS_PAGE='263',
 XY='(-1325,6750)',
 ROT='0',
 VER='1',
 PACK_TYPE='0402LF',
 LOCATION='R2360',
 CDS_LIB='pure_quanta',
 CDS_PART_NAME='Q_RES_0402LF-0,5%,1/16W,CHIP,CA',
 WATTAGE='1/16W',
 TOLERANCE='5%',
 MATERIAL='CHIP',
 VALUE='0',
 PRIM_FILE='./archive_libs/logical/q_res/chips/chips.prt';

PART_NAME
 R2362 'Q_RES_0402LF-33.2,1%,1/16W,CHIA':;

SECTION_NUMBER 1
 '@S9S_MB_2U_LIB.S9S_MB_2U(SCH_1):PAGE14_I122@PURE_QUANTA.Q_RES(CHIPS)':
 C_PATH='@s9s_mb_2u_lib.s9s_mb_2u(sch_1):page14_i122@pure_quanta.q_res(chips)',
 P_PATH='@s9s_mb_2u_lib.s9s_mb_2u(sch_1):page14_i122@pure_quanta.q_res(chips)',
 PATH='I122',
 DRAWING='@S9S_MB_2U_LIB.S9S_MB_2U(SCH_1):PAGE14',
 PHYS_PAGE='14',
 XY='(-1600,25)',
 ROT='0',
 VER='1',
 PACK_TYPE='0402LF',
 CDS_LIB='pure_quanta',
 CDS_PART_NAME='Q_RES_0402LF-33.2,1%,1/16W,CHIA',
 WATTAGE='1/16W',
 TOLERANCE='1%',
 MATERIAL='CHIP',
 VALUE='33.2',
 PRIM_FILE='./archive_libs/logical/q_res/chips/chips.prt';

PART_NAME
 R2363 'Q_RES_0402LF-10,1%,1/16W,CHIP,A':;

SECTION_NUMBER 1
 '@S9S_MB_2U_LIB.S9S_MB_2U(SCH_1):PAGE190_I101@PURE_QUANTA.Q_RES(CHIPS)':
 C_PATH='@s9s_mb_2u_lib.s9s_mb_2u(sch_1):page190_i101@pure_quanta.q_res(chips)',
 P_PATH='@s9s_mb_2u_lib.s9s_mb_2u(sch_1):page202_i101@pure_quanta.q_res(chips)',
 PATH='I101',
 DRAWING='@S9S_MB_2U_LIB.S9S_MB_2U(SCH_1):PAGE190',
 PHYS_PAGE='202',
 XY='(-625,2725)',
 ROT='0',
 VER='1',
 PACK_TYPE='0402LF',
 LOCATION='R2363',
 CDS_LIB='pure_quanta',
 CDS_PART_NAME='Q_RES_0402LF-10,1%,1/16W,CHIP,A',
 WATTAGE='1/16W',
 TOLERANCE='1%',
 MATERIAL='CHIP',
 VALUE='10',
 PRIM_FILE='./archive_libs/logical/q_res/chips/chips.prt';

PART_NAME
 R2365 'Q_RES_0402LF-1K,1%,1/16W,CHIP,A':;

SECTION_NUMBER 1
 '@S9S_MB_2U_LIB.S9S_MB_2U(SCH_1):PAGE252_I50@PURE_QUANTA.Q_RES(CHIPS)':
 C_PATH='@s9s_mb_2u_lib.s9s_mb_2u(sch_1):page252_i50@pure_quanta.q_res(chips)',
 P_PATH='@s9s_mb_2u_lib.s9s_mb_2u(sch_1):page266_i50@pure_quanta.q_res(chips)',
 PATH='I50',
 DRAWING='@S9S_MB_2U_LIB.S9S_MB_2U(SCH_1):PAGE252',
 PHYS_PAGE='266',
 XY='(-5125,6700)',
 ROT='0',
 VER='1',
 PACK_TYPE='0402LF',
 LOCATION='R2365',
 CDS_LIB='pure_quanta',
 CDS_PART_NAME='Q_RES_0402LF-1K,1%,1/16W,CHIP,A',
 WATTAGE='1/16W',
 TOLERANCE='1%',
 MATERIAL='CHIP',
 VALUE='1K',
 PRIM_FILE='./archive_libs/logical/q_res/chips/chips.prt';

PART_NAME
 R2366 'Q_RES_0402LF-0,5%,1/16W,CHIP,CA':;

SECTION_NUMBER 1
 '@S9S_MB_2U_LIB.S9S_MB_2U(SCH_1):PAGE252_I49@PURE_QUANTA.Q_RES(CHIPS)':
 C_PATH='@s9s_mb_2u_lib.s9s_mb_2u(sch_1):page252_i49@pure_quanta.q_res(chips)',
 P_PATH='@s9s_mb_2u_lib.s9s_mb_2u(sch_1):page266_i49@pure_quanta.q_res(chips)',
 PATH='I49',
 DRAWING='@S9S_MB_2U_LIB.S9S_MB_2U(SCH_1):PAGE252',
 PHYS_PAGE='266',
 XY='(-5125,6550)',
 ROT='0',
 VER='1',
 PACK_TYPE='0402LF',
 LOCATION='R2366',
 CDS_LIB='pure_quanta',
 CDS_PART_NAME='Q_RES_0402LF-0,5%,1/16W,CHIP,CA',
 WATTAGE='1/16W',
 TOLERANCE='5%',
 MATERIAL='CHIP',
 VALUE='0',
 PRIM_FILE='./archive_libs/logical/q_res/chips/chips.prt';

PART_NAME
 R2367 'Q_RES_0402LF-10K,1%,1/16W,EMPTA':;

SECTION_NUMBER 1
 '@S9S_MB_2U_LIB.S9S_MB_2U(SCH_1):PAGE285_I14@PURE_QUANTA.Q_RES(CHIPS)':
 C_PATH='@s9s_mb_2u_lib.s9s_mb_2u(sch_1):page285_i14@pure_quanta.q_res(chips)',
 P_PATH='@s9s_mb_2u_lib.s9s_mb_2u(sch_1):page299_i14@pure_quanta.q_res(chips)',
 PATH='I14',
 DRAWING='@S9S_MB_2U_LIB.S9S_MB_2U(SCH_1):PAGE285',
 PHYS_PAGE='299',
 XY='(-10325,3350)',
 ROT='0',
 VER='1',
 PACK_TYPE='0402LF',
 LOCATION='R2367',
 CDS_LIB='pure_quanta',
 CDS_PART_NAME='Q_RES_0402LF-10K,1%,1/16W,EMPTA',
 WATTAGE='1/16W',
 TOLERANCE='1%',
 MATERIAL='EMPTY',
 VALUE='10K',
 PRIM_FILE='./archive_libs/logical/q_res/chips/chips.prt';

PART_NAME
 R2368 'Q_RES_0402LF-150,1%,1/16W,CHIPA':;

SECTION_NUMBER 1
 '@S9S_MB_2U_LIB.S9S_MB_2U(SCH_1):PAGE252_I44@PURE_QUANTA.Q_RES(CHIPS)':
 C_PATH='@s9s_mb_2u_lib.s9s_mb_2u(sch_1):page252_i44@pure_quanta.q_res(chips)',
 P_PATH='@s9s_mb_2u_lib.s9s_mb_2u(sch_1):page266_i44@pure_quanta.q_res(chips)',
 PATH='I44',
 DRAWING='@S9S_MB_2U_LIB.S9S_MB_2U(SCH_1):PAGE252',
 PHYS_PAGE='266',
 XY='(-5125,6100)',
 ROT='0',
 VER='1',
 PACK_TYPE='0402LF',
 LOCATION='R2368',
 CDS_LIB='pure_quanta',
 CDS_PART_NAME='Q_RES_0402LF-150,1%,1/16W,CHIPA',
 WATTAGE='1/16W',
 TOLERANCE='1%',
 MATERIAL='CHIP',
 VALUE='150',
 PRIM_FILE='./archive_libs/logical/q_res/chips/chips.prt';

PART_NAME
 R2369 'Q_RES_0402LF-0,5%,1/16W,CHIP,CA':;

SECTION_NUMBER 1
 '@S9S_MB_2U_LIB.S9S_MB_2U(SCH_1):PAGE252_I43@PURE_QUANTA.Q_RES(CHIPS)':
 C_PATH='@s9s_mb_2u_lib.s9s_mb_2u(sch_1):page252_i43@pure_quanta.q_res(chips)',
 P_PATH='@s9s_mb_2u_lib.s9s_mb_2u(sch_1):page266_i43@pure_quanta.q_res(chips)',
 PATH='I43',
 DRAWING='@S9S_MB_2U_LIB.S9S_MB_2U(SCH_1):PAGE252',
 PHYS_PAGE='266',
 XY='(-5125,5950)',
 ROT='0',
 VER='1',
 PACK_TYPE='0402LF',
 LOCATION='R2369',
 CDS_LIB='pure_quanta',
 CDS_PART_NAME='Q_RES_0402LF-0,5%,1/16W,CHIP,CA',
 WATTAGE='1/16W',
 TOLERANCE='5%',
 MATERIAL='CHIP',
 VALUE='0',
 PRIM_FILE='./archive_libs/logical/q_res/chips/chips.prt';

PART_NAME
 R2370 'Q_RES_0402LF-0,5%,1/16W,CHIP,CA':;

SECTION_NUMBER 1
 '@S9S_MB_2U_LIB.S9S_MB_2U(SCH_1):PAGE252_I41@PURE_QUANTA.Q_RES(CHIPS)':
 C_PATH='@s9s_mb_2u_lib.s9s_mb_2u(sch_1):page252_i41@pure_quanta.q_res(chips)',
 P_PATH='@s9s_mb_2u_lib.s9s_mb_2u(sch_1):page266_i41@pure_quanta.q_res(chips)',
 PATH='I41',
 DRAWING='@S9S_MB_2U_LIB.S9S_MB_2U(SCH_1):PAGE252',
 PHYS_PAGE='266',
 XY='(-5125,5800)',
 ROT='0',
 VER='1',
 PACK_TYPE='0402LF',
 LOCATION='R2370',
 CDS_LIB='pure_quanta',
 CDS_PART_NAME='Q_RES_0402LF-0,5%,1/16W,CHIP,CA',
 WATTAGE='1/16W',
 TOLERANCE='5%',
 MATERIAL='CHIP',
 VALUE='0',
 PRIM_FILE='./archive_libs/logical/q_res/chips/chips.prt';

PART_NAME
 R2371 'Q_RES_0402LF-33.2,1%,1/16W,CHIA':;

SECTION_NUMBER 1
 '@S9S_MB_2U_LIB.S9S_MB_2U(SCH_1):PAGE252_I80@PURE_QUANTA.Q_RES(CHIPS)':
 C_PATH='@s9s_mb_2u_lib.s9s_mb_2u(sch_1):page252_i80@pure_quanta.q_res(chips)',
 P_PATH='@s9s_mb_2u_lib.s9s_mb_2u(sch_1):page266_i80@pure_quanta.q_res(chips)',
 PATH='I80',
 DRAWING='@S9S_MB_2U_LIB.S9S_MB_2U(SCH_1):PAGE252',
 PHYS_PAGE='266',
 XY='(-4800,5400)',
 ROT='0',
 VER='1',
 PACK_TYPE='0402LF',
 LOCATION='R2371',
 CDS_LIB='pure_quanta',
 CDS_PART_NAME='Q_RES_0402LF-33.2,1%,1/16W,CHIA',
 WATTAGE='1/16W',
 TOLERANCE='1%',
 MATERIAL='CHIP',
 VALUE='33.2',
 PRIM_FILE='./archive_libs/logical/q_res/chips/chips.prt';

PART_NAME
 R2372 'Q_RES_0402LF-33.2,1%,1/16W,CHIA':;

SECTION_NUMBER 1
 '@S9S_MB_2U_LIB.S9S_MB_2U(SCH_1):PAGE252_I78@PURE_QUANTA.Q_RES(CHIPS)':
 C_PATH='@s9s_mb_2u_lib.s9s_mb_2u(sch_1):page252_i78@pure_quanta.q_res(chips)',
 P_PATH='@s9s_mb_2u_lib.s9s_mb_2u(sch_1):page266_i78@pure_quanta.q_res(chips)',
 PATH='I78',
 DRAWING='@S9S_MB_2U_LIB.S9S_MB_2U(SCH_1):PAGE252',
 PHYS_PAGE='266',
 XY='(-4800,5250)',
 ROT='0',
 VER='1',
 PACK_TYPE='0402LF',
 LOCATION='R2372',
 CDS_LIB='pure_quanta',
 CDS_PART_NAME='Q_RES_0402LF-33.2,1%,1/16W,CHIA',
 WATTAGE='1/16W',
 TOLERANCE='1%',
 MATERIAL='CHIP',
 VALUE='33.2',
 PRIM_FILE='./archive_libs/logical/q_res/chips/chips.prt';

PART_NAME
 R2373 'Q_RES_0402LF-1K,1%,1/16W,CHIP,A':;

SECTION_NUMBER 1
 '@S9S_MB_2U_LIB.S9S_MB_2U(SCH_1):PAGE252_I23@PURE_QUANTA.Q_RES(CHIPS)':
 C_PATH='@s9s_mb_2u_lib.s9s_mb_2u(sch_1):page252_i23@pure_quanta.q_res(chips)',
 P_PATH='@s9s_mb_2u_lib.s9s_mb_2u(sch_1):page266_i23@pure_quanta.q_res(chips)',
 PATH='I23',
 DRAWING='@S9S_MB_2U_LIB.S9S_MB_2U(SCH_1):PAGE252',
 PHYS_PAGE='266',
 XY='(-5250,2850)',
 ROT='0',
 VER='1',
 PACK_TYPE='0402LF',
 LOCATION='R2373',
 CDS_LIB='pure_quanta',
 CDS_PART_NAME='Q_RES_0402LF-1K,1%,1/16W,CHIP,A',
 WATTAGE='1/16W',
 TOLERANCE='1%',
 MATERIAL='CHIP',
 VALUE='1K',
 PRIM_FILE='./archive_libs/logical/q_res/chips/chips.prt';

PART_NAME
 R2374 'Q_RES_0402LF-2K,1%,1/16W,CHIP,A':;

SECTION_NUMBER 1
 '@S9S_MB_2U_LIB.S9S_MB_2U(SCH_1):PAGE285_I13@PURE_QUANTA.Q_RES(CHIPS)':
 C_PATH='@s9s_mb_2u_lib.s9s_mb_2u(sch_1):page285_i13@pure_quanta.q_res(chips)',
 P_PATH='@s9s_mb_2u_lib.s9s_mb_2u(sch_1):page299_i13@pure_quanta.q_res(chips)',
 PATH='I13',
 DRAWING='@S9S_MB_2U_LIB.S9S_MB_2U(SCH_1):PAGE285',
 PHYS_PAGE='299',
 XY='(-9650,2950)',
 ROT='0',
 VER='2',
 PACK_TYPE='0402LF',
 LOCATION='R2374',
 CDS_LIB='pure_quanta',
 CDS_PART_NAME='Q_RES_0402LF-2K,1%,1/16W,CHIP,A',
 WATTAGE='1/16W',
 TOLERANCE='1%',
 MATERIAL='CHIP',
 VALUE='2K',
 PRIM_FILE='./archive_libs/logical/q_res/chips/chips.prt';

PART_NAME
 R2375 'Q_RES_0402LF-1K,1%,1/16W,CHIP,A':;

SECTION_NUMBER 1
 '@S9S_MB_2U_LIB.S9S_MB_2U(SCH_1):PAGE252_I19@PURE_QUANTA.Q_RES(CHIPS)':
 C_PATH='@s9s_mb_2u_lib.s9s_mb_2u(sch_1):page252_i19@pure_quanta.q_res(chips)',
 P_PATH='@s9s_mb_2u_lib.s9s_mb_2u(sch_1):page266_i19@pure_quanta.q_res(chips)',
 PATH='I19',
 DRAWING='@S9S_MB_2U_LIB.S9S_MB_2U(SCH_1):PAGE252',
 PHYS_PAGE='266',
 XY='(-5250,2450)',
 ROT='0',
 VER='1',
 PACK_TYPE='0402LF',
 LOCATION='R2375',
 CDS_LIB='pure_quanta',
 CDS_PART_NAME='Q_RES_0402LF-1K,1%,1/16W,CHIP,A',
 WATTAGE='1/16W',
 TOLERANCE='1%',
 MATERIAL='CHIP',
 VALUE='1K',
 PRIM_FILE='./archive_libs/logical/q_res/chips/chips.prt';

PART_NAME
 R2376 'Q_RES_0402LF-0,5%,1/16W,CHIP,CA':;

SECTION_NUMBER 1
 '@S9S_MB_2U_LIB.S9S_MB_2U(SCH_1):PAGE252_I17@PURE_QUANTA.Q_RES(CHIPS)':
 C_PATH='@s9s_mb_2u_lib.s9s_mb_2u(sch_1):page252_i17@pure_quanta.q_res(chips)',
 P_PATH='@s9s_mb_2u_lib.s9s_mb_2u(sch_1):page266_i17@pure_quanta.q_res(chips)',
 PATH='I17',
 DRAWING='@S9S_MB_2U_LIB.S9S_MB_2U(SCH_1):PAGE252',
 PHYS_PAGE='266',
 XY='(-5675,2300)',
 ROT='0',
 VER='1',
 PACK_TYPE='0402LF',
 LOCATION='R2376',
 CDS_LIB='pure_quanta',
 CDS_PART_NAME='Q_RES_0402LF-0,5%,1/16W,CHIP,CA',
 WATTAGE='1/16W',
 TOLERANCE='5%',
 MATERIAL='CHIP',
 VALUE='0',
 PRIM_FILE='./archive_libs/logical/q_res/chips/chips.prt';

PART_NAME
 R2377 'Q_RES_0402LF-1K,1%,1/16W,CHIP,A':;

SECTION_NUMBER 1
 '@S9S_MB_2U_LIB.S9S_MB_2U(SCH_1):PAGE252_I54@PURE_QUANTA.Q_RES(CHIPS)':
 C_PATH='@s9s_mb_2u_lib.s9s_mb_2u(sch_1):page252_i54@pure_quanta.q_res(chips)',
 P_PATH='@s9s_mb_2u_lib.s9s_mb_2u(sch_1):page266_i54@pure_quanta.q_res(chips)',
 PATH='I54',
 DRAWING='@S9S_MB_2U_LIB.S9S_MB_2U(SCH_1):PAGE252',
 PHYS_PAGE='266',
 XY='(-4950,1900)',
 ROT='0',
 VER='1',
 PACK_TYPE='0402LF',
 LOCATION='R2377',
 CDS_LIB='pure_quanta',
 CDS_PART_NAME='Q_RES_0402LF-1K,1%,1/16W,CHIP,A',
 WATTAGE='1/16W',
 TOLERANCE='1%',
 MATERIAL='CHIP',
 VALUE='1K',
 PRIM_FILE='./archive_libs/logical/q_res/chips/chips.prt';

PART_NAME
 R2379 'Q_RES_0402LF-0,5%,1/16W,CHIP,CA':;

SECTION_NUMBER 1
 '@S9S_MB_2U_LIB.S9S_MB_2U(SCH_1):PAGE252_I55@PURE_QUANTA.Q_RES(CHIPS)':
 C_PATH='@s9s_mb_2u_lib.s9s_mb_2u(sch_1):page252_i55@pure_quanta.q_res(chips)',
 P_PATH='@s9s_mb_2u_lib.s9s_mb_2u(sch_1):page266_i55@pure_quanta.q_res(chips)',
 PATH='I55',
 DRAWING='@S9S_MB_2U_LIB.S9S_MB_2U(SCH_1):PAGE252',
 PHYS_PAGE='266',
 XY='(-4950,1750)',
 ROT='0',
 VER='1',
 PACK_TYPE='0402LF',
 LOCATION='R2379',
 CDS_LIB='pure_quanta',
 CDS_PART_NAME='Q_RES_0402LF-0,5%,1/16W,CHIP,CA',
 WATTAGE='1/16W',
 TOLERANCE='5%',
 MATERIAL='CHIP',
 VALUE='0',
 PRIM_FILE='./archive_libs/logical/q_res/chips/chips.prt';

PART_NAME
 R2380 'Q_RES_0402LF-0,5%,1/16W,CHIP,CA':;

SECTION_NUMBER 1
 '@S9S_MB_2U_LIB.S9S_MB_2U(SCH_1):PAGE285_I37@PURE_QUANTA.Q_RES(CHIPS)':
 C_PATH='@s9s_mb_2u_lib.s9s_mb_2u(sch_1):page285_i37@pure_quanta.q_res(chips)',
 P_PATH='@s9s_mb_2u_lib.s9s_mb_2u(sch_1):page299_i37@pure_quanta.q_res(chips)',
 PATH='I37',
 DRAWING='@S9S_MB_2U_LIB.S9S_MB_2U(SCH_1):PAGE285',
 PHYS_PAGE='299',
 XY='(-6175,3875)',
 ROT='0',
 VER='1',
 PACK_TYPE='0402LF',
 LOCATION='R2380',
 CDS_LIB='pure_quanta',
 CDS_PART_NAME='Q_RES_0402LF-0,5%,1/16W,CHIP,CA',
 WATTAGE='1/16W',
 TOLERANCE='5%',
 MATERIAL='CHIP',
 VALUE='0',
 PRIM_FILE='./archive_libs/logical/q_res/chips/chips.prt';

PART_NAME
 R2381 'Q_RES_0402LF-49.9,1%,1/16W,CHIA':;

SECTION_NUMBER 1
 '@S9S_MB_2U_LIB.S9S_MB_2U(SCH_1):PAGE252_I125@PURE_QUANTA.Q_RES(CHIPS)':
 C_PATH='@s9s_mb_2u_lib.s9s_mb_2u(sch_1):page252_i125@pure_quanta.q_res(chips)',
 P_PATH='@s9s_mb_2u_lib.s9s_mb_2u(sch_1):page266_i125@pure_quanta.q_res(chips)',
 PATH='I125',
 DRAWING='@S9S_MB_2U_LIB.S9S_MB_2U(SCH_1):PAGE252',
 PHYS_PAGE='266',
 XY='(950,2050)',
 ROT='0',
 VER='1',
 PACK_TYPE='0402LF',
 LOCATION='R2381',
 CDS_LIB='pure_quanta',
 CDS_PART_NAME='Q_RES_0402LF-49.9,1%,1/16W,CHIA',
 WATTAGE='1/16W',
 TOLERANCE='1%',
 MATERIAL='CHIP',
 VALUE='49.9',
 PRIM_FILE='./archive_libs/logical/q_res/chips/chips.prt';

PART_NAME
 R2382 'Q_RES_0402LF-49.9,1%,1/16W,EMPA':;

SECTION_NUMBER 1
 '@S9S_MB_2U_LIB.S9S_MB_2U(SCH_1):PAGE252_I123@PURE_QUANTA.Q_RES(CHIPS)':
 C_PATH='@s9s_mb_2u_lib.s9s_mb_2u(sch_1):page252_i123@pure_quanta.q_res(chips)',
 P_PATH='@s9s_mb_2u_lib.s9s_mb_2u(sch_1):page266_i123@pure_quanta.q_res(chips)',
 PATH='I123',
 DRAWING='@S9S_MB_2U_LIB.S9S_MB_2U(SCH_1):PAGE252',
 PHYS_PAGE='266',
 XY='(950,1900)',
 ROT='0',
 VER='1',
 PACK_TYPE='0402LF',
 LOCATION='R2382',
 CDS_LIB='pure_quanta',
 CDS_PART_NAME='Q_RES_0402LF-49.9,1%,1/16W,EMPA',
 WATTAGE='1/16W',
 TOLERANCE='1%',
 MATERIAL='EMPTY',
 VALUE='49.9',
 PRIM_FILE='./archive_libs/logical/q_res/chips/chips.prt';

PART_NAME
 R2383 'Q_RES_0402LF-1K,1%,1/16W,CHIP,A':;

SECTION_NUMBER 1
 '@S9S_MB_2U_LIB.S9S_MB_2U(SCH_1):PAGE260_I59@PURE_QUANTA.Q_RES(CHIPS)':
 C_PATH='@s9s_mb_2u_lib.s9s_mb_2u(sch_1):page260_i59@pure_quanta.q_res(chips)',
 P_PATH='@s9s_mb_2u_lib.s9s_mb_2u(sch_1):page274_i59@pure_quanta.q_res(chips)',
 PATH='I59',
 DRAWING='@S9S_MB_2U_LIB.S9S_MB_2U(SCH_1):PAGE260',
 PHYS_PAGE='274',
 XY='(-9200,7725)',
 ROT='0',
 VER='1',
 PACK_TYPE='0402LF',
 LOCATION='R2383',
 CDS_LIB='pure_quanta',
 CDS_PART_NAME='Q_RES_0402LF-1K,1%,1/16W,CHIP,A',
 WATTAGE='1/16W',
 TOLERANCE='1%',
 MATERIAL='CHIP',
 VALUE='1K',
 PRIM_FILE='./archive_libs/logical/q_res/chips/chips.prt';

PART_NAME
 R2384 'Q_RES_0402LF-10K,1%,1/16W,EMPTA':;

SECTION_NUMBER 1
 '@S9S_MB_2U_LIB.S9S_MB_2U(SCH_1):PAGE286_I5@PURE_QUANTA.Q_RES(CHIPS)':
 C_PATH='@s9s_mb_2u_lib.s9s_mb_2u(sch_1):page286_i5@pure_quanta.q_res(chips)',
 P_PATH='@s9s_mb_2u_lib.s9s_mb_2u(sch_1):page300_i5@pure_quanta.q_res(chips)',
 PATH='I5',
 DRAWING='@S9S_MB_2U_LIB.S9S_MB_2U(SCH_1):PAGE286',
 PHYS_PAGE='300',
 XY='(1925,7400)',
 ROT='0',
 VER='1',
 PACK_TYPE='0402LF',
 LOCATION='R2384',
 CDS_LIB='pure_quanta',
 CDS_PART_NAME='Q_RES_0402LF-10K,1%,1/16W,EMPTA',
 WATTAGE='1/16W',
 TOLERANCE='1%',
 MATERIAL='EMPTY',
 VALUE='10K',
 PRIM_FILE='./archive_libs/logical/q_res/chips/chips.prt';

PART_NAME
 R2385 'Q_RES_0402LF-2K,1%,1/16W,CHIP,A':;

SECTION_NUMBER 1
 '@S9S_MB_2U_LIB.S9S_MB_2U(SCH_1):PAGE286_I7@PURE_QUANTA.Q_RES(CHIPS)':
 C_PATH='@s9s_mb_2u_lib.s9s_mb_2u(sch_1):page286_i7@pure_quanta.q_res(chips)',
 P_PATH='@s9s_mb_2u_lib.s9s_mb_2u(sch_1):page300_i7@pure_quanta.q_res(chips)',
 PATH='I7',
 DRAWING='@S9S_MB_2U_LIB.S9S_MB_2U(SCH_1):PAGE286',
 PHYS_PAGE='300',
 XY='(2500,7025)',
 ROT='0',
 VER='2',
 PACK_TYPE='0402LF',
 LOCATION='R2385',
 CDS_LIB='pure_quanta',
 CDS_PART_NAME='Q_RES_0402LF-2K,1%,1/16W,CHIP,A',
 WATTAGE='1/16W',
 TOLERANCE='1%',
 MATERIAL='CHIP',
 VALUE='2K',
 PRIM_FILE='./archive_libs/logical/q_res/chips/chips.prt';

PART_NAME
 R2386 'Q_RES_0402LF-100,1%,1/16W,EMPTA':;

SECTION_NUMBER 1
 '@S9S_MB_2U_LIB.S9S_MB_2U(SCH_1):PAGE260_I37@PURE_QUANTA.Q_RES(CHIPS)':
 C_PATH='@s9s_mb_2u_lib.s9s_mb_2u(sch_1):page260_i37@pure_quanta.q_res(chips)',
 P_PATH='@s9s_mb_2u_lib.s9s_mb_2u(sch_1):page274_i37@pure_quanta.q_res(chips)',
 PATH='I37',
 DRAWING='@S9S_MB_2U_LIB.S9S_MB_2U(SCH_1):PAGE260',
 PHYS_PAGE='274',
 XY='(-10375,7225)',
 ROT='0',
 VER='1',
 PACK_TYPE='0402LF',
 LOCATION='R2386',
 CDS_LIB='pure_quanta',
 CDS_PART_NAME='Q_RES_0402LF-100,1%,1/16W,EMPTA',
 WATTAGE='1/16W',
 TOLERANCE='1%',
 MATERIAL='EMPTY',
 VALUE='100',
 PRIM_FILE='./archive_libs/logical/q_res/chips/chips.prt';

PART_NAME
 R2387 'Q_RES_0402LF-0,5%,1/16W,CHIP,CA':;

SECTION_NUMBER 1
 '@S9S_MB_2U_LIB.S9S_MB_2U(SCH_1):PAGE286_I29@PURE_QUANTA.Q_RES(CHIPS)':
 C_PATH='@s9s_mb_2u_lib.s9s_mb_2u(sch_1):page286_i29@pure_quanta.q_res(chips)',
 P_PATH='@s9s_mb_2u_lib.s9s_mb_2u(sch_1):page300_i29@pure_quanta.q_res(chips)',
 PATH='I29',
 DRAWING='@S9S_MB_2U_LIB.S9S_MB_2U(SCH_1):PAGE286',
 PHYS_PAGE='300',
 XY='(7375,7725)',
 ROT='0',
 VER='1',
 PACK_TYPE='0402LF',
 LOCATION='R2387',
 CDS_LIB='pure_quanta',
 CDS_PART_NAME='Q_RES_0402LF-0,5%,1/16W,CHIP,CA',
 WATTAGE='1/16W',
 TOLERANCE='5%',
 MATERIAL='CHIP',
 VALUE='0',
 PRIM_FILE='./archive_libs/logical/q_res/chips/chips.prt';

PART_NAME
 R2388 'Q_RES_0402LF-0,5%,1/16W,CHIP,CA':;

SECTION_NUMBER 1
 '@S9S_MB_2U_LIB.S9S_MB_2U(SCH_1):PAGE260_I57@PURE_QUANTA.Q_RES(CHIPS)':
 C_PATH='@s9s_mb_2u_lib.s9s_mb_2u(sch_1):page260_i57@pure_quanta.q_res(chips)',
 P_PATH='@s9s_mb_2u_lib.s9s_mb_2u(sch_1):page274_i57@pure_quanta.q_res(chips)',
 PATH='I57',
 DRAWING='@S9S_MB_2U_LIB.S9S_MB_2U(SCH_1):PAGE260',
 PHYS_PAGE='274',
 XY='(-9200,6975)',
 ROT='0',
 VER='1',
 PACK_TYPE='0402LF',
 LOCATION='R2388',
 CDS_LIB='pure_quanta',
 CDS_PART_NAME='Q_RES_0402LF-0,5%,1/16W,CHIP,CA',
 WATTAGE='1/16W',
 TOLERANCE='5%',
 MATERIAL='CHIP',
 VALUE='0',
 PRIM_FILE='./archive_libs/logical/q_res/chips/chips.prt';

PART_NAME
 R2389 'Q_RES_0402LF-0,5%,1/16W,CHIP,CA':;

SECTION_NUMBER 1
 '@S9S_MB_2U_LIB.S9S_MB_2U(SCH_1):PAGE260_I52@PURE_QUANTA.Q_RES(CHIPS)':
 C_PATH='@s9s_mb_2u_lib.s9s_mb_2u(sch_1):page260_i52@pure_quanta.q_res(chips)',
 P_PATH='@s9s_mb_2u_lib.s9s_mb_2u(sch_1):page274_i52@pure_quanta.q_res(chips)',
 PATH='I52',
 DRAWING='@S9S_MB_2U_LIB.S9S_MB_2U(SCH_1):PAGE260',
 PHYS_PAGE='274',
 XY='(-9200,6825)',
 ROT='0',
 VER='1',
 PACK_TYPE='0402LF',
 LOCATION='R2389',
 CDS_LIB='pure_quanta',
 CDS_PART_NAME='Q_RES_0402LF-0,5%,1/16W,CHIP,CA',
 WATTAGE='1/16W',
 TOLERANCE='5%',
 MATERIAL='CHIP',
 VALUE='0',
 PRIM_FILE='./archive_libs/logical/q_res/chips/chips.prt';

PART_NAME
 R2390 'Q_RES_0402LF-0,5%,1/16W,CHIP,CA':;

SECTION_NUMBER 1
 '@S9S_MB_2U_LIB.S9S_MB_2U(SCH_1):PAGE260_I53@PURE_QUANTA.Q_RES(CHIPS)':
 C_PATH='@s9s_mb_2u_lib.s9s_mb_2u(sch_1):page260_i53@pure_quanta.q_res(chips)',
 P_PATH='@s9s_mb_2u_lib.s9s_mb_2u(sch_1):page274_i53@pure_quanta.q_res(chips)',
 PATH='I53',
 DRAWING='@S9S_MB_2U_LIB.S9S_MB_2U(SCH_1):PAGE260',
 PHYS_PAGE='274',
 XY='(-9200,6425)',
 ROT='0',
 VER='1',
 PACK_TYPE='0402LF',
 LOCATION='R2390',
 SEC='1',
 CDS_LIB='pure_quanta',
 CDS_PART_NAME='Q_RES_0402LF-0,5%,1/16W,CHIP,CA',
 SEC_TYPE='0402LF',
 WATTAGE='1/16W',
 TOLERANCE='5%',
 MATERIAL='CHIP',
 VALUE='0',
 PRIM_FILE='./archive_libs/logical/q_res/chips/chips.prt';

PART_NAME
 R2391 'Q_RES_0402LF-0,5%,1/16W,CHIP,CA':;

SECTION_NUMBER 1
 '@S9S_MB_2U_LIB.S9S_MB_2U(SCH_1):PAGE260_I51@PURE_QUANTA.Q_RES(CHIPS)':
 C_PATH='@s9s_mb_2u_lib.s9s_mb_2u(sch_1):page260_i51@pure_quanta.q_res(chips)',
 P_PATH='@s9s_mb_2u_lib.s9s_mb_2u(sch_1):page274_i51@pure_quanta.q_res(chips)',
 PATH='I51',
 DRAWING='@S9S_MB_2U_LIB.S9S_MB_2U(SCH_1):PAGE260',
 PHYS_PAGE='274',
 XY='(-9200,6275)',
 ROT='0',
 VER='1',
 PACK_TYPE='0402LF',
 LOCATION='R2391',
 CDS_LIB='pure_quanta',
 CDS_PART_NAME='Q_RES_0402LF-0,5%,1/16W,CHIP,CA',
 WATTAGE='1/16W',
 TOLERANCE='5%',
 MATERIAL='CHIP',
 VALUE='0',
 PRIM_FILE='./archive_libs/logical/q_res/chips/chips.prt';

PART_NAME
 R2392 'Q_RES_0402LF-1K,1%,1/16W,CHIP,A':;

SECTION_NUMBER 1
 '@S9S_MB_2U_LIB.S9S_MB_2U(SCH_1):PAGE260_I18@PURE_QUANTA.Q_RES(CHIPS)':
 C_PATH='@s9s_mb_2u_lib.s9s_mb_2u(sch_1):page260_i18@pure_quanta.q_res(chips)',
 P_PATH='@s9s_mb_2u_lib.s9s_mb_2u(sch_1):page274_i18@pure_quanta.q_res(chips)',
 PATH='I18',
 DRAWING='@S9S_MB_2U_LIB.S9S_MB_2U(SCH_1):PAGE260',
 PHYS_PAGE='274',
 XY='(-9025,3575)',
 ROT='0',
 VER='1',
 PACK_TYPE='0402LF',
 LOCATION='R2392',
 CDS_LIB='pure_quanta',
 CDS_PART_NAME='Q_RES_0402LF-1K,1%,1/16W,CHIP,A',
 WATTAGE='1/16W',
 TOLERANCE='1%',
 MATERIAL='CHIP',
 VALUE='1K',
 PRIM_FILE='./archive_libs/logical/q_res/chips/chips.prt';

PART_NAME
 R2393 'Q_RES_0402LF-1K,1%,1/16W,CHIP,A':;

SECTION_NUMBER 1
 '@S9S_MB_2U_LIB.S9S_MB_2U(SCH_1):PAGE260_I17@PURE_QUANTA.Q_RES(CHIPS)':
 C_PATH='@s9s_mb_2u_lib.s9s_mb_2u(sch_1):page260_i17@pure_quanta.q_res(chips)',
 P_PATH='@s9s_mb_2u_lib.s9s_mb_2u(sch_1):page274_i17@pure_quanta.q_res(chips)',
 PATH='I17',
 DRAWING='@S9S_MB_2U_LIB.S9S_MB_2U(SCH_1):PAGE260',
 PHYS_PAGE='274',
 XY='(-9025,3475)',
 ROT='0',
 VER='1',
 PACK_TYPE='0402LF',
 LOCATION='R2393',
 CDS_LIB='pure_quanta',
 CDS_PART_NAME='Q_RES_0402LF-1K,1%,1/16W,CHIP,A',
 WATTAGE='1/16W',
 TOLERANCE='1%',
 MATERIAL='CHIP',
 VALUE='1K',
 PRIM_FILE='./archive_libs/logical/q_res/chips/chips.prt';

PART_NAME
 R2394 'Q_RES_0402LF-0,5%,1/16W,CHIP,CA':;

SECTION_NUMBER 1
 '@S9S_MB_2U_LIB.S9S_MB_2U(SCH_1):PAGE260_I14@PURE_QUANTA.Q_RES(CHIPS)':
 C_PATH='@s9s_mb_2u_lib.s9s_mb_2u(sch_1):page260_i14@pure_quanta.q_res(chips)',
 P_PATH='@s9s_mb_2u_lib.s9s_mb_2u(sch_1):page274_i14@pure_quanta.q_res(chips)',
 PATH='I14',
 DRAWING='@S9S_MB_2U_LIB.S9S_MB_2U(SCH_1):PAGE260',
 PHYS_PAGE='274',
 XY='(-9025,3175)',
 ROT='0',
 VER='1',
 PACK_TYPE='0402LF',
 LOCATION='R2394',
 CDS_LIB='pure_quanta',
 CDS_PART_NAME='Q_RES_0402LF-0,5%,1/16W,CHIP,CA',
 WATTAGE='1/16W',
 TOLERANCE='5%',
 MATERIAL='CHIP',
 VALUE='0',
 PRIM_FILE='./archive_libs/logical/q_res/chips/chips.prt';

PART_NAME
 R2396 'Q_RES_0402LF-1K,1%,1/16W,CHIP,A':;

SECTION_NUMBER 1
 '@S9S_MB_2U_LIB.S9S_MB_2U(SCH_1):PAGE260_I13@PURE_QUANTA.Q_RES(CHIPS)':
 C_PATH='@s9s_mb_2u_lib.s9s_mb_2u(sch_1):page260_i13@pure_quanta.q_res(chips)',
 P_PATH='@s9s_mb_2u_lib.s9s_mb_2u(sch_1):page274_i13@pure_quanta.q_res(chips)',
 PATH='I13',
 DRAWING='@S9S_MB_2U_LIB.S9S_MB_2U(SCH_1):PAGE260',
 PHYS_PAGE='274',
 XY='(-9025,2925)',
 ROT='0',
 VER='1',
 PACK_TYPE='0402LF',
 LOCATION='R2396',
 CDS_LIB='pure_quanta',
 CDS_PART_NAME='Q_RES_0402LF-1K,1%,1/16W,CHIP,A',
 WATTAGE='1/16W',
 TOLERANCE='1%',
 MATERIAL='CHIP',
 VALUE='1K',
 PRIM_FILE='./archive_libs/logical/q_res/chips/chips.prt';

PART_NAME
 R2397 'Q_RES_0402LF-0,5%,1/16W,CHIP,CA':;

SECTION_NUMBER 1
 '@S9S_MB_2U_LIB.S9S_MB_2U(SCH_1):PAGE260_I11@PURE_QUANTA.Q_RES(CHIPS)':
 C_PATH='@s9s_mb_2u_lib.s9s_mb_2u(sch_1):page260_i11@pure_quanta.q_res(chips)',
 P_PATH='@s9s_mb_2u_lib.s9s_mb_2u(sch_1):page274_i11@pure_quanta.q_res(chips)',
 PATH='I11',
 DRAWING='@S9S_MB_2U_LIB.S9S_MB_2U(SCH_1):PAGE260',
 PHYS_PAGE='274',
 XY='(-9025,2775)',
 ROT='0',
 VER='1',
 PACK_TYPE='0402LF',
 LOCATION='R2397',
 CDS_LIB='pure_quanta',
 CDS_PART_NAME='Q_RES_0402LF-0,5%,1/16W,CHIP,CA',
 WATTAGE='1/16W',
 TOLERANCE='5%',
 MATERIAL='CHIP',
 VALUE='0',
 PRIM_FILE='./archive_libs/logical/q_res/chips/chips.prt';

PART_NAME
 R2398 'Q_RES_0402LF-1K,1%,1/16W,CHIP,A':;

SECTION_NUMBER 1
 '@S9S_MB_2U_LIB.S9S_MB_2U(SCH_1):PAGE260_I79@PURE_QUANTA.Q_RES(CHIPS)':
 C_PATH='@s9s_mb_2u_lib.s9s_mb_2u(sch_1):page260_i79@pure_quanta.q_res(chips)',
 P_PATH='@s9s_mb_2u_lib.s9s_mb_2u(sch_1):page274_i79@pure_quanta.q_res(chips)',
 PATH='I79',
 DRAWING='@S9S_MB_2U_LIB.S9S_MB_2U(SCH_1):PAGE260',
 PHYS_PAGE='274',
 XY='(-4100,3325)',
 ROT='0',
 VER='2',
 PACK_TYPE='0402LF',
 LOCATION='R2398',
 CDS_LIB='pure_quanta',
 CDS_PART_NAME='Q_RES_0402LF-1K,1%,1/16W,CHIP,A',
 WATTAGE='1/16W',
 TOLERANCE='1%',
 MATERIAL='CHIP',
 VALUE='1K',
 PRIM_FILE='./archive_libs/logical/q_res/chips/chips.prt';

PART_NAME
 R2399 'Q_RES_0402LF-150,1%,1/16W,CHIPA':;

SECTION_NUMBER 1
 '@S9S_MB_2U_LIB.S9S_MB_2U(SCH_1):PAGE264_I43@PURE_QUANTA.Q_RES(CHIPS)':
 C_PATH='@s9s_mb_2u_lib.s9s_mb_2u(sch_1):page264_i43@pure_quanta.q_res(chips)',
 P_PATH='@s9s_mb_2u_lib.s9s_mb_2u(sch_1):page278_i43@pure_quanta.q_res(chips)',
 PATH='I43',
 DRAWING='@S9S_MB_2U_LIB.S9S_MB_2U(SCH_1):PAGE264',
 PHYS_PAGE='278',
 XY='(-9850,8500)',
 ROT='0',
 VER='1',
 PACK_TYPE='0402LF',
 LOCATION='R2399',
 CDS_LIB='pure_quanta',
 CDS_PART_NAME='Q_RES_0402LF-150,1%,1/16W,CHIPA',
 WATTAGE='1/16W',
 TOLERANCE='1%',
 MATERIAL='CHIP',
 VALUE='150',
 PRIM_FILE='./archive_libs/logical/q_res/chips/chips.prt';

PART_NAME
 R2400 'Q_RES_0402LF-0,5%,1/16W,CHIP,CA':;

SECTION_NUMBER 1
 '@S9S_MB_2U_LIB.S9S_MB_2U(SCH_1):PAGE264_I42@PURE_QUANTA.Q_RES(CHIPS)':
 C_PATH='@s9s_mb_2u_lib.s9s_mb_2u(sch_1):page264_i42@pure_quanta.q_res(chips)',
 P_PATH='@s9s_mb_2u_lib.s9s_mb_2u(sch_1):page278_i42@pure_quanta.q_res(chips)',
 PATH='I42',
 DRAWING='@S9S_MB_2U_LIB.S9S_MB_2U(SCH_1):PAGE264',
 PHYS_PAGE='278',
 XY='(-9850,8350)',
 ROT='0',
 VER='1',
 PACK_TYPE='0402LF',
 LOCATION='R2400',
 CDS_LIB='pure_quanta',
 CDS_PART_NAME='Q_RES_0402LF-0,5%,1/16W,CHIP,CA',
 WATTAGE='1/16W',
 TOLERANCE='5%',
 MATERIAL='CHIP',
 VALUE='0',
 PRIM_FILE='./archive_libs/logical/q_res/chips/chips.prt';

PART_NAME
 R2401 'Q_RES_0402LF-0,5%,1/16W,CHIP,CA':;

SECTION_NUMBER 1
 '@S9S_MB_2U_LIB.S9S_MB_2U(SCH_1):PAGE264_I40@PURE_QUANTA.Q_RES(CHIPS)':
 C_PATH='@s9s_mb_2u_lib.s9s_mb_2u(sch_1):page264_i40@pure_quanta.q_res(chips)',
 P_PATH='@s9s_mb_2u_lib.s9s_mb_2u(sch_1):page278_i40@pure_quanta.q_res(chips)',
 PATH='I40',
 DRAWING='@S9S_MB_2U_LIB.S9S_MB_2U(SCH_1):PAGE264',
 PHYS_PAGE='278',
 XY='(-9850,8200)',
 ROT='0',
 VER='1',
 PACK_TYPE='0402LF',
 LOCATION='R2401',
 CDS_LIB='pure_quanta',
 CDS_PART_NAME='Q_RES_0402LF-0,5%,1/16W,CHIP,CA',
 WATTAGE='1/16W',
 TOLERANCE='5%',
 MATERIAL='CHIP',
 VALUE='0',
 PRIM_FILE='./archive_libs/logical/q_res/chips/chips.prt';

PART_NAME
 R2402 'Q_RES_0402LF-0,5%,1/16W,CHIP,CA':;

SECTION_NUMBER 1
 '@S9S_MB_2U_LIB.S9S_MB_2U(SCH_1):PAGE264_I39@PURE_QUANTA.Q_RES(CHIPS)':
 C_PATH='@s9s_mb_2u_lib.s9s_mb_2u(sch_1):page264_i39@pure_quanta.q_res(chips)',
 P_PATH='@s9s_mb_2u_lib.s9s_mb_2u(sch_1):page278_i39@pure_quanta.q_res(chips)',
 PATH='I39',
 DRAWING='@S9S_MB_2U_LIB.S9S_MB_2U(SCH_1):PAGE264',
 PHYS_PAGE='278',
 XY='(-9850,7800)',
 ROT='0',
 VER='1',
 PACK_TYPE='0402LF',
 LOCATION='R2402',
 CDS_LIB='pure_quanta',
 CDS_PART_NAME='Q_RES_0402LF-0,5%,1/16W,CHIP,CA',
 WATTAGE='1/16W',
 TOLERANCE='5%',
 MATERIAL='CHIP',
 VALUE='0',
 PRIM_FILE='./archive_libs/logical/q_res/chips/chips.prt';

PART_NAME
 R2403 'Q_RES_0402LF-0,5%,1/16W,CHIP,CA':;

SECTION_NUMBER 1
 '@S9S_MB_2U_LIB.S9S_MB_2U(SCH_1):PAGE264_I38@PURE_QUANTA.Q_RES(CHIPS)':
 C_PATH='@s9s_mb_2u_lib.s9s_mb_2u(sch_1):page264_i38@pure_quanta.q_res(chips)',
 P_PATH='@s9s_mb_2u_lib.s9s_mb_2u(sch_1):page278_i38@pure_quanta.q_res(chips)',
 PATH='I38',
 DRAWING='@S9S_MB_2U_LIB.S9S_MB_2U(SCH_1):PAGE264',
 PHYS_PAGE='278',
 XY='(-9850,7650)',
 ROT='0',
 VER='1',
 PACK_TYPE='0402LF',
 LOCATION='R2403',
 CDS_LIB='pure_quanta',
 CDS_PART_NAME='Q_RES_0402LF-0,5%,1/16W,CHIP,CA',
 WATTAGE='1/16W',
 TOLERANCE='5%',
 MATERIAL='CHIP',
 VALUE='0',
 PRIM_FILE='./archive_libs/logical/q_res/chips/chips.prt';

PART_NAME
 R2404 'Q_RES_0402LF-1K,1%,1/16W,CHIP,A':;

SECTION_NUMBER 1
 '@S9S_MB_2U_LIB.S9S_MB_2U(SCH_1):PAGE264_I85@PURE_QUANTA.Q_RES(CHIPS)':
 C_PATH='@s9s_mb_2u_lib.s9s_mb_2u(sch_1):page264_i85@pure_quanta.q_res(chips)',
 P_PATH='@s9s_mb_2u_lib.s9s_mb_2u(sch_1):page278_i85@pure_quanta.q_res(chips)',
 PATH='I85',
 DRAWING='@S9S_MB_2U_LIB.S9S_MB_2U(SCH_1):PAGE264',
 PHYS_PAGE='278',
 XY='(-4425,4675)',
 ROT='0',
 VER='2',
 PACK_TYPE='0402LF',
 LOCATION='R2404',
 CDS_LIB='pure_quanta',
 CDS_PART_NAME='Q_RES_0402LF-1K,1%,1/16W,CHIP,A',
 WATTAGE='1/16W',
 TOLERANCE='1%',
 MATERIAL='CHIP',
 VALUE='1K',
 PRIM_FILE='./archive_libs/logical/q_res/chips/chips.prt';

PART_NAME
 R2405 'Q_RES_0402LF-0,5%,1/16W,CHIP,CA':;

SECTION_NUMBER 1
 '@S9S_MB_2U_LIB.S9S_MB_2U(SCH_1):PAGE264_I60@PURE_QUANTA.Q_RES(CHIPS)':
 C_PATH='@s9s_mb_2u_lib.s9s_mb_2u(sch_1):page264_i60@pure_quanta.q_res(chips)',
 P_PATH='@s9s_mb_2u_lib.s9s_mb_2u(sch_1):page278_i60@pure_quanta.q_res(chips)',
 PATH='I60',
 DRAWING='@S9S_MB_2U_LIB.S9S_MB_2U(SCH_1):PAGE264',
 PHYS_PAGE='278',
 XY='(-5325,4450)',
 ROT='0',
 VER='1',
 PACK_TYPE='0402LF',
 LOCATION='R2405',
 CDS_LIB='pure_quanta',
 CDS_PART_NAME='Q_RES_0402LF-0,5%,1/16W,CHIP,CA',
 WATTAGE='1/16W',
 TOLERANCE='5%',
 MATERIAL='CHIP',
 VALUE='0',
 PRIM_FILE='./archive_libs/logical/q_res/chips/chips.prt';

PART_NAME
 R2406 'Q_RES_0402LF-10K,1%,1/16W,EMPTA':;

SECTION_NUMBER 1
 '@S9S_MB_2U_LIB.S9S_MB_2U(SCH_1):PAGE267_I9@PURE_QUANTA.Q_RES(CHIPS)':
 C_PATH='@s9s_mb_2u_lib.s9s_mb_2u(sch_1):page267_i9@pure_quanta.q_res(chips)',
 P_PATH='@s9s_mb_2u_lib.s9s_mb_2u(sch_1):page281_i9@pure_quanta.q_res(chips)',
 PATH='I9',
 DRAWING='@S9S_MB_2U_LIB.S9S_MB_2U(SCH_1):PAGE267',
 PHYS_PAGE='281',
 XY='(-10950,3800)',
 ROT='0',
 VER='1',
 PACK_TYPE='0402LF',
 LOCATION='R2406',
 CDS_LIB='pure_quanta',
 CDS_PART_NAME='Q_RES_0402LF-10K,1%,1/16W,EMPTA',
 WATTAGE='1/16W',
 TOLERANCE='1%',
 MATERIAL='EMPTY',
 VALUE='10K',
 PRIM_FILE='./archive_libs/logical/q_res/chips/chips.prt';

PART_NAME
 R2407 'Q_RES_0402LF-10K,1%,1/16W,CHIPA':;

SECTION_NUMBER 1
 '@S9S_MB_2U_LIB.S9S_MB_2U(SCH_1):PAGE267_I45@PURE_QUANTA.Q_RES(CHIPS)':
 C_PATH='@s9s_mb_2u_lib.s9s_mb_2u(sch_1):page267_i45@pure_quanta.q_res(chips)',
 P_PATH='@s9s_mb_2u_lib.s9s_mb_2u(sch_1):page281_i45@pure_quanta.q_res(chips)',
 PATH='I45',
 DRAWING='@S9S_MB_2U_LIB.S9S_MB_2U(SCH_1):PAGE267',
 BOM_COST='VR_PCH',
 PHYS_PAGE='281',
 XY='(-7225,4650)',
 ROT='0',
 VER='2',
 PACK_TYPE='0402LF',
 LOCATION='R2407',
 CDS_LIB='pure_quanta',
 CDS_PART_NAME='Q_RES_0402LF-10K,1%,1/16W,CHIPA',
 WATTAGE='1/16W',
 TOLERANCE='1%',
 MATERIAL='CHIP',
 VALUE='10K',
 PRIM_FILE='./archive_libs/logical/q_res/chips/chips.prt';

PART_NAME
 R2408 'Q_RES_0402LF-0,5%,1/16W,CHIP,CA':;

SECTION_NUMBER 1
 '@S9S_MB_2U_LIB.S9S_MB_2U(SCH_1):PAGE267_I29@PURE_QUANTA.Q_RES(CHIPS)':
 C_PATH='@s9s_mb_2u_lib.s9s_mb_2u(sch_1):page267_i29@pure_quanta.q_res(chips)',
 P_PATH='@s9s_mb_2u_lib.s9s_mb_2u(sch_1):page281_i29@pure_quanta.q_res(chips)',
 PATH='I29',
 DRAWING='@S9S_MB_2U_LIB.S9S_MB_2U(SCH_1):PAGE267',
 PHYS_PAGE='281',
 XY='(-6800,4325)',
 ROT='0',
 VER='1',
 PACK_TYPE='0402LF',
 LOCATION='R2408',
 CDS_LIB='pure_quanta',
 CDS_PART_NAME='Q_RES_0402LF-0,5%,1/16W,CHIP,CA',
 WATTAGE='1/16W',
 TOLERANCE='5%',
 MATERIAL='CHIP',
 VALUE='0',
 PRIM_FILE='./archive_libs/logical/q_res/chips/chips.prt';

PART_NAME
 R2409 'Q_RES_0402LF-10K,1%,1/16W,CHIPA':;

SECTION_NUMBER 1
 '@S9S_MB_2U_LIB.S9S_MB_2U(SCH_1):PAGE268_I32@PURE_QUANTA.Q_RES(CHIPS)':
 C_PATH='@s9s_mb_2u_lib.s9s_mb_2u(sch_1):page268_i32@pure_quanta.q_res(chips)',
 P_PATH='@s9s_mb_2u_lib.s9s_mb_2u(sch_1):page282_i32@pure_quanta.q_res(chips)',
 PATH='I32',
 DRAWING='@S9S_MB_2U_LIB.S9S_MB_2U(SCH_1):PAGE268',
 BOM_COST='VR_PCH',
 PHYS_PAGE='282',
 XY='(-5425,10900)',
 ROT='0',
 VER='2',
 PACK_TYPE='0402LF',
 LOCATION='R2409',
 CDS_LIB='pure_quanta',
 CDS_PART_NAME='Q_RES_0402LF-10K,1%,1/16W,CHIPA',
 WATTAGE='1/16W',
 TOLERANCE='1%',
 MATERIAL='CHIP',
 VALUE='10K',
 PRIM_FILE='./archive_libs/logical/q_res/chips/chips.prt';

PART_NAME
 R2410 'Q_RES_0402LF-33.2,1%,1/16W,CHIA':;

SECTION_NUMBER 1
 '@S9S_MB_2U_LIB.S9S_MB_2U(SCH_1):PAGE183_I65@PURE_QUANTA.Q_RES(CHIPS)':
 C_PATH='@s9s_mb_2u_lib.s9s_mb_2u(sch_1):page183_i65@pure_quanta.q_res(chips)',
 P_PATH='@s9s_mb_2u_lib.s9s_mb_2u(sch_1):page194_i65@pure_quanta.q_res(chips)',
 PATH='I65',
 DRAWING='@S9S_MB_2U_LIB.S9S_MB_2U(SCH_1):PAGE183',
 PHYS_PAGE='194',
 XY='(2800,3425)',
 ROT='0',
 VER='1',
 PACK_TYPE='0402LF',
 CDS_LIB='pure_quanta',
 CDS_PART_NAME='Q_RES_0402LF-33.2,1%,1/16W,CHIA',
 WATTAGE='1/16W',
 TOLERANCE='1%',
 MATERIAL='CHIP',
 VALUE='33.2',
 PRIM_FILE='./archive_libs/logical/q_res/chips/chips.prt';

PART_NAME
 R2411 'Q_RES_0402LF-33.2,1%,1/16W,CHIA':;

SECTION_NUMBER 1
 '@S9S_MB_2U_LIB.S9S_MB_2U(SCH_1):PAGE183_I66@PURE_QUANTA.Q_RES(CHIPS)':
 C_PATH='@s9s_mb_2u_lib.s9s_mb_2u(sch_1):page183_i66@pure_quanta.q_res(chips)',
 P_PATH='@s9s_mb_2u_lib.s9s_mb_2u(sch_1):page194_i66@pure_quanta.q_res(chips)',
 PATH='I66',
 DRAWING='@S9S_MB_2U_LIB.S9S_MB_2U(SCH_1):PAGE183',
 PHYS_PAGE='194',
 XY='(2800,3375)',
 ROT='0',
 VER='1',
 PACK_TYPE='0402LF',
 CDS_LIB='pure_quanta',
 CDS_PART_NAME='Q_RES_0402LF-33.2,1%,1/16W,CHIA',
 WATTAGE='1/16W',
 TOLERANCE='1%',
 MATERIAL='CHIP',
 VALUE='33.2',
 PRIM_FILE='./archive_libs/logical/q_res/chips/chips.prt';

PART_NAME
 R2412 'Q_RES_0402LF-0,5%,1/16W,CHIP,CA':;

SECTION_NUMBER 1
 '@S9S_MB_2U_LIB.S9S_MB_2U(SCH_1):PAGE313_I83@PURE_QUANTA.Q_RES(CHIPS)':
 C_PATH='@s9s_mb_2u_lib.s9s_mb_2u(sch_1):page313_i83@pure_quanta.q_res(chips)',
 P_PATH='@s9s_mb_2u_lib.s9s_mb_2u(sch_1):page214_i83@pure_quanta.q_res(chips)',
 PATH='I83',
 DRAWING='@S9S_MB_2U_LIB.S9S_MB_2U(SCH_1):PAGE313',
 PHYS_PAGE='214',
 XY='(2675,-1400)',
 ROT='0',
 VER='1',
 PACK_TYPE='0402LF',
 CDS_LIB='pure_quanta',
 CDS_PART_NAME='Q_RES_0402LF-0,5%,1/16W,CHIP,CA',
 WATTAGE='1/16W',
 TOLERANCE='5%',
 MATERIAL='CHIP',
 VALUE='0',
 PRIM_FILE='./archive_libs/logical/q_res/chips/chips.prt';

PART_NAME
 R2413 'Q_RES_0402LF-0,5%,1/16W,CHIP,CA':;

SECTION_NUMBER 1
 '@S9S_MB_2U_LIB.S9S_MB_2U(SCH_1):PAGE227_I86@PURE_QUANTA.Q_RES(CHIPS)':
 C_PATH='@s9s_mb_2u_lib.s9s_mb_2u(sch_1):page227_i86@pure_quanta.q_res(chips)',
 P_PATH='@s9s_mb_2u_lib.s9s_mb_2u(sch_1):page240_i86@pure_quanta.q_res(chips)',
 PATH='I86',
 DRAWING='@S9S_MB_2U_LIB.S9S_MB_2U(SCH_1):PAGE227',
 PHYS_PAGE='240',
 XY='(-13300,-225)',
 ROT='0',
 VER='1',
 PACK_TYPE='0402LF',
 CDS_LIB='pure_quanta',
 CDS_PART_NAME='Q_RES_0402LF-0,5%,1/16W,CHIP,CA',
 WATTAGE='1/16W',
 TOLERANCE='5%',
 MATERIAL='CHIP',
 VALUE='0',
 PRIM_FILE='./archive_libs/logical/q_res/chips/chips.prt';

PART_NAME
 R2414 'Q_RES_0402LF-0,5%,1/16W,CHIP,CA':;

SECTION_NUMBER 1
 '@S9S_MB_2U_LIB.S9S_MB_2U(SCH_1):PAGE227_I85@PURE_QUANTA.Q_RES(CHIPS)':
 C_PATH='@s9s_mb_2u_lib.s9s_mb_2u(sch_1):page227_i85@pure_quanta.q_res(chips)',
 P_PATH='@s9s_mb_2u_lib.s9s_mb_2u(sch_1):page240_i85@pure_quanta.q_res(chips)',
 PATH='I85',
 DRAWING='@S9S_MB_2U_LIB.S9S_MB_2U(SCH_1):PAGE227',
 PHYS_PAGE='240',
 XY='(-13300,-275)',
 ROT='0',
 VER='1',
 PACK_TYPE='0402LF',
 CDS_LIB='pure_quanta',
 CDS_PART_NAME='Q_RES_0402LF-0,5%,1/16W,CHIP,CA',
 WATTAGE='1/16W',
 TOLERANCE='5%',
 MATERIAL='CHIP',
 VALUE='0',
 PRIM_FILE='./archive_libs/logical/q_res/chips/chips.prt';

PART_NAME
 R2415 'Q_RES_0402LF-0,5%,1/16W,CHIP,CA':;

SECTION_NUMBER 1
 '@S9S_MB_2U_LIB.S9S_MB_2U(SCH_1):PAGE227_I25@PURE_QUANTA.Q_RES(CHIPS)':
 C_PATH='@s9s_mb_2u_lib.s9s_mb_2u(sch_1):page227_i25@pure_quanta.q_res(chips)',
 P_PATH='@s9s_mb_2u_lib.s9s_mb_2u(sch_1):page240_i25@pure_quanta.q_res(chips)',
 PATH='I25',
 DRAWING='@S9S_MB_2U_LIB.S9S_MB_2U(SCH_1):PAGE227',
 PHYS_PAGE='240',
 XY='(-13300,-575)',
 ROT='0',
 VER='1',
 PACK_TYPE='0402LF',
 CDS_LIB='pure_quanta',
 CDS_PART_NAME='Q_RES_0402LF-0,5%,1/16W,CHIP,CA',
 WATTAGE='1/16W',
 TOLERANCE='5%',
 MATERIAL='CHIP',
 VALUE='0',
 PRIM_FILE='./archive_libs/logical/q_res/chips/chips.prt';

PART_NAME
 R2416 'Q_RES_0402LF-0,5%,1/16W,CHIP,CA':;

SECTION_NUMBER 1
 '@S9S_MB_2U_LIB.S9S_MB_2U(SCH_1):PAGE227_I24@PURE_QUANTA.Q_RES(CHIPS)':
 C_PATH='@s9s_mb_2u_lib.s9s_mb_2u(sch_1):page227_i24@pure_quanta.q_res(chips)',
 P_PATH='@s9s_mb_2u_lib.s9s_mb_2u(sch_1):page240_i24@pure_quanta.q_res(chips)',
 PATH='I24',
 DRAWING='@S9S_MB_2U_LIB.S9S_MB_2U(SCH_1):PAGE227',
 PHYS_PAGE='240',
 XY='(-13300,-625)',
 ROT='0',
 VER='1',
 PACK_TYPE='0402LF',
 CDS_LIB='pure_quanta',
 CDS_PART_NAME='Q_RES_0402LF-0,5%,1/16W,CHIP,CA',
 WATTAGE='1/16W',
 TOLERANCE='5%',
 MATERIAL='CHIP',
 VALUE='0',
 PRIM_FILE='./archive_libs/logical/q_res/chips/chips.prt';

PART_NAME
 R2417 'Q_RES_0402LF-33.2,1%,1/16W,CHIA':;

SECTION_NUMBER 1
 '@S9S_MB_2U_LIB.S9S_MB_2U(SCH_1):PAGE227_I22@PURE_QUANTA.Q_RES(CHIPS)':
 C_PATH='@s9s_mb_2u_lib.s9s_mb_2u(sch_1):page227_i22@pure_quanta.q_res(chips)',
 P_PATH='@s9s_mb_2u_lib.s9s_mb_2u(sch_1):page240_i22@pure_quanta.q_res(chips)',
 PATH='I22',
 DRAWING='@S9S_MB_2U_LIB.S9S_MB_2U(SCH_1):PAGE227',
 PHYS_PAGE='240',
 XY='(-13300,-675)',
 ROT='0',
 VER='1',
 PACK_TYPE='0402LF',
 CDS_LIB='pure_quanta',
 CDS_PART_NAME='Q_RES_0402LF-33.2,1%,1/16W,CHIA',
 WATTAGE='1/16W',
 TOLERANCE='1%',
 MATERIAL='CHIP',
 VALUE='33.2',
 PRIM_FILE='./archive_libs/logical/q_res/chips/chips.prt';

PART_NAME
 R2418 'Q_RES_0402LF-33.2,1%,1/16W,CHIA':;

SECTION_NUMBER 1
 '@S9S_MB_2U_LIB.S9S_MB_2U(SCH_1):PAGE227_I23@PURE_QUANTA.Q_RES(CHIPS)':
 C_PATH='@s9s_mb_2u_lib.s9s_mb_2u(sch_1):page227_i23@pure_quanta.q_res(chips)',
 P_PATH='@s9s_mb_2u_lib.s9s_mb_2u(sch_1):page240_i23@pure_quanta.q_res(chips)',
 PATH='I23',
 DRAWING='@S9S_MB_2U_LIB.S9S_MB_2U(SCH_1):PAGE227',
 PHYS_PAGE='240',
 XY='(-13300,-725)',
 ROT='0',
 VER='1',
 PACK_TYPE='0402LF',
 CDS_LIB='pure_quanta',
 CDS_PART_NAME='Q_RES_0402LF-33.2,1%,1/16W,CHIA',
 WATTAGE='1/16W',
 TOLERANCE='1%',
 MATERIAL='CHIP',
 VALUE='33.2',
 PRIM_FILE='./archive_libs/logical/q_res/chips/chips.prt';

PART_NAME
 R2419 'Q_RES_0402LF-33.2,1%,1/16W,CHIA':;

SECTION_NUMBER 1
 '@S9S_MB_2U_LIB.S9S_MB_2U(SCH_1):PAGE227_I100@PURE_QUANTA.Q_RES(CHIPS)':
 C_PATH='@s9s_mb_2u_lib.s9s_mb_2u(sch_1):page227_i100@pure_quanta.q_res(chips)',
 P_PATH='@s9s_mb_2u_lib.s9s_mb_2u(sch_1):page240_i100@pure_quanta.q_res(chips)',
 PATH='I100',
 DRAWING='@S9S_MB_2U_LIB.S9S_MB_2U(SCH_1):PAGE227',
 PHYS_PAGE='240',
 XY='(-13275,1275)',
 ROT='0',
 VER='1',
 PACK_TYPE='0402LF',
 CDS_LIB='pure_quanta',
 CDS_PART_NAME='Q_RES_0402LF-33.2,1%,1/16W,CHIA',
 WATTAGE='1/16W',
 TOLERANCE='1%',
 MATERIAL='CHIP',
 VALUE='33.2',
 PRIM_FILE='./archive_libs/logical/q_res/chips/chips.prt';

PART_NAME
 R2420 'Q_RES_0402LF-33.2,1%,1/16W,CHIA':;

SECTION_NUMBER 1
 '@S9S_MB_2U_LIB.S9S_MB_2U(SCH_1):PAGE227_I98@PURE_QUANTA.Q_RES(CHIPS)':
 C_PATH='@s9s_mb_2u_lib.s9s_mb_2u(sch_1):page227_i98@pure_quanta.q_res(chips)',
 P_PATH='@s9s_mb_2u_lib.s9s_mb_2u(sch_1):page240_i98@pure_quanta.q_res(chips)',
 PATH='I98',
 DRAWING='@S9S_MB_2U_LIB.S9S_MB_2U(SCH_1):PAGE227',
 PHYS_PAGE='240',
 XY='(-13275,1225)',
 ROT='0',
 VER='1',
 PACK_TYPE='0402LF',
 CDS_LIB='pure_quanta',
 CDS_PART_NAME='Q_RES_0402LF-33.2,1%,1/16W,CHIA',
 WATTAGE='1/16W',
 TOLERANCE='1%',
 MATERIAL='CHIP',
 VALUE='33.2',
 PRIM_FILE='./archive_libs/logical/q_res/chips/chips.prt';

PART_NAME
 R2421 'Q_RES_0402LF-33.2,1%,1/16W,CHIA':;

SECTION_NUMBER 1
 '@S9S_MB_2U_LIB.S9S_MB_2U(SCH_1):PAGE227_I99@PURE_QUANTA.Q_RES(CHIPS)':
 C_PATH='@s9s_mb_2u_lib.s9s_mb_2u(sch_1):page227_i99@pure_quanta.q_res(chips)',
 P_PATH='@s9s_mb_2u_lib.s9s_mb_2u(sch_1):page240_i99@pure_quanta.q_res(chips)',
 PATH='I99',
 DRAWING='@S9S_MB_2U_LIB.S9S_MB_2U(SCH_1):PAGE227',
 PHYS_PAGE='240',
 XY='(-13275,1175)',
 ROT='0',
 VER='1',
 PACK_TYPE='0402LF',
 CDS_LIB='pure_quanta',
 CDS_PART_NAME='Q_RES_0402LF-33.2,1%,1/16W,CHIA',
 WATTAGE='1/16W',
 TOLERANCE='1%',
 MATERIAL='CHIP',
 VALUE='33.2',
 PRIM_FILE='./archive_libs/logical/q_res/chips/chips.prt';

PART_NAME
 R2422 'Q_RES_0402LF-33.2,1%,1/16W,CHIA':;

SECTION_NUMBER 1
 '@S9S_MB_2U_LIB.S9S_MB_2U(SCH_1):PAGE227_I95@PURE_QUANTA.Q_RES(CHIPS)':
 C_PATH='@s9s_mb_2u_lib.s9s_mb_2u(sch_1):page227_i95@pure_quanta.q_res(chips)',
 P_PATH='@s9s_mb_2u_lib.s9s_mb_2u(sch_1):page240_i95@pure_quanta.q_res(chips)',
 PATH='I95',
 DRAWING='@S9S_MB_2U_LIB.S9S_MB_2U(SCH_1):PAGE227',
 PHYS_PAGE='240',
 XY='(-13275,1125)',
 ROT='0',
 VER='1',
 PACK_TYPE='0402LF',
 CDS_LIB='pure_quanta',
 CDS_PART_NAME='Q_RES_0402LF-33.2,1%,1/16W,CHIA',
 WATTAGE='1/16W',
 TOLERANCE='1%',
 MATERIAL='CHIP',
 VALUE='33.2',
 PRIM_FILE='./archive_libs/logical/q_res/chips/chips.prt';

PART_NAME
 R2423 'Q_RES_0402LF-33.2,1%,1/16W,CHIA':;

SECTION_NUMBER 1
 '@S9S_MB_2U_LIB.S9S_MB_2U(SCH_1):PAGE227_I97@PURE_QUANTA.Q_RES(CHIPS)':
 C_PATH='@s9s_mb_2u_lib.s9s_mb_2u(sch_1):page227_i97@pure_quanta.q_res(chips)',
 P_PATH='@s9s_mb_2u_lib.s9s_mb_2u(sch_1):page240_i97@pure_quanta.q_res(chips)',
 PATH='I97',
 DRAWING='@S9S_MB_2U_LIB.S9S_MB_2U(SCH_1):PAGE227',
 PHYS_PAGE='240',
 XY='(-13275,1075)',
 ROT='0',
 VER='1',
 PACK_TYPE='0402LF',
 CDS_LIB='pure_quanta',
 CDS_PART_NAME='Q_RES_0402LF-33.2,1%,1/16W,CHIA',
 WATTAGE='1/16W',
 TOLERANCE='1%',
 MATERIAL='CHIP',
 VALUE='33.2',
 PRIM_FILE='./archive_libs/logical/q_res/chips/chips.prt';

PART_NAME
 R2424 'Q_RES_0402LF-33.2,1%,1/16W,CHIA':;

SECTION_NUMBER 1
 '@S9S_MB_2U_LIB.S9S_MB_2U(SCH_1):PAGE227_I96@PURE_QUANTA.Q_RES(CHIPS)':
 C_PATH='@s9s_mb_2u_lib.s9s_mb_2u(sch_1):page227_i96@pure_quanta.q_res(chips)',
 P_PATH='@s9s_mb_2u_lib.s9s_mb_2u(sch_1):page240_i96@pure_quanta.q_res(chips)',
 PATH='I96',
 DRAWING='@S9S_MB_2U_LIB.S9S_MB_2U(SCH_1):PAGE227',
 PHYS_PAGE='240',
 XY='(-13275,1025)',
 ROT='0',
 VER='1',
 PACK_TYPE='0402LF',
 CDS_LIB='pure_quanta',
 CDS_PART_NAME='Q_RES_0402LF-33.2,1%,1/16W,CHIA',
 WATTAGE='1/16W',
 TOLERANCE='1%',
 MATERIAL='CHIP',
 VALUE='33.2',
 PRIM_FILE='./archive_libs/logical/q_res/chips/chips.prt';

PART_NAME
 R2425 'Q_RES_0402LF-33.2,1%,1/16W,CHIA':;

SECTION_NUMBER 1
 '@S9S_MB_2U_LIB.S9S_MB_2U(SCH_1):PAGE227_I93@PURE_QUANTA.Q_RES(CHIPS)':
 C_PATH='@s9s_mb_2u_lib.s9s_mb_2u(sch_1):page227_i93@pure_quanta.q_res(chips)',
 P_PATH='@s9s_mb_2u_lib.s9s_mb_2u(sch_1):page240_i93@pure_quanta.q_res(chips)',
 PATH='I93',
 DRAWING='@S9S_MB_2U_LIB.S9S_MB_2U(SCH_1):PAGE227',
 PHYS_PAGE='240',
 XY='(-13275,875)',
 ROT='0',
 VER='1',
 PACK_TYPE='0402LF',
 CDS_LIB='pure_quanta',
 CDS_PART_NAME='Q_RES_0402LF-33.2,1%,1/16W,CHIA',
 WATTAGE='1/16W',
 TOLERANCE='1%',
 MATERIAL='CHIP',
 VALUE='33.2',
 PRIM_FILE='./archive_libs/logical/q_res/chips/chips.prt';

PART_NAME
 R2426 'Q_RES_0402LF-100,1%,1/16W,EMPTA':;

SECTION_NUMBER 1
 '@S9S_MB_2U_LIB.S9S_MB_2U(SCH_1):PAGE297_I311@PURE_QUANTA.Q_RES(CHIPS)':
 C_PATH='@s9s_mb_2u_lib.s9s_mb_2u(sch_1):page297_i311@pure_quanta.q_res(chips)',
 P_PATH='@s9s_mb_2u_lib.s9s_mb_2u(sch_1):page191_i311@pure_quanta.q_res(chips)',
 PATH='I311',
 DRAWING='@S9S_MB_2U_LIB.S9S_MB_2U(SCH_1):PAGE297',
 PHYS_PAGE='191',
 XY='(3850,3850)',
 ROT='0',
 VER='2',
 PACK_TYPE='0402LF',
 LOCATION='R2426',
 CDS_LIB='pure_quanta',
 CDS_PART_NAME='Q_RES_0402LF-100,1%,1/16W,EMPTA',
 WATTAGE='1/16W',
 TOLERANCE='1%',
 MATERIAL='EMPTY',
 VALUE='100',
 PRIM_FILE='./archive_libs/logical/q_res/chips/chips.prt';

PART_NAME
 R2449 'Q_RES_0402LF-33.2,1%,1/16W,CHIA':;

SECTION_NUMBER 1
 '@S9S_MB_2U_LIB.S9S_MB_2U(SCH_1):PAGE228_I206@PURE_QUANTA.Q_RES(CHIPS)':
 C_PATH='@s9s_mb_2u_lib.s9s_mb_2u(sch_1):page228_i206@pure_quanta.q_res(chips)',
 P_PATH='@s9s_mb_2u_lib.s9s_mb_2u(sch_1):page241_i206@pure_quanta.q_res(chips)',
 PATH='I206',
 DRAWING='@S9S_MB_2U_LIB.S9S_MB_2U(SCH_1):PAGE228',
 PHYS_PAGE='241',
 XY='(-325,2450)',
 ROT='0',
 VER='1',
 PACK_TYPE='0402LF',
 CDS_LIB='pure_quanta',
 CDS_PART_NAME='Q_RES_0402LF-33.2,1%,1/16W,CHIA',
 WATTAGE='1/16W',
 TOLERANCE='1%',
 MATERIAL='CHIP',
 VALUE='33.2',
 PRIM_FILE='./archive_libs/logical/q_res/chips/chips.prt';

PART_NAME
 R2450 'Q_RES_0402LF-33.2,1%,1/16W,CHIA':;

SECTION_NUMBER 1
 '@S9S_MB_2U_LIB.S9S_MB_2U(SCH_1):PAGE228_I207@PURE_QUANTA.Q_RES(CHIPS)':
 C_PATH='@s9s_mb_2u_lib.s9s_mb_2u(sch_1):page228_i207@pure_quanta.q_res(chips)',
 P_PATH='@s9s_mb_2u_lib.s9s_mb_2u(sch_1):page241_i207@pure_quanta.q_res(chips)',
 PATH='I207',
 DRAWING='@S9S_MB_2U_LIB.S9S_MB_2U(SCH_1):PAGE228',
 PHYS_PAGE='241',
 XY='(-325,2400)',
 ROT='0',
 VER='1',
 PACK_TYPE='0402LF',
 CDS_LIB='pure_quanta',
 CDS_PART_NAME='Q_RES_0402LF-33.2,1%,1/16W,CHIA',
 WATTAGE='1/16W',
 TOLERANCE='1%',
 MATERIAL='CHIP',
 VALUE='33.2',
 PRIM_FILE='./archive_libs/logical/q_res/chips/chips.prt';

PART_NAME
 R2451 'Q_RES_0402LF-10K,1%,1/16W,EMPTA':;

SECTION_NUMBER 1
 '@S9S_MB_2U_LIB.S9S_MB_2U(SCH_1):PAGE190_I94@PURE_QUANTA.Q_RES(CHIPS)':
 C_PATH='@s9s_mb_2u_lib.s9s_mb_2u(sch_1):page190_i94@pure_quanta.q_res(chips)',
 P_PATH='@s9s_mb_2u_lib.s9s_mb_2u(sch_1):page202_i94@pure_quanta.q_res(chips)',
 PATH='I94',
 DRAWING='@S9S_MB_2U_LIB.S9S_MB_2U(SCH_1):PAGE190',
 PHYS_PAGE='202',
 XY='(25,1675)',
 ROT='0',
 VER='2',
 PACK_TYPE='0402LF',
 CDS_LIB='pure_quanta',
 CDS_PART_NAME='Q_RES_0402LF-10K,1%,1/16W,EMPTA',
 WATTAGE='1/16W',
 TOLERANCE='1%',
 MATERIAL='EMPTY',
 VALUE='10K',
 PRIM_FILE='./archive_libs/logical/q_res/chips/chips.prt';

PART_NAME
 R2452 'Q_RES_0402LF-0,5%,1/16W,CHIP,CA':;

SECTION_NUMBER 1
 '@S9S_MB_2U_LIB.S9S_MB_2U(SCH_1):PAGE313_I84@PURE_QUANTA.Q_RES(CHIPS)':
 C_PATH='@s9s_mb_2u_lib.s9s_mb_2u(sch_1):page313_i84@pure_quanta.q_res(chips)',
 P_PATH='@s9s_mb_2u_lib.s9s_mb_2u(sch_1):page214_i84@pure_quanta.q_res(chips)',
 PATH='I84',
 DRAWING='@S9S_MB_2U_LIB.S9S_MB_2U(SCH_1):PAGE313',
 PHYS_PAGE='214',
 XY='(2675,-1600)',
 ROT='0',
 VER='1',
 PACK_TYPE='0402LF',
 CDS_LIB='pure_quanta',
 CDS_PART_NAME='Q_RES_0402LF-0,5%,1/16W,CHIP,CA',
 WATTAGE='1/16W',
 TOLERANCE='5%',
 MATERIAL='CHIP',
 VALUE='0',
 PRIM_FILE='./archive_libs/logical/q_res/chips/chips.prt';

PART_NAME
 R2453 'Q_RES_0402LF-33.2,1%,1/16W,CHIA':;

SECTION_NUMBER 1
 '@S9S_MB_2U_LIB.S9S_MB_2U(SCH_1):PAGE228_I219@PURE_QUANTA.Q_RES(CHIPS)':
 C_PATH='@s9s_mb_2u_lib.s9s_mb_2u(sch_1):page228_i219@pure_quanta.q_res(chips)',
 P_PATH='@s9s_mb_2u_lib.s9s_mb_2u(sch_1):page241_i219@pure_quanta.q_res(chips)',
 PATH='I219',
 DRAWING='@S9S_MB_2U_LIB.S9S_MB_2U(SCH_1):PAGE228',
 PHYS_PAGE='241',
 XY='(-350,2125)',
 ROT='0',
 VER='1',
 PACK_TYPE='0402LF',
 CDS_LIB='pure_quanta',
 CDS_PART_NAME='Q_RES_0402LF-33.2,1%,1/16W,CHIA',
 WATTAGE='1/16W',
 TOLERANCE='1%',
 MATERIAL='CHIP',
 VALUE='33.2',
 PRIM_FILE='./archive_libs/logical/q_res/chips/chips.prt';

PART_NAME
 R2454 'Q_RES_0402LF-33.2,1%,1/16W,CHIA':;

SECTION_NUMBER 1
 '@S9S_MB_2U_LIB.S9S_MB_2U(SCH_1):PAGE228_I218@PURE_QUANTA.Q_RES(CHIPS)':
 C_PATH='@s9s_mb_2u_lib.s9s_mb_2u(sch_1):page228_i218@pure_quanta.q_res(chips)',
 P_PATH='@s9s_mb_2u_lib.s9s_mb_2u(sch_1):page241_i218@pure_quanta.q_res(chips)',
 PATH='I218',
 DRAWING='@S9S_MB_2U_LIB.S9S_MB_2U(SCH_1):PAGE228',
 PHYS_PAGE='241',
 XY='(-350,2075)',
 ROT='0',
 VER='1',
 PACK_TYPE='0402LF',
 CDS_LIB='pure_quanta',
 CDS_PART_NAME='Q_RES_0402LF-33.2,1%,1/16W,CHIA',
 WATTAGE='1/16W',
 TOLERANCE='1%',
 MATERIAL='CHIP',
 VALUE='33.2',
 PRIM_FILE='./archive_libs/logical/q_res/chips/chips.prt';

PART_NAME
 R2455 'Q_RES_0402LF-33.2,1%,1/16W,CHIA':;

SECTION_NUMBER 1
 '@S9S_MB_2U_LIB.S9S_MB_2U(SCH_1):PAGE228_I217@PURE_QUANTA.Q_RES(CHIPS)':
 C_PATH='@s9s_mb_2u_lib.s9s_mb_2u(sch_1):page228_i217@pure_quanta.q_res(chips)',
 P_PATH='@s9s_mb_2u_lib.s9s_mb_2u(sch_1):page241_i217@pure_quanta.q_res(chips)',
 PATH='I217',
 DRAWING='@S9S_MB_2U_LIB.S9S_MB_2U(SCH_1):PAGE228',
 PHYS_PAGE='241',
 XY='(-350,1850)',
 ROT='0',
 VER='1',
 PACK_TYPE='0402LF',
 CDS_LIB='pure_quanta',
 CDS_PART_NAME='Q_RES_0402LF-33.2,1%,1/16W,CHIA',
 WATTAGE='1/16W',
 TOLERANCE='1%',
 MATERIAL='CHIP',
 VALUE='33.2',
 PRIM_FILE='./archive_libs/logical/q_res/chips/chips.prt';

PART_NAME
 R2456 'Q_RES_0402LF-33.2,1%,1/16W,CHIA':;

SECTION_NUMBER 1
 '@S9S_MB_2U_LIB.S9S_MB_2U(SCH_1):PAGE228_I216@PURE_QUANTA.Q_RES(CHIPS)':
 C_PATH='@s9s_mb_2u_lib.s9s_mb_2u(sch_1):page228_i216@pure_quanta.q_res(chips)',
 P_PATH='@s9s_mb_2u_lib.s9s_mb_2u(sch_1):page241_i216@pure_quanta.q_res(chips)',
 PATH='I216',
 DRAWING='@S9S_MB_2U_LIB.S9S_MB_2U(SCH_1):PAGE228',
 PHYS_PAGE='241',
 XY='(-350,1800)',
 ROT='0',
 VER='1',
 PACK_TYPE='0402LF',
 CDS_LIB='pure_quanta',
 CDS_PART_NAME='Q_RES_0402LF-33.2,1%,1/16W,CHIA',
 WATTAGE='1/16W',
 TOLERANCE='1%',
 MATERIAL='CHIP',
 VALUE='33.2',
 PRIM_FILE='./archive_libs/logical/q_res/chips/chips.prt';

PART_NAME
 R2457 'Q_RES_0402LF-100K,1%,1/16W,CHIA':;

SECTION_NUMBER 1
 '@S9S_MB_2U_LIB.S9S_MB_2U(SCH_1):PAGE297_I165@PURE_QUANTA.Q_RES(CHIPS)':
 C_PATH='@s9s_mb_2u_lib.s9s_mb_2u(sch_1):page297_i165@pure_quanta.q_res(chips)',
 P_PATH='@s9s_mb_2u_lib.s9s_mb_2u(sch_1):page191_i165@pure_quanta.q_res(chips)',
 PATH='I165',
 DRAWING='@S9S_MB_2U_LIB.S9S_MB_2U(SCH_1):PAGE297',
 PHYS_PAGE='191',
 XY='(4350,650)',
 ROT='0',
 VER='2',
 PACK_TYPE='0402LF',
 CDS_LIB='pure_quanta',
 CDS_PART_NAME='Q_RES_0402LF-100K,1%,1/16W,CHIA',
 WATTAGE='1/16W',
 TOLERANCE='1%',
 MATERIAL='CHIP',
 VALUE='100K',
 PRIM_FILE='./archive_libs/logical/q_res/chips/chips.prt';

PART_NAME
 R2473 'Q_RES_0402LF-49.9,1%,1/16W,CHIA':;

SECTION_NUMBER 1
 '@S9S_MB_2U_LIB.S9S_MB_2U(SCH_1):PAGE151_I83@PURE_QUANTA.Q_RES(CHIPS)':
 C_PATH='@s9s_mb_2u_lib.s9s_mb_2u(sch_1):page151_i83@pure_quanta.q_res(chips)',
 P_PATH='@s9s_mb_2u_lib.s9s_mb_2u(sch_1):page154_i83@pure_quanta.q_res(chips)',
 PATH='I83',
 DRAWING='@S9S_MB_2U_LIB.S9S_MB_2U(SCH_1):PAGE151',
 PHYS_PAGE='154',
 XY='(-1825,3725)',
 ROT='0',
 VER='1',
 PACK_TYPE='0402LF',
 LOCATION='R2473',
 CDS_LIB='pure_quanta',
 CDS_PART_NAME='Q_RES_0402LF-49.9,1%,1/16W,CHIA',
 WATTAGE='1/16W',
 TOLERANCE='1%',
 MATERIAL='CHIP',
 VALUE='49.9',
 PRIM_FILE='./archive_libs/logical/q_res/chips/chips.prt';

PART_NAME
 R2474 'Q_RES_0402LF-0,5%,1/16W,EMPTY,A':;

SECTION_NUMBER 1
 '@S9S_MB_2U_LIB.S9S_MB_2U(SCH_1):PAGE151_I19@PURE_QUANTA.Q_RES(CHIPS)':
 C_PATH='@s9s_mb_2u_lib.s9s_mb_2u(sch_1):page151_i19@pure_quanta.q_res(chips)',
 P_PATH='@s9s_mb_2u_lib.s9s_mb_2u(sch_1):page154_i19@pure_quanta.q_res(chips)',
 PATH='I19',
 DRAWING='@S9S_MB_2U_LIB.S9S_MB_2U(SCH_1):PAGE151',
 PHYS_PAGE='154',
 XY='(-1900,3200)',
 ROT='0',
 VER='1',
 PACK_TYPE='0402LF',
 CDS_LIB='pure_quanta',
 CDS_PART_NAME='Q_RES_0402LF-0,5%,1/16W,EMPTY,A',
 WATTAGE='1/16W',
 TOLERANCE='5%',
 MATERIAL='EMPTY',
 VALUE='0',
 PRIM_FILE='./archive_libs/logical/q_res/chips/chips.prt';

PART_NAME
 R2476 'Q_RES_0402LF-200K,1%,1/16W,EMPA':;

SECTION_NUMBER 1
 '@S9S_MB_2U_LIB.S9S_MB_2U(SCH_1):PAGE183_I70@PURE_QUANTA.Q_RES(CHIPS)':
 C_PATH='@s9s_mb_2u_lib.s9s_mb_2u(sch_1):page183_i70@pure_quanta.q_res(chips)',
 P_PATH='@s9s_mb_2u_lib.s9s_mb_2u(sch_1):page194_i70@pure_quanta.q_res(chips)',
 PATH='I70',
 DRAWING='@S9S_MB_2U_LIB.S9S_MB_2U(SCH_1):PAGE183',
 PHYS_PAGE='194',
 XY='(2300,3100)',
 ROT='0',
 VER='1',
 PACK_TYPE='0402LF',
 CDS_LIB='pure_quanta',
 CDS_PART_NAME='Q_RES_0402LF-200K,1%,1/16W,EMPA',
 WATTAGE='1/16W',
 TOLERANCE='1%',
 MATERIAL='EMPTY',
 VALUE='200K',
 PRIM_FILE='./archive_libs/logical/q_res/chips/chips.prt';

PART_NAME
 R2477 'Q_RES_0402LF-33.2,1%,1/16W,CHIA':;

SECTION_NUMBER 1
 '@S9S_MB_2U_LIB.S9S_MB_2U(SCH_1):PAGE223_I88@PURE_QUANTA.Q_RES(CHIPS)':
 C_PATH='@s9s_mb_2u_lib.s9s_mb_2u(sch_1):page223_i88@pure_quanta.q_res(chips)',
 P_PATH='@s9s_mb_2u_lib.s9s_mb_2u(sch_1):page235_i88@pure_quanta.q_res(chips)',
 PATH='I88',
 DRAWING='@S9S_MB_2U_LIB.S9S_MB_2U(SCH_1):PAGE223',
 PHYS_PAGE='235',
 XY='(-2000,7125)',
 ROT='0',
 VER='1',
 PACK_TYPE='0402LF',
 CDS_LIB='pure_quanta',
 CDS_PART_NAME='Q_RES_0402LF-33.2,1%,1/16W,CHIA',
 WATTAGE='1/16W',
 TOLERANCE='1%',
 MATERIAL='CHIP',
 VALUE='33.2',
 PRIM_FILE='./archive_libs/logical/q_res/chips/chips.prt';

PART_NAME
 R2478 'Q_RES_0402LF-33.2,1%,1/16W,CHIA':;

SECTION_NUMBER 1
 '@S9S_MB_2U_LIB.S9S_MB_2U(SCH_1):PAGE223_I89@PURE_QUANTA.Q_RES(CHIPS)':
 C_PATH='@s9s_mb_2u_lib.s9s_mb_2u(sch_1):page223_i89@pure_quanta.q_res(chips)',
 P_PATH='@s9s_mb_2u_lib.s9s_mb_2u(sch_1):page235_i89@pure_quanta.q_res(chips)',
 PATH='I89',
 DRAWING='@S9S_MB_2U_LIB.S9S_MB_2U(SCH_1):PAGE223',
 PHYS_PAGE='235',
 XY='(-2000,7025)',
 ROT='0',
 VER='1',
 PACK_TYPE='0402LF',
 CDS_LIB='pure_quanta',
 CDS_PART_NAME='Q_RES_0402LF-33.2,1%,1/16W,CHIA',
 WATTAGE='1/16W',
 TOLERANCE='1%',
 MATERIAL='CHIP',
 VALUE='33.2',
 PRIM_FILE='./archive_libs/logical/q_res/chips/chips.prt';

PART_NAME
 R2479 'Q_RES_0402LF-33.2,1%,1/16W,CHIA':;

SECTION_NUMBER 1
 '@S9S_MB_2U_LIB.S9S_MB_2U(SCH_1):PAGE223_I76@PURE_QUANTA.Q_RES(CHIPS)':
 C_PATH='@s9s_mb_2u_lib.s9s_mb_2u(sch_1):page223_i76@pure_quanta.q_res(chips)',
 P_PATH='@s9s_mb_2u_lib.s9s_mb_2u(sch_1):page235_i76@pure_quanta.q_res(chips)',
 PATH='I76',
 DRAWING='@S9S_MB_2U_LIB.S9S_MB_2U(SCH_1):PAGE223',
 PHYS_PAGE='235',
 XY='(-2000,5525)',
 ROT='0',
 VER='1',
 PACK_TYPE='0402LF',
 CDS_LIB='pure_quanta',
 CDS_PART_NAME='Q_RES_0402LF-33.2,1%,1/16W,CHIA',
 WATTAGE='1/16W',
 TOLERANCE='1%',
 MATERIAL='CHIP',
 VALUE='33.2',
 PRIM_FILE='./archive_libs/logical/q_res/chips/chips.prt';

PART_NAME
 R2480 'Q_RES_0402LF-33.2,1%,1/16W,CHIA':;

SECTION_NUMBER 1
 '@S9S_MB_2U_LIB.S9S_MB_2U(SCH_1):PAGE223_I77@PURE_QUANTA.Q_RES(CHIPS)':
 C_PATH='@s9s_mb_2u_lib.s9s_mb_2u(sch_1):page223_i77@pure_quanta.q_res(chips)',
 P_PATH='@s9s_mb_2u_lib.s9s_mb_2u(sch_1):page235_i77@pure_quanta.q_res(chips)',
 PATH='I77',
 DRAWING='@S9S_MB_2U_LIB.S9S_MB_2U(SCH_1):PAGE223',
 PHYS_PAGE='235',
 XY='(-2000,5425)',
 ROT='0',
 VER='1',
 PACK_TYPE='0402LF',
 CDS_LIB='pure_quanta',
 CDS_PART_NAME='Q_RES_0402LF-33.2,1%,1/16W,CHIA',
 WATTAGE='1/16W',
 TOLERANCE='1%',
 MATERIAL='CHIP',
 VALUE='33.2',
 PRIM_FILE='./archive_libs/logical/q_res/chips/chips.prt';

PART_NAME
 R2481 'Q_RES_0402LF-4.75K,1%,1/16W,EMA':;

SECTION_NUMBER 1
 '@S9S_MB_2U_LIB.S9S_MB_2U(SCH_1):PAGE197_I280@PURE_QUANTA.Q_RES(CHIPS)':
 C_PATH='@s9s_mb_2u_lib.s9s_mb_2u(sch_1):page197_i280@pure_quanta.q_res(chips)',
 P_PATH='@s9s_mb_2u_lib.s9s_mb_2u(sch_1):page208_i280@pure_quanta.q_res(chips)',
 PATH='I280',
 DRAWING='@S9S_MB_2U_LIB.S9S_MB_2U(SCH_1):PAGE197',
 PHYS_PAGE='208',
 XY='(-5625,10725)',
 ROT='0',
 VER='2',
 PACK_TYPE='0402LF',
 CDS_LIB='pure_quanta',
 CDS_PART_NAME='Q_RES_0402LF-4.75K,1%,1/16W,EMA',
 WATTAGE='1/16W',
 TOLERANCE='1%',
 MATERIAL='EMPTY',
 VALUE='4.75K',
 PRIM_FILE='./archive_libs/logical/q_res/chips/chips.prt';

PART_NAME
 R2486 'Q_RES_0402LF-10K,1%,1/16W,CHIPA':;

SECTION_NUMBER 1
 '@S9S_MB_2U_LIB.S9S_MB_2U(SCH_1):PAGE232_I40@PURE_QUANTA.Q_RES(CHIPS)':
 C_PATH='@s9s_mb_2u_lib.s9s_mb_2u(sch_1):page232_i40@pure_quanta.q_res(chips)',
 P_PATH='@s9s_mb_2u_lib.s9s_mb_2u(sch_1):page244_i40@pure_quanta.q_res(chips)',
 PATH='I40',
 DRAWING='@S9S_MB_2U_LIB.S9S_MB_2U(SCH_1):PAGE232',
 PHYS_PAGE='244',
 XY='(875,-150)',
 ROT='0',
 VER='2',
 PACK_TYPE='0402LF',
 CDS_LIB='pure_quanta',
 CDS_PART_NAME='Q_RES_0402LF-10K,1%,1/16W,CHIPA',
 WATTAGE='1/16W',
 TOLERANCE='1%',
 MATERIAL='CHIP',
 VALUE='10K',
 PRIM_FILE='./archive_libs/logical/q_res/chips/chips.prt';

PART_NAME
 R2487 'Q_RES_0402LF-4.7K,1%,1/16W,EMPA':;

SECTION_NUMBER 1
 '@S9S_MB_2U_LIB.S9S_MB_2U(SCH_1):PAGE152_I71@PURE_QUANTA.Q_RES(CHIPS)':
 C_PATH='@s9s_mb_2u_lib.s9s_mb_2u(sch_1):page152_i71@pure_quanta.q_res(chips)',
 P_PATH='@s9s_mb_2u_lib.s9s_mb_2u(sch_1):page155_i71@pure_quanta.q_res(chips)',
 PATH='I71',
 DRAWING='@S9S_MB_2U_LIB.S9S_MB_2U(SCH_1):PAGE152',
 PHYS_PAGE='155',
 XY='(-3950,4450)',
 ROT='0',
 VER='2',
 PACK_TYPE='0402LF',
 CDS_LIB='pure_quanta',
 CDS_PART_NAME='Q_RES_0402LF-4.7K,1%,1/16W,EMPA',
 WATTAGE='1/16W',
 TOLERANCE='1%',
 MATERIAL='EMPTY',
 VALUE='4.7K',
 PRIM_FILE='./archive_libs/logical/q_res/chips/chips.prt';

PART_NAME
 R2488 'Q_RES_0402LF-4.7K,1%,1/16W,CHIA':;

SECTION_NUMBER 1
 '@S9S_MB_2U_LIB.S9S_MB_2U(SCH_1):PAGE152_I74@PURE_QUANTA.Q_RES(CHIPS)':
 C_PATH='@s9s_mb_2u_lib.s9s_mb_2u(sch_1):page152_i74@pure_quanta.q_res(chips)',
 P_PATH='@s9s_mb_2u_lib.s9s_mb_2u(sch_1):page155_i74@pure_quanta.q_res(chips)',
 PATH='I74',
 DRAWING='@S9S_MB_2U_LIB.S9S_MB_2U(SCH_1):PAGE152',
 PHYS_PAGE='155',
 XY='(-7225,4550)',
 ROT='0',
 VER='2',
 PACK_TYPE='0402LF',
 CDS_LIB='pure_quanta',
 CDS_PART_NAME='Q_RES_0402LF-4.7K,1%,1/16W,CHIA',
 WATTAGE='1/16W',
 TOLERANCE='1%',
 MATERIAL='CHIP',
 VALUE='4.7K',
 PRIM_FILE='./archive_libs/logical/q_res/chips/chips.prt';

PART_NAME
 R2489 'Q_RES_0402LF-33.2,1%,1/16W,CHIA':;

SECTION_NUMBER 1
 '@S9S_MB_2U_LIB.S9S_MB_2U(SCH_1):PAGE152_I75@PURE_QUANTA.Q_RES(CHIPS)':
 C_PATH='@s9s_mb_2u_lib.s9s_mb_2u(sch_1):page152_i75@pure_quanta.q_res(chips)',
 P_PATH='@s9s_mb_2u_lib.s9s_mb_2u(sch_1):page155_i75@pure_quanta.q_res(chips)',
 PATH='I75',
 DRAWING='@S9S_MB_2U_LIB.S9S_MB_2U(SCH_1):PAGE152',
 PHYS_PAGE='155',
 XY='(-3650,4000)',
 ROT='0',
 VER='1',
 PACK_TYPE='0402LF',
 CDS_LIB='pure_quanta',
 CDS_PART_NAME='Q_RES_0402LF-33.2,1%,1/16W,CHIA',
 WATTAGE='1/16W',
 TOLERANCE='1%',
 MATERIAL='CHIP',
 VALUE='33.2',
 PRIM_FILE='./archive_libs/logical/q_res/chips/chips.prt';

PART_NAME
 R2490 'Q_RES_0402LF-1K,1%,1/16W,CHIP,A':;

SECTION_NUMBER 1
 '@S9S_MB_2U_LIB.S9S_MB_2U(SCH_1):PAGE115_I46@PURE_QUANTA.Q_RES(CHIPS)':
 C_PATH='@s9s_mb_2u_lib.s9s_mb_2u(sch_1):page115_i46@pure_quanta.q_res(chips)',
 P_PATH='@s9s_mb_2u_lib.s9s_mb_2u(sch_1):page115_i46@pure_quanta.q_res(chips)',
 PATH='I46',
 DRAWING='@S9S_MB_2U_LIB.S9S_MB_2U(SCH_1):PAGE115',
 PHYS_PAGE='115',
 XY='(1825,1975)',
 ROT='0',
 VER='1',
 PACK_TYPE='0402LF',
 CDS_LIB='pure_quanta',
 CDS_PART_NAME='Q_RES_0402LF-1K,1%,1/16W,CHIP,A',
 WATTAGE='1/16W',
 TOLERANCE='1%',
 MATERIAL='CHIP',
 VALUE='1K',
 PRIM_FILE='./archive_libs/logical/q_res/chips/chips.prt';

PART_NAME
 R2491 'Q_RES_0402LF-1K,1%,1/16W,CHIP,A':;

SECTION_NUMBER 1
 '@S9S_MB_2U_LIB.S9S_MB_2U(SCH_1):PAGE115_I42@PURE_QUANTA.Q_RES(CHIPS)':
 C_PATH='@s9s_mb_2u_lib.s9s_mb_2u(sch_1):page115_i42@pure_quanta.q_res(chips)',
 P_PATH='@s9s_mb_2u_lib.s9s_mb_2u(sch_1):page115_i42@pure_quanta.q_res(chips)',
 PATH='I42',
 DRAWING='@S9S_MB_2U_LIB.S9S_MB_2U(SCH_1):PAGE115',
 PHYS_PAGE='115',
 XY='(1825,1350)',
 ROT='0',
 VER='1',
 PACK_TYPE='0402LF',
 CDS_LIB='pure_quanta',
 CDS_PART_NAME='Q_RES_0402LF-1K,1%,1/16W,CHIP,A',
 WATTAGE='1/16W',
 TOLERANCE='1%',
 MATERIAL='CHIP',
 VALUE='1K',
 PRIM_FILE='./archive_libs/logical/q_res/chips/chips.prt';

PART_NAME
 R2492 'Q_RES_0402LF-1K,1%,1/16W,CHIP,A':;

SECTION_NUMBER 1
 '@S9S_MB_2U_LIB.S9S_MB_2U(SCH_1):PAGE115_I41@PURE_QUANTA.Q_RES(CHIPS)':
 C_PATH='@s9s_mb_2u_lib.s9s_mb_2u(sch_1):page115_i41@pure_quanta.q_res(chips)',
 P_PATH='@s9s_mb_2u_lib.s9s_mb_2u(sch_1):page115_i41@pure_quanta.q_res(chips)',
 PATH='I41',
 DRAWING='@S9S_MB_2U_LIB.S9S_MB_2U(SCH_1):PAGE115',
 PHYS_PAGE='115',
 XY='(1825,725)',
 ROT='0',
 VER='1',
 PACK_TYPE='0402LF',
 CDS_LIB='pure_quanta',
 CDS_PART_NAME='Q_RES_0402LF-1K,1%,1/16W,CHIP,A',
 WATTAGE='1/16W',
 TOLERANCE='1%',
 MATERIAL='CHIP',
 VALUE='1K',
 PRIM_FILE='./archive_libs/logical/q_res/chips/chips.prt';

PART_NAME
 R2493 'Q_RES_0402LF-1K,1%,1/16W,CHIP,A':;

SECTION_NUMBER 1
 '@S9S_MB_2U_LIB.S9S_MB_2U(SCH_1):PAGE115_I38@PURE_QUANTA.Q_RES(CHIPS)':
 C_PATH='@s9s_mb_2u_lib.s9s_mb_2u(sch_1):page115_i38@pure_quanta.q_res(chips)',
 P_PATH='@s9s_mb_2u_lib.s9s_mb_2u(sch_1):page115_i38@pure_quanta.q_res(chips)',
 PATH='I38',
 DRAWING='@S9S_MB_2U_LIB.S9S_MB_2U(SCH_1):PAGE115',
 PHYS_PAGE='115',
 XY='(1825,100)',
 ROT='0',
 VER='1',
 PACK_TYPE='0402LF',
 CDS_LIB='pure_quanta',
 CDS_PART_NAME='Q_RES_0402LF-1K,1%,1/16W,CHIP,A',
 WATTAGE='1/16W',
 TOLERANCE='1%',
 MATERIAL='CHIP',
 VALUE='1K',
 PRIM_FILE='./archive_libs/logical/q_res/chips/chips.prt';

PART_NAME
 R2494 'Q_RES_0402LF-1K,1%,1/16W,CHIP,A':;

SECTION_NUMBER 1
 '@S9S_MB_2U_LIB.S9S_MB_2U(SCH_1):PAGE115_I18@PURE_QUANTA.Q_RES(CHIPS)':
 C_PATH='@s9s_mb_2u_lib.s9s_mb_2u(sch_1):page115_i18@pure_quanta.q_res(chips)',
 P_PATH='@s9s_mb_2u_lib.s9s_mb_2u(sch_1):page115_i18@pure_quanta.q_res(chips)',
 PATH='I18',
 DRAWING='@S9S_MB_2U_LIB.S9S_MB_2U(SCH_1):PAGE115',
 PHYS_PAGE='115',
 XY='(1825,-875)',
 ROT='0',
 VER='1',
 PACK_TYPE='0402LF',
 CDS_LIB='pure_quanta',
 CDS_PART_NAME='Q_RES_0402LF-1K,1%,1/16W,CHIP,A',
 WATTAGE='1/16W',
 TOLERANCE='1%',
 MATERIAL='CHIP',
 VALUE='1K',
 PRIM_FILE='./archive_libs/logical/q_res/chips/chips.prt';

PART_NAME
 R2495 'Q_RES_0402LF-1K,1%,1/16W,CHIP,A':;

SECTION_NUMBER 1
 '@S9S_MB_2U_LIB.S9S_MB_2U(SCH_1):PAGE115_I17@PURE_QUANTA.Q_RES(CHIPS)':
 C_PATH='@s9s_mb_2u_lib.s9s_mb_2u(sch_1):page115_i17@pure_quanta.q_res(chips)',
 P_PATH='@s9s_mb_2u_lib.s9s_mb_2u(sch_1):page115_i17@pure_quanta.q_res(chips)',
 PATH='I17',
 DRAWING='@S9S_MB_2U_LIB.S9S_MB_2U(SCH_1):PAGE115',
 PHYS_PAGE='115',
 XY='(1825,-1500)',
 ROT='0',
 VER='1',
 PACK_TYPE='0402LF',
 CDS_LIB='pure_quanta',
 CDS_PART_NAME='Q_RES_0402LF-1K,1%,1/16W,CHIP,A',
 WATTAGE='1/16W',
 TOLERANCE='1%',
 MATERIAL='CHIP',
 VALUE='1K',
 PRIM_FILE='./archive_libs/logical/q_res/chips/chips.prt';

PART_NAME
 R2496 'Q_RES_0402LF-1K,1%,1/16W,CHIP,A':;

SECTION_NUMBER 1
 '@S9S_MB_2U_LIB.S9S_MB_2U(SCH_1):PAGE115_I12@PURE_QUANTA.Q_RES(CHIPS)':
 C_PATH='@s9s_mb_2u_lib.s9s_mb_2u(sch_1):page115_i12@pure_quanta.q_res(chips)',
 P_PATH='@s9s_mb_2u_lib.s9s_mb_2u(sch_1):page115_i12@pure_quanta.q_res(chips)',
 PATH='I12',
 DRAWING='@S9S_MB_2U_LIB.S9S_MB_2U(SCH_1):PAGE115',
 PHYS_PAGE='115',
 XY='(1825,-2125)',
 ROT='0',
 VER='1',
 PACK_TYPE='0402LF',
 CDS_LIB='pure_quanta',
 CDS_PART_NAME='Q_RES_0402LF-1K,1%,1/16W,CHIP,A',
 WATTAGE='1/16W',
 TOLERANCE='1%',
 MATERIAL='CHIP',
 VALUE='1K',
 PRIM_FILE='./archive_libs/logical/q_res/chips/chips.prt';

PART_NAME
 R2497 'Q_RES_0402LF-1K,1%,1/16W,CHIP,A':;

SECTION_NUMBER 1
 '@S9S_MB_2U_LIB.S9S_MB_2U(SCH_1):PAGE115_I9@PURE_QUANTA.Q_RES(CHIPS)':
 C_PATH='@s9s_mb_2u_lib.s9s_mb_2u(sch_1):page115_i9@pure_quanta.q_res(chips)',
 P_PATH='@s9s_mb_2u_lib.s9s_mb_2u(sch_1):page115_i9@pure_quanta.q_res(chips)',
 PATH='I9',
 DRAWING='@S9S_MB_2U_LIB.S9S_MB_2U(SCH_1):PAGE115',
 PHYS_PAGE='115',
 XY='(1825,-2750)',
 ROT='0',
 VER='1',
 PACK_TYPE='0402LF',
 CDS_LIB='pure_quanta',
 CDS_PART_NAME='Q_RES_0402LF-1K,1%,1/16W,CHIP,A',
 WATTAGE='1/16W',
 TOLERANCE='1%',
 MATERIAL='CHIP',
 VALUE='1K',
 PRIM_FILE='./archive_libs/logical/q_res/chips/chips.prt';

PART_NAME
 R2498 'Q_RES_0402LF-33.2,1%,1/16W,CHIA':;

SECTION_NUMBER 1
 '@S9S_MB_2U_LIB.S9S_MB_2U(SCH_1):PAGE115_I72@PURE_QUANTA.Q_RES(CHIPS)':
 C_PATH='@s9s_mb_2u_lib.s9s_mb_2u(sch_1):page115_i72@pure_quanta.q_res(chips)',
 P_PATH='@s9s_mb_2u_lib.s9s_mb_2u(sch_1):page115_i72@pure_quanta.q_res(chips)',
 PATH='I72',
 DRAWING='@S9S_MB_2U_LIB.S9S_MB_2U(SCH_1):PAGE115',
 PHYS_PAGE='115',
 XY='(4075,1975)',
 ROT='0',
 VER='1',
 PACK_TYPE='0402LF',
 LOCATION='R2498',
 CDS_LIB='pure_quanta',
 CDS_PART_NAME='Q_RES_0402LF-33.2,1%,1/16W,CHIA',
 WATTAGE='1/16W',
 TOLERANCE='1%',
 MATERIAL='CHIP',
 VALUE='33.2',
 PRIM_FILE='./archive_libs/logical/q_res/chips/chips.prt';

PART_NAME
 R2499 'Q_RES_0402LF-33.2,1%,1/16W,CHIA':;

SECTION_NUMBER 1
 '@S9S_MB_2U_LIB.S9S_MB_2U(SCH_1):PAGE115_I71@PURE_QUANTA.Q_RES(CHIPS)':
 C_PATH='@s9s_mb_2u_lib.s9s_mb_2u(sch_1):page115_i71@pure_quanta.q_res(chips)',
 P_PATH='@s9s_mb_2u_lib.s9s_mb_2u(sch_1):page115_i71@pure_quanta.q_res(chips)',
 PATH='I71',
 DRAWING='@S9S_MB_2U_LIB.S9S_MB_2U(SCH_1):PAGE115',
 PHYS_PAGE='115',
 XY='(4075,1350)',
 ROT='0',
 VER='1',
 PACK_TYPE='0402LF',
 LOCATION='R2499',
 CDS_LIB='pure_quanta',
 CDS_PART_NAME='Q_RES_0402LF-33.2,1%,1/16W,CHIA',
 WATTAGE='1/16W',
 TOLERANCE='1%',
 MATERIAL='CHIP',
 VALUE='33.2',
 PRIM_FILE='./archive_libs/logical/q_res/chips/chips.prt';

PART_NAME
 R2500 'Q_RES_0402LF-33.2,1%,1/16W,CHIA':;

SECTION_NUMBER 1
 '@S9S_MB_2U_LIB.S9S_MB_2U(SCH_1):PAGE115_I70@PURE_QUANTA.Q_RES(CHIPS)':
 C_PATH='@s9s_mb_2u_lib.s9s_mb_2u(sch_1):page115_i70@pure_quanta.q_res(chips)',
 P_PATH='@s9s_mb_2u_lib.s9s_mb_2u(sch_1):page115_i70@pure_quanta.q_res(chips)',
 PATH='I70',
 DRAWING='@S9S_MB_2U_LIB.S9S_MB_2U(SCH_1):PAGE115',
 PHYS_PAGE='115',
 XY='(4075,725)',
 ROT='0',
 VER='1',
 PACK_TYPE='0402LF',
 LOCATION='R2500',
 CDS_LIB='pure_quanta',
 CDS_PART_NAME='Q_RES_0402LF-33.2,1%,1/16W,CHIA',
 WATTAGE='1/16W',
 TOLERANCE='1%',
 MATERIAL='CHIP',
 VALUE='33.2',
 PRIM_FILE='./archive_libs/logical/q_res/chips/chips.prt';

PART_NAME
 R2501 'Q_RES_0402LF-33.2,1%,1/16W,CHIA':;

SECTION_NUMBER 1
 '@S9S_MB_2U_LIB.S9S_MB_2U(SCH_1):PAGE115_I69@PURE_QUANTA.Q_RES(CHIPS)':
 C_PATH='@s9s_mb_2u_lib.s9s_mb_2u(sch_1):page115_i69@pure_quanta.q_res(chips)',
 P_PATH='@s9s_mb_2u_lib.s9s_mb_2u(sch_1):page115_i69@pure_quanta.q_res(chips)',
 PATH='I69',
 DRAWING='@S9S_MB_2U_LIB.S9S_MB_2U(SCH_1):PAGE115',
 PHYS_PAGE='115',
 XY='(4075,100)',
 ROT='0',
 VER='1',
 PACK_TYPE='0402LF',
 LOCATION='R2501',
 CDS_LIB='pure_quanta',
 CDS_PART_NAME='Q_RES_0402LF-33.2,1%,1/16W,CHIA',
 WATTAGE='1/16W',
 TOLERANCE='1%',
 MATERIAL='CHIP',
 VALUE='33.2',
 PRIM_FILE='./archive_libs/logical/q_res/chips/chips.prt';

PART_NAME
 R2502 'Q_RES_0402LF-33.2,1%,1/16W,CHIA':;

SECTION_NUMBER 1
 '@S9S_MB_2U_LIB.S9S_MB_2U(SCH_1):PAGE115_I68@PURE_QUANTA.Q_RES(CHIPS)':
 C_PATH='@s9s_mb_2u_lib.s9s_mb_2u(sch_1):page115_i68@pure_quanta.q_res(chips)',
 P_PATH='@s9s_mb_2u_lib.s9s_mb_2u(sch_1):page115_i68@pure_quanta.q_res(chips)',
 PATH='I68',
 DRAWING='@S9S_MB_2U_LIB.S9S_MB_2U(SCH_1):PAGE115',
 PHYS_PAGE='115',
 XY='(4075,-875)',
 ROT='0',
 VER='1',
 PACK_TYPE='0402LF',
 LOCATION='R2502',
 CDS_LIB='pure_quanta',
 CDS_PART_NAME='Q_RES_0402LF-33.2,1%,1/16W,CHIA',
 WATTAGE='1/16W',
 TOLERANCE='1%',
 MATERIAL='CHIP',
 VALUE='33.2',
 PRIM_FILE='./archive_libs/logical/q_res/chips/chips.prt';

PART_NAME
 R2503 'Q_RES_0402LF-33.2,1%,1/16W,CHIA':;

SECTION_NUMBER 1
 '@S9S_MB_2U_LIB.S9S_MB_2U(SCH_1):PAGE115_I67@PURE_QUANTA.Q_RES(CHIPS)':
 C_PATH='@s9s_mb_2u_lib.s9s_mb_2u(sch_1):page115_i67@pure_quanta.q_res(chips)',
 P_PATH='@s9s_mb_2u_lib.s9s_mb_2u(sch_1):page115_i67@pure_quanta.q_res(chips)',
 PATH='I67',
 DRAWING='@S9S_MB_2U_LIB.S9S_MB_2U(SCH_1):PAGE115',
 PHYS_PAGE='115',
 XY='(4075,-1500)',
 ROT='0',
 VER='1',
 PACK_TYPE='0402LF',
 LOCATION='R2503',
 CDS_LIB='pure_quanta',
 CDS_PART_NAME='Q_RES_0402LF-33.2,1%,1/16W,CHIA',
 WATTAGE='1/16W',
 TOLERANCE='1%',
 MATERIAL='CHIP',
 VALUE='33.2',
 PRIM_FILE='./archive_libs/logical/q_res/chips/chips.prt';

PART_NAME
 R2504 'Q_RES_0402LF-33.2,1%,1/16W,CHIA':;

SECTION_NUMBER 1
 '@S9S_MB_2U_LIB.S9S_MB_2U(SCH_1):PAGE115_I66@PURE_QUANTA.Q_RES(CHIPS)':
 C_PATH='@s9s_mb_2u_lib.s9s_mb_2u(sch_1):page115_i66@pure_quanta.q_res(chips)',
 P_PATH='@s9s_mb_2u_lib.s9s_mb_2u(sch_1):page115_i66@pure_quanta.q_res(chips)',
 PATH='I66',
 DRAWING='@S9S_MB_2U_LIB.S9S_MB_2U(SCH_1):PAGE115',
 PHYS_PAGE='115',
 XY='(4075,-2125)',
 ROT='0',
 VER='1',
 PACK_TYPE='0402LF',
 LOCATION='R2504',
 CDS_LIB='pure_quanta',
 CDS_PART_NAME='Q_RES_0402LF-33.2,1%,1/16W,CHIA',
 WATTAGE='1/16W',
 TOLERANCE='1%',
 MATERIAL='CHIP',
 VALUE='33.2',
 PRIM_FILE='./archive_libs/logical/q_res/chips/chips.prt';

PART_NAME
 R2505 'Q_RES_0402LF-33.2,1%,1/16W,CHIA':;

SECTION_NUMBER 1
 '@S9S_MB_2U_LIB.S9S_MB_2U(SCH_1):PAGE115_I65@PURE_QUANTA.Q_RES(CHIPS)':
 C_PATH='@s9s_mb_2u_lib.s9s_mb_2u(sch_1):page115_i65@pure_quanta.q_res(chips)',
 P_PATH='@s9s_mb_2u_lib.s9s_mb_2u(sch_1):page115_i65@pure_quanta.q_res(chips)',
 PATH='I65',
 DRAWING='@S9S_MB_2U_LIB.S9S_MB_2U(SCH_1):PAGE115',
 PHYS_PAGE='115',
 XY='(4075,-2750)',
 ROT='0',
 VER='1',
 PACK_TYPE='0402LF',
 LOCATION='R2505',
 CDS_LIB='pure_quanta',
 CDS_PART_NAME='Q_RES_0402LF-33.2,1%,1/16W,CHIA',
 WATTAGE='1/16W',
 TOLERANCE='1%',
 MATERIAL='CHIP',
 VALUE='33.2',
 PRIM_FILE='./archive_libs/logical/q_res/chips/chips.prt';

PART_NAME
 R2506 'Q_RES_0402LF-1K,1%,1/16W,CHIP,A':;

SECTION_NUMBER 1
 '@S9S_MB_2U_LIB.S9S_MB_2U(SCH_1):PAGE226_I87@PURE_QUANTA.Q_RES(CHIPS)':
 C_PATH='@s9s_mb_2u_lib.s9s_mb_2u(sch_1):page226_i87@pure_quanta.q_res(chips)',
 P_PATH='@s9s_mb_2u_lib.s9s_mb_2u(sch_1):page239_i87@pure_quanta.q_res(chips)',
 PATH='I87',
 DRAWING='@S9S_MB_2U_LIB.S9S_MB_2U(SCH_1):PAGE226',
 PHYS_PAGE='239',
 XY='(-8400,3575)',
 ROT='0',
 VER='2',
 PACK_TYPE='0402LF',
 CDS_LIB='pure_quanta',
 CDS_PART_NAME='Q_RES_0402LF-1K,1%,1/16W,CHIP,A',
 WATTAGE='1/16W',
 TOLERANCE='1%',
 MATERIAL='CHIP',
 VALUE='1K',
 PRIM_FILE='./archive_libs/logical/q_res/chips/chips.prt';

PART_NAME
 R2507 'Q_RES_0402LF-1K,1%,1/16W,CHIP,A':;

SECTION_NUMBER 1
 '@S9S_MB_2U_LIB.S9S_MB_2U(SCH_1):PAGE226_I88@PURE_QUANTA.Q_RES(CHIPS)':
 C_PATH='@s9s_mb_2u_lib.s9s_mb_2u(sch_1):page226_i88@pure_quanta.q_res(chips)',
 P_PATH='@s9s_mb_2u_lib.s9s_mb_2u(sch_1):page239_i88@pure_quanta.q_res(chips)',
 PATH='I88',
 DRAWING='@S9S_MB_2U_LIB.S9S_MB_2U(SCH_1):PAGE226',
 PHYS_PAGE='239',
 XY='(-8175,3575)',
 ROT='0',
 VER='2',
 PACK_TYPE='0402LF',
 CDS_LIB='pure_quanta',
 CDS_PART_NAME='Q_RES_0402LF-1K,1%,1/16W,CHIP,A',
 WATTAGE='1/16W',
 TOLERANCE='1%',
 MATERIAL='CHIP',
 VALUE='1K',
 PRIM_FILE='./archive_libs/logical/q_res/chips/chips.prt';

PART_NAME
 R2508 'Q_RES_0402LF-10K,1%,1/16W,EMPTA':;

SECTION_NUMBER 1
 '@S9S_MB_2U_LIB.S9S_MB_2U(SCH_1):PAGE176_I173@PURE_QUANTA.Q_RES(CHIPS)':
 C_PATH='@s9s_mb_2u_lib.s9s_mb_2u(sch_1):page176_i173@pure_quanta.q_res(chips)',
 P_PATH='@s9s_mb_2u_lib.s9s_mb_2u(sch_1):page184_i173@pure_quanta.q_res(chips)',
 PATH='I173',
 DRAWING='@S9S_MB_2U_LIB.S9S_MB_2U(SCH_1):PAGE176',
 PHYS_PAGE='184',
 XY='(-2475,800)',
 ROT='0',
 VER='2',
 PACK_TYPE='0402LF',
 CDS_LIB='pure_quanta',
 CDS_PART_NAME='Q_RES_0402LF-10K,1%,1/16W,EMPTA',
 WATTAGE='1/16W',
 TOLERANCE='1%',
 MATERIAL='EMPTY',
 VALUE='10K',
 PRIM_FILE='./archive_libs/logical/q_res/chips/chips.prt';

PART_NAME
 R2509 'Q_RES_0402LF-1K,1%,1/16W,EMPTYA':;

SECTION_NUMBER 1
 '@S9S_MB_2U_LIB.S9S_MB_2U(SCH_1):PAGE176_I174@PURE_QUANTA.Q_RES(CHIPS)':
 C_PATH='@s9s_mb_2u_lib.s9s_mb_2u(sch_1):page176_i174@pure_quanta.q_res(chips)',
 P_PATH='@s9s_mb_2u_lib.s9s_mb_2u(sch_1):page184_i174@pure_quanta.q_res(chips)',
 PATH='I174',
 DRAWING='@S9S_MB_2U_LIB.S9S_MB_2U(SCH_1):PAGE176',
 PHYS_PAGE='184',
 XY='(-2475,150)',
 ROT='0',
 VER='2',
 PACK_TYPE='0402LF',
 CDS_LIB='pure_quanta',
 CDS_PART_NAME='Q_RES_0402LF-1K,1%,1/16W,EMPTYA',
 WATTAGE='1/16W',
 TOLERANCE='1%',
 MATERIAL='EMPTY',
 VALUE='1K',
 PRIM_FILE='./archive_libs/logical/q_res/chips/chips.prt';

PART_NAME
 R2510 'Q_RES_0402LF-10K,1%,1/16W,EMPTA':;

SECTION_NUMBER 1
 '@S9S_MB_2U_LIB.S9S_MB_2U(SCH_1):PAGE176_I175@PURE_QUANTA.Q_RES(CHIPS)':
 C_PATH='@s9s_mb_2u_lib.s9s_mb_2u(sch_1):page176_i175@pure_quanta.q_res(chips)',
 P_PATH='@s9s_mb_2u_lib.s9s_mb_2u(sch_1):page184_i175@pure_quanta.q_res(chips)',
 PATH='I175',
 DRAWING='@S9S_MB_2U_LIB.S9S_MB_2U(SCH_1):PAGE176',
 PHYS_PAGE='184',
 XY='(-2200,800)',
 ROT='0',
 VER='2',
 PACK_TYPE='0402LF',
 CDS_LIB='pure_quanta',
 CDS_PART_NAME='Q_RES_0402LF-10K,1%,1/16W,EMPTA',
 WATTAGE='1/16W',
 TOLERANCE='1%',
 MATERIAL='EMPTY',
 VALUE='10K',
 PRIM_FILE='./archive_libs/logical/q_res/chips/chips.prt';

PART_NAME
 R2511 'Q_RES_0402LF-1K,1%,1/16W,EMPTYA':;

SECTION_NUMBER 1
 '@S9S_MB_2U_LIB.S9S_MB_2U(SCH_1):PAGE176_I176@PURE_QUANTA.Q_RES(CHIPS)':
 C_PATH='@s9s_mb_2u_lib.s9s_mb_2u(sch_1):page176_i176@pure_quanta.q_res(chips)',
 P_PATH='@s9s_mb_2u_lib.s9s_mb_2u(sch_1):page184_i176@pure_quanta.q_res(chips)',
 PATH='I176',
 DRAWING='@S9S_MB_2U_LIB.S9S_MB_2U(SCH_1):PAGE176',
 PHYS_PAGE='184',
 XY='(-2200,150)',
 ROT='0',
 VER='2',
 PACK_TYPE='0402LF',
 CDS_LIB='pure_quanta',
 CDS_PART_NAME='Q_RES_0402LF-1K,1%,1/16W,EMPTYA',
 WATTAGE='1/16W',
 TOLERANCE='1%',
 MATERIAL='EMPTY',
 VALUE='1K',
 PRIM_FILE='./archive_libs/logical/q_res/chips/chips.prt';

PART_NAME
 R2512 'Q_RES_0402LF-49.9,1%,1/16W,CHIA':;

SECTION_NUMBER 1
 '@S9S_MB_2U_LIB.S9S_MB_2U(SCH_1):PAGE226_I91@PURE_QUANTA.Q_RES(CHIPS)':
 C_PATH='@s9s_mb_2u_lib.s9s_mb_2u(sch_1):page226_i91@pure_quanta.q_res(chips)',
 P_PATH='@s9s_mb_2u_lib.s9s_mb_2u(sch_1):page239_i91@pure_quanta.q_res(chips)',
 PATH='I91',
 DRAWING='@S9S_MB_2U_LIB.S9S_MB_2U(SCH_1):PAGE226',
 PHYS_PAGE='239',
 XY='(-10125,2175)',
 ROT='0',
 VER='2',
 PACK_TYPE='0402LF',
 CDS_LIB='pure_quanta',
 CDS_PART_NAME='Q_RES_0402LF-49.9,1%,1/16W,CHIA',
 WATTAGE='1/16W',
 TOLERANCE='1%',
 MATERIAL='CHIP',
 VALUE='49.9',
 PRIM_FILE='./archive_libs/logical/q_res/chips/chips.prt';

PART_NAME
 R2513 'Q_RES_0402LF-0,5%,1/16W,CHIP,CA':;

SECTION_NUMBER 1
 '@S9S_MB_2U_LIB.S9S_MB_2U(SCH_1):PAGE226_I90@PURE_QUANTA.Q_RES(CHIPS)':
 C_PATH='@s9s_mb_2u_lib.s9s_mb_2u(sch_1):page226_i90@pure_quanta.q_res(chips)',
 P_PATH='@s9s_mb_2u_lib.s9s_mb_2u(sch_1):page239_i90@pure_quanta.q_res(chips)',
 PATH='I90',
 DRAWING='@S9S_MB_2U_LIB.S9S_MB_2U(SCH_1):PAGE226',
 PHYS_PAGE='239',
 XY='(-9450,1725)',
 ROT='0',
 VER='1',
 PACK_TYPE='0402LF',
 CDS_LIB='pure_quanta',
 CDS_PART_NAME='Q_RES_0402LF-0,5%,1/16W,CHIP,CA',
 WATTAGE='1/16W',
 TOLERANCE='5%',
 MATERIAL='CHIP',
 VALUE='0',
 PRIM_FILE='./archive_libs/logical/q_res/chips/chips.prt';

PART_NAME
 R2514 'Q_RES_0402LF-1K,1%,1/16W,EMPTYA':;

SECTION_NUMBER 1
 '@S9S_MB_2U_LIB.S9S_MB_2U(SCH_1):PAGE226_I89@PURE_QUANTA.Q_RES(CHIPS)':
 C_PATH='@s9s_mb_2u_lib.s9s_mb_2u(sch_1):page226_i89@pure_quanta.q_res(chips)',
 P_PATH='@s9s_mb_2u_lib.s9s_mb_2u(sch_1):page239_i89@pure_quanta.q_res(chips)',
 PATH='I89',
 DRAWING='@S9S_MB_2U_LIB.S9S_MB_2U(SCH_1):PAGE226',
 PHYS_PAGE='239',
 XY='(-9400,3300)',
 ROT='0',
 VER='1',
 PACK_TYPE='0402LF',
 CDS_LIB='pure_quanta',
 CDS_PART_NAME='Q_RES_0402LF-1K,1%,1/16W,EMPTYA',
 WATTAGE='1/16W',
 TOLERANCE='1%',
 MATERIAL='EMPTY',
 VALUE='1K',
 PRIM_FILE='./archive_libs/logical/q_res/chips/chips.prt';

PART_NAME
 R2520 'Q_RES_0402LF-0,5%,1/16W,CHIP,CA':;

SECTION_NUMBER 1
 '@S9S_MB_2U_LIB.S9S_MB_2U(SCH_1):PAGE270_I65@PURE_QUANTA.Q_RES(CHIPS)':
 C_PATH='@s9s_mb_2u_lib.s9s_mb_2u(sch_1):page270_i65@pure_quanta.q_res(chips)',
 P_PATH='@s9s_mb_2u_lib.s9s_mb_2u(sch_1):page284_i65@pure_quanta.q_res(chips)',
 PATH='I65',
 DRAWING='@S9S_MB_2U_LIB.S9S_MB_2U(SCH_1):PAGE270',
 PHYS_PAGE='284',
 XY='(-1850,1875)',
 ROT='0',
 VER='1',
 PACK_TYPE='0402LF',
 LOCATION='R2520',
 CDS_LIB='pure_quanta',
 CDS_PART_NAME='Q_RES_0402LF-0,5%,1/16W,CHIP,CA',
 WATTAGE='1/16W',
 TOLERANCE='5%',
 MATERIAL='CHIP',
 VALUE='0',
 PRIM_FILE='./archive_libs/logical/q_res/chips/chips.prt';

PART_NAME
 R2521 'Q_RES_0402LF-0,5%,1/16W,CHIP,CA':;

SECTION_NUMBER 1
 '@S9S_MB_2U_LIB.S9S_MB_2U(SCH_1):PAGE270_I66@PURE_QUANTA.Q_RES(CHIPS)':
 C_PATH='@s9s_mb_2u_lib.s9s_mb_2u(sch_1):page270_i66@pure_quanta.q_res(chips)',
 P_PATH='@s9s_mb_2u_lib.s9s_mb_2u(sch_1):page284_i66@pure_quanta.q_res(chips)',
 PATH='I66',
 DRAWING='@S9S_MB_2U_LIB.S9S_MB_2U(SCH_1):PAGE270',
 PHYS_PAGE='284',
 XY='(-1850,1725)',
 ROT='0',
 VER='1',
 PACK_TYPE='0402LF',
 LOCATION='R2521',
 CDS_LIB='pure_quanta',
 CDS_PART_NAME='Q_RES_0402LF-0,5%,1/16W,CHIP,CA',
 WATTAGE='1/16W',
 TOLERANCE='5%',
 MATERIAL='CHIP',
 VALUE='0',
 PRIM_FILE='./archive_libs/logical/q_res/chips/chips.prt';

PART_NAME
 R2522 'Q_RES_0402LF-1K,1%,1/16W,CHIP,A':;

SECTION_NUMBER 1
 '@S9S_MB_2U_LIB.S9S_MB_2U(SCH_1):PAGE270_I25@PURE_QUANTA.Q_RES(CHIPS)':
 C_PATH='@s9s_mb_2u_lib.s9s_mb_2u(sch_1):page270_i25@pure_quanta.q_res(chips)',
 P_PATH='@s9s_mb_2u_lib.s9s_mb_2u(sch_1):page284_i25@pure_quanta.q_res(chips)',
 PATH='I25',
 DRAWING='@S9S_MB_2U_LIB.S9S_MB_2U(SCH_1):PAGE270',
 PHYS_PAGE='284',
 XY='(-2300,-675)',
 ROT='0',
 VER='1',
 PACK_TYPE='0402LF',
 LOCATION='R2522',
 CDS_LIB='pure_quanta',
 CDS_PART_NAME='Q_RES_0402LF-1K,1%,1/16W,CHIP,A',
 WATTAGE='1/16W',
 TOLERANCE='1%',
 MATERIAL='CHIP',
 VALUE='1K',
 PRIM_FILE='./archive_libs/logical/q_res/chips/chips.prt';

PART_NAME
 R2523 'Q_RES_0402LF-0,5%,1/16W,CHIP,CA':;

SECTION_NUMBER 1
 '@S9S_MB_2U_LIB.S9S_MB_2U(SCH_1):PAGE270_I36@PURE_QUANTA.Q_RES(CHIPS)':
 C_PATH='@s9s_mb_2u_lib.s9s_mb_2u(sch_1):page270_i36@pure_quanta.q_res(chips)',
 P_PATH='@s9s_mb_2u_lib.s9s_mb_2u(sch_1):page284_i36@pure_quanta.q_res(chips)',
 PATH='I36',
 DRAWING='@S9S_MB_2U_LIB.S9S_MB_2U(SCH_1):PAGE270',
 PHYS_PAGE='284',
 XY='(-1650,-825)',
 ROT='0',
 VER='1',
 PACK_TYPE='0402LF',
 LOCATION='R2523',
 CDS_LIB='pure_quanta',
 CDS_PART_NAME='Q_RES_0402LF-0,5%,1/16W,CHIP,CA',
 WATTAGE='1/16W',
 TOLERANCE='5%',
 MATERIAL='CHIP',
 VALUE='0',
 PRIM_FILE='./archive_libs/logical/q_res/chips/chips.prt';

PART_NAME
 R2524 'Q_RES_0402LF-1K,1%,1/16W,CHIP,A':;

SECTION_NUMBER 1
 '@S9S_MB_2U_LIB.S9S_MB_2U(SCH_1):PAGE270_I17@PURE_QUANTA.Q_RES(CHIPS)':
 C_PATH='@s9s_mb_2u_lib.s9s_mb_2u(sch_1):page270_i17@pure_quanta.q_res(chips)',
 P_PATH='@s9s_mb_2u_lib.s9s_mb_2u(sch_1):page284_i17@pure_quanta.q_res(chips)',
 PATH='I17',
 DRAWING='@S9S_MB_2U_LIB.S9S_MB_2U(SCH_1):PAGE270',
 PHYS_PAGE='284',
 XY='(-2300,-975)',
 ROT='0',
 VER='1',
 PACK_TYPE='0402LF',
 LOCATION='R2524',
 CDS_LIB='pure_quanta',
 CDS_PART_NAME='Q_RES_0402LF-1K,1%,1/16W,CHIP,A',
 WATTAGE='1/16W',
 TOLERANCE='1%',
 MATERIAL='CHIP',
 VALUE='1K',
 PRIM_FILE='./archive_libs/logical/q_res/chips/chips.prt';

PART_NAME
 R2525 'Q_RES_0402LF-1K,1%,1/16W,CHIP,A':;

SECTION_NUMBER 1
 '@S9S_MB_2U_LIB.S9S_MB_2U(SCH_1):PAGE270_I18@PURE_QUANTA.Q_RES(CHIPS)':
 C_PATH='@s9s_mb_2u_lib.s9s_mb_2u(sch_1):page270_i18@pure_quanta.q_res(chips)',
 P_PATH='@s9s_mb_2u_lib.s9s_mb_2u(sch_1):page284_i18@pure_quanta.q_res(chips)',
 PATH='I18',
 DRAWING='@S9S_MB_2U_LIB.S9S_MB_2U(SCH_1):PAGE270',
 PHYS_PAGE='284',
 XY='(-2300,-1075)',
 ROT='0',
 VER='1',
 PACK_TYPE='0402LF',
 LOCATION='R2525',
 CDS_LIB='pure_quanta',
 CDS_PART_NAME='Q_RES_0402LF-1K,1%,1/16W,CHIP,A',
 WATTAGE='1/16W',
 TOLERANCE='1%',
 MATERIAL='CHIP',
 VALUE='1K',
 PRIM_FILE='./archive_libs/logical/q_res/chips/chips.prt';

PART_NAME
 R2526 'Q_RES_0402LF-0,5%,1/16W,CHIP,CA':;

SECTION_NUMBER 1
 '@S9S_MB_2U_LIB.S9S_MB_2U(SCH_1):PAGE182_I247@PURE_QUANTA.Q_RES(CHIPS)':
 C_PATH='@s9s_mb_2u_lib.s9s_mb_2u(sch_1):page182_i247@pure_quanta.q_res(chips)',
 P_PATH='@s9s_mb_2u_lib.s9s_mb_2u(sch_1):page190_i247@pure_quanta.q_res(chips)',
 PATH='I247',
 DRAWING='@S9S_MB_2U_LIB.S9S_MB_2U(SCH_1):PAGE182',
 PHYS_PAGE='190',
 XY='(10600,3500)',
 ROT='0',
 VER='1',
 PACK_TYPE='0402LF',
 CDS_LIB='pure_quanta',
 CDS_PART_NAME='Q_RES_0402LF-0,5%,1/16W,CHIP,CA',
 WATTAGE='1/16W',
 TOLERANCE='5%',
 MATERIAL='CHIP',
 VALUE='0',
 PRIM_FILE='./archive_libs/logical/q_res/chips/chips.prt';

PART_NAME
 R2528 'Q_RES_0402LF-100K,1%,1/16W,CHIA':;

SECTION_NUMBER 1
 '@S9S_MB_2U_LIB.S9S_MB_2U(SCH_1):PAGE234_I8@PURE_QUANTA.Q_RES(CHIPS)':
 C_PATH='@s9s_mb_2u_lib.s9s_mb_2u(sch_1):page234_i8@pure_quanta.q_res(chips)',
 P_PATH='@s9s_mb_2u_lib.s9s_mb_2u(sch_1):page247_i8@pure_quanta.q_res(chips)',
 PATH='I8',
 DRAWING='@S9S_MB_2U_LIB.S9S_MB_2U(SCH_1):PAGE234',
 PHYS_PAGE='247',
 XY='(11650,3850)',
 ROT='0',
 VER='2',
 PACK_TYPE='0402LF',
 CDS_LIB='pure_quanta',
 CDS_PART_NAME='Q_RES_0402LF-100K,1%,1/16W,CHIA',
 WATTAGE='1/16W',
 TOLERANCE='1%',
 MATERIAL='CHIP',
 VALUE='100K',
 PRIM_FILE='./archive_libs/logical/q_res/chips/chips.prt';

PART_NAME
 R2529 'Q_RES_0402LF-0,5%,1/16W,CHIP,CA':;

SECTION_NUMBER 1
 '@S9S_MB_2U_LIB.S9S_MB_2U(SCH_1):PAGE234_I7@PURE_QUANTA.Q_RES(CHIPS)':
 C_PATH='@s9s_mb_2u_lib.s9s_mb_2u(sch_1):page234_i7@pure_quanta.q_res(chips)',
 P_PATH='@s9s_mb_2u_lib.s9s_mb_2u(sch_1):page247_i7@pure_quanta.q_res(chips)',
 PATH='I7',
 DRAWING='@S9S_MB_2U_LIB.S9S_MB_2U(SCH_1):PAGE234',
 PHYS_PAGE='247',
 XY='(12575,3450)',
 ROT='0',
 VER='1',
 PACK_TYPE='0402LF',
 CDS_LIB='pure_quanta',
 CDS_PART_NAME='Q_RES_0402LF-0,5%,1/16W,CHIP,CA',
 WATTAGE='1/16W',
 TOLERANCE='5%',
 MATERIAL='CHIP',
 VALUE='0',
 PRIM_FILE='./archive_libs/logical/q_res/chips/chips.prt';

PART_NAME
 R2530 'Q_RES_0402LF-4.7K,5%,1/16W,CHIA':;

SECTION_NUMBER 1
 '@S9S_MB_2U_LIB.S9S_MB_2U(SCH_1):PAGE234_I10@PURE_QUANTA.Q_RES(CHIPS)':
 C_PATH='@s9s_mb_2u_lib.s9s_mb_2u(sch_1):page234_i10@pure_quanta.q_res(chips)',
 P_PATH='@s9s_mb_2u_lib.s9s_mb_2u(sch_1):page247_i10@pure_quanta.q_res(chips)',
 PATH='I10',
 DRAWING='@S9S_MB_2U_LIB.S9S_MB_2U(SCH_1):PAGE234',
 PHYS_PAGE='247',
 XY='(14600,4050)',
 ROT='0',
 VER='2',
 PACK_TYPE='0402LF',
 CDS_LIB='pure_quanta',
 CDS_PART_NAME='Q_RES_0402LF-4.7K,5%,1/16W,CHIA',
 WATTAGE='1/16W',
 TOLERANCE='5%',
 MATERIAL='CHIP',
 VALUE='4.7K',
 PRIM_FILE='./archive_libs/logical/q_res/chips/chips.prt';

PART_NAME
 R2531 'Q_RES_0402LF-0,5%,1/16W,CHIP,CA':;

SECTION_NUMBER 1
 '@S9S_MB_2U_LIB.S9S_MB_2U(SCH_1):PAGE234_I3@PURE_QUANTA.Q_RES(CHIPS)':
 C_PATH='@s9s_mb_2u_lib.s9s_mb_2u(sch_1):page234_i3@pure_quanta.q_res(chips)',
 P_PATH='@s9s_mb_2u_lib.s9s_mb_2u(sch_1):page247_i3@pure_quanta.q_res(chips)',
 PATH='I3',
 DRAWING='@S9S_MB_2U_LIB.S9S_MB_2U(SCH_1):PAGE234',
 PHYS_PAGE='247',
 XY='(10325,3125)',
 ROT='0',
 VER='1',
 PACK_TYPE='0402LF',
 CDS_LIB='pure_quanta',
 CDS_PART_NAME='Q_RES_0402LF-0,5%,1/16W,CHIP,CA',
 WATTAGE='1/16W',
 TOLERANCE='5%',
 MATERIAL='CHIP',
 VALUE='0',
 PRIM_FILE='./archive_libs/logical/q_res/chips/chips.prt';

PART_NAME
 R2550 'Q_RES_0402LF-0,5%,1/16W,CHIP,CA':;

SECTION_NUMBER 1
 '@S9S_MB_2U_LIB.S9S_MB_2U(SCH_1):PAGE270_I19@PURE_QUANTA.Q_RES(CHIPS)':
 C_PATH='@s9s_mb_2u_lib.s9s_mb_2u(sch_1):page270_i19@pure_quanta.q_res(chips)',
 P_PATH='@s9s_mb_2u_lib.s9s_mb_2u(sch_1):page284_i19@pure_quanta.q_res(chips)',
 PATH='I19',
 DRAWING='@S9S_MB_2U_LIB.S9S_MB_2U(SCH_1):PAGE270',
 PHYS_PAGE='284',
 XY='(-2000,-1375)',
 ROT='0',
 VER='1',
 PACK_TYPE='0402LF',
 LOCATION='R2550',
 CDS_LIB='pure_quanta',
 CDS_PART_NAME='Q_RES_0402LF-0,5%,1/16W,CHIP,CA',
 WATTAGE='1/16W',
 TOLERANCE='5%',
 MATERIAL='CHIP',
 VALUE='0',
 PRIM_FILE='./archive_libs/logical/q_res/chips/chips.prt';

PART_NAME
 R2551 'Q_RES_0402LF-1K,1%,1/16W,CHIP,A':;

SECTION_NUMBER 1
 '@S9S_MB_2U_LIB.S9S_MB_2U(SCH_1):PAGE270_I15@PURE_QUANTA.Q_RES(CHIPS)':
 C_PATH='@s9s_mb_2u_lib.s9s_mb_2u(sch_1):page270_i15@pure_quanta.q_res(chips)',
 P_PATH='@s9s_mb_2u_lib.s9s_mb_2u(sch_1):page284_i15@pure_quanta.q_res(chips)',
 PATH='I15',
 DRAWING='@S9S_MB_2U_LIB.S9S_MB_2U(SCH_1):PAGE270',
 PHYS_PAGE='284',
 XY='(-2000,-1625)',
 ROT='0',
 VER='1',
 PACK_TYPE='0402LF',
 LOCATION='R2551',
 CDS_LIB='pure_quanta',
 CDS_PART_NAME='Q_RES_0402LF-1K,1%,1/16W,CHIP,A',
 WATTAGE='1/16W',
 TOLERANCE='1%',
 MATERIAL='CHIP',
 VALUE='1K',
 PRIM_FILE='./archive_libs/logical/q_res/chips/chips.prt';

PART_NAME
 R2552 'Q_RES_0402LF-0,5%,1/16W,CHIP,CA':;

SECTION_NUMBER 1
 '@S9S_MB_2U_LIB.S9S_MB_2U(SCH_1):PAGE270_I16@PURE_QUANTA.Q_RES(CHIPS)':
 C_PATH='@s9s_mb_2u_lib.s9s_mb_2u(sch_1):page270_i16@pure_quanta.q_res(chips)',
 P_PATH='@s9s_mb_2u_lib.s9s_mb_2u(sch_1):page284_i16@pure_quanta.q_res(chips)',
 PATH='I16',
 DRAWING='@S9S_MB_2U_LIB.S9S_MB_2U(SCH_1):PAGE270',
 PHYS_PAGE='284',
 XY='(-2000,-1775)',
 ROT='0',
 VER='1',
 PACK_TYPE='0402LF',
 LOCATION='R2552',
 CDS_LIB='pure_quanta',
 CDS_PART_NAME='Q_RES_0402LF-0,5%,1/16W,CHIP,CA',
 WATTAGE='1/16W',
 TOLERANCE='5%',
 MATERIAL='CHIP',
 VALUE='0',
 PRIM_FILE='./archive_libs/logical/q_res/chips/chips.prt';

PART_NAME
 R2553 'Q_RES_0402LF-100,1%,1/16W,CHIPA':;

SECTION_NUMBER 1
 '@S9S_MB_2U_LIB.S9S_MB_2U(SCH_1):PAGE270_I99@PURE_QUANTA.Q_RES(CHIPS)':
 C_PATH='@s9s_mb_2u_lib.s9s_mb_2u(sch_1):page270_i99@pure_quanta.q_res(chips)',
 P_PATH='@s9s_mb_2u_lib.s9s_mb_2u(sch_1):page284_i99@pure_quanta.q_res(chips)',
 PATH='I99',
 DRAWING='@S9S_MB_2U_LIB.S9S_MB_2U(SCH_1):PAGE270',
 PHYS_PAGE='284',
 XY='(3925,-925)',
 ROT='0',
 VER='1',
 PACK_TYPE='0402LF',
 LOCATION='R2553',
 CDS_LIB='pure_quanta',
 CDS_PART_NAME='Q_RES_0402LF-100,1%,1/16W,CHIPA',
 WATTAGE='1/16W',
 TOLERANCE='1%',
 MATERIAL='CHIP',
 VALUE='100',
 PRIM_FILE='./archive_libs/logical/q_res/chips/chips.prt';

PART_NAME
 R2554 'Q_RES_0402LF-49.9,1%,1/16W,CHIA':;

SECTION_NUMBER 1
 '@S9S_MB_2U_LIB.S9S_MB_2U(SCH_1):PAGE270_I100@PURE_QUANTA.Q_RES(CHIPS)':
 C_PATH='@s9s_mb_2u_lib.s9s_mb_2u(sch_1):page270_i100@pure_quanta.q_res(chips)',
 P_PATH='@s9s_mb_2u_lib.s9s_mb_2u(sch_1):page284_i100@pure_quanta.q_res(chips)',
 PATH='I100',
 DRAWING='@S9S_MB_2U_LIB.S9S_MB_2U(SCH_1):PAGE270',
 PHYS_PAGE='284',
 XY='(3925,-1075)',
 ROT='0',
 VER='1',
 PACK_TYPE='0402LF',
 LOCATION='R2554',
 CDS_LIB='pure_quanta',
 CDS_PART_NAME='Q_RES_0402LF-49.9,1%,1/16W,CHIA',
 WATTAGE='1/16W',
 TOLERANCE='1%',
 MATERIAL='CHIP',
 VALUE='49.9',
 PRIM_FILE='./archive_libs/logical/q_res/chips/chips.prt';

PART_NAME
 R2555 'Q_RES_0402LF-49.9,1%,1/16W,EMPA':;

SECTION_NUMBER 1
 '@S9S_MB_2U_LIB.S9S_MB_2U(SCH_1):PAGE270_I101@PURE_QUANTA.Q_RES(CHIPS)':
 C_PATH='@s9s_mb_2u_lib.s9s_mb_2u(sch_1):page270_i101@pure_quanta.q_res(chips)',
 P_PATH='@s9s_mb_2u_lib.s9s_mb_2u(sch_1):page284_i101@pure_quanta.q_res(chips)',
 PATH='I101',
 DRAWING='@S9S_MB_2U_LIB.S9S_MB_2U(SCH_1):PAGE270',
 PHYS_PAGE='284',
 XY='(3925,-1225)',
 ROT='0',
 VER='1',
 PACK_TYPE='0402LF',
 LOCATION='R2555',
 CDS_LIB='pure_quanta',
 CDS_PART_NAME='Q_RES_0402LF-49.9,1%,1/16W,EMPA',
 WATTAGE='1/16W',
 TOLERANCE='1%',
 MATERIAL='EMPTY',
 VALUE='49.9',
 PRIM_FILE='./archive_libs/logical/q_res/chips/chips.prt';

PART_NAME
 R2556 'Q_RES_0402LF-1K,1%,1/16W,CHIP,A':;

SECTION_NUMBER 1
 '@S9S_MB_2U_LIB.S9S_MB_2U(SCH_1):PAGE278_I105@PURE_QUANTA.Q_RES(CHIPS)':
 C_PATH='@s9s_mb_2u_lib.s9s_mb_2u(sch_1):page278_i105@pure_quanta.q_res(chips)',
 P_PATH='@s9s_mb_2u_lib.s9s_mb_2u(sch_1):page292_i105@pure_quanta.q_res(chips)',
 PATH='I105',
 DRAWING='@S9S_MB_2U_LIB.S9S_MB_2U(SCH_1):PAGE278',
 PHYS_PAGE='292',
 XY='(1175,9300)',
 ROT='0',
 VER='1',
 PACK_TYPE='0402LF',
 LOCATION='R2556',
 CDS_LIB='pure_quanta',
 CDS_PART_NAME='Q_RES_0402LF-1K,1%,1/16W,CHIP,A',
 WATTAGE='1/16W',
 TOLERANCE='1%',
 MATERIAL='CHIP',
 VALUE='1K',
 PRIM_FILE='./archive_libs/logical/q_res/chips/chips.prt';

PART_NAME
 R2557 'Q_RES_0402LF-0,5%,1/16W,CHIP,CA':;

SECTION_NUMBER 1
 '@S9S_MB_2U_LIB.S9S_MB_2U(SCH_1):PAGE282_I58@PURE_QUANTA.Q_RES(CHIPS)':
 C_PATH='@s9s_mb_2u_lib.s9s_mb_2u(sch_1):page282_i58@pure_quanta.q_res(chips)',
 P_PATH='@s9s_mb_2u_lib.s9s_mb_2u(sch_1):page296_i58@pure_quanta.q_res(chips)',
 PATH='I58',
 DRAWING='@S9S_MB_2U_LIB.S9S_MB_2U(SCH_1):PAGE282',
 PHYS_PAGE='296',
 XY='(-800,950)',
 ROT='0',
 VER='1',
 PACK_TYPE='0402LF',
 LOCATION='R2557',
 SEC='1',
 CDS_LIB='pure_quanta',
 CDS_PART_NAME='Q_RES_0402LF-0,5%,1/16W,CHIP,CA',
 SEC_TYPE='0402LF',
 WATTAGE='1/16W',
 TOLERANCE='5%',
 MATERIAL='CHIP',
 VALUE='0',
 PRIM_FILE='./archive_libs/logical/q_res/chips/chips.prt';

PART_NAME
 R2558 'Q_RES_0402LF-0,5%,1/16W,CHIP,CA':;

SECTION_NUMBER 1
 '@S9S_MB_2U_LIB.S9S_MB_2U(SCH_1):PAGE278_I104@PURE_QUANTA.Q_RES(CHIPS)':
 C_PATH='@s9s_mb_2u_lib.s9s_mb_2u(sch_1):page278_i104@pure_quanta.q_res(chips)',
 P_PATH='@s9s_mb_2u_lib.s9s_mb_2u(sch_1):page292_i104@pure_quanta.q_res(chips)',
 PATH='I104',
 DRAWING='@S9S_MB_2U_LIB.S9S_MB_2U(SCH_1):PAGE278',
 PHYS_PAGE='292',
 XY='(1175,9000)',
 ROT='0',
 VER='1',
 PACK_TYPE='0402LF',
 LOCATION='R2558',
 SEC='1',
 CDS_LIB='pure_quanta',
 CDS_PART_NAME='Q_RES_0402LF-0,5%,1/16W,CHIP,CA',
 SEC_TYPE='0402LF',
 WATTAGE='1/16W',
 TOLERANCE='5%',
 MATERIAL='CHIP',
 VALUE='0',
 PRIM_FILE='./archive_libs/logical/q_res/chips/chips.prt';

PART_NAME
 R2559 'Q_RES_0402LF-150,1%,1/16W,CHIPA':;

SECTION_NUMBER 1
 '@S9S_MB_2U_LIB.S9S_MB_2U(SCH_1):PAGE278_I61@PURE_QUANTA.Q_RES(CHIPS)':
 C_PATH='@s9s_mb_2u_lib.s9s_mb_2u(sch_1):page278_i61@pure_quanta.q_res(chips)',
 P_PATH='@s9s_mb_2u_lib.s9s_mb_2u(sch_1):page292_i61@pure_quanta.q_res(chips)',
 PATH='I61',
 DRAWING='@S9S_MB_2U_LIB.S9S_MB_2U(SCH_1):PAGE278',
 PHYS_PAGE='292',
 XY='(1175,8700)',
 ROT='0',
 VER='1',
 PACK_TYPE='0402LF',
 LOCATION='R2559',
 CDS_LIB='pure_quanta',
 CDS_PART_NAME='Q_RES_0402LF-150,1%,1/16W,CHIPA',
 WATTAGE='1/16W',
 TOLERANCE='1%',
 MATERIAL='CHIP',
 VALUE='150',
 PRIM_FILE='./archive_libs/logical/q_res/chips/chips.prt';

PART_NAME
 R2560 'Q_RES_0402LF-0,5%,1/16W,CHIP,CA':;

SECTION_NUMBER 1
 '@S9S_MB_2U_LIB.S9S_MB_2U(SCH_1):PAGE278_I60@PURE_QUANTA.Q_RES(CHIPS)':
 C_PATH='@s9s_mb_2u_lib.s9s_mb_2u(sch_1):page278_i60@pure_quanta.q_res(chips)',
 P_PATH='@s9s_mb_2u_lib.s9s_mb_2u(sch_1):page292_i60@pure_quanta.q_res(chips)',
 PATH='I60',
 DRAWING='@S9S_MB_2U_LIB.S9S_MB_2U(SCH_1):PAGE278',
 PHYS_PAGE='292',
 XY='(1175,8550)',
 ROT='0',
 VER='1',
 PACK_TYPE='0402LF',
 LOCATION='R2560',
 CDS_LIB='pure_quanta',
 CDS_PART_NAME='Q_RES_0402LF-0,5%,1/16W,CHIP,CA',
 WATTAGE='1/16W',
 TOLERANCE='5%',
 MATERIAL='CHIP',
 VALUE='0',
 PRIM_FILE='./archive_libs/logical/q_res/chips/chips.prt';

PART_NAME
 R2561 'Q_RES_0402LF-0,5%,1/16W,CHIP,CA':;

SECTION_NUMBER 1
 '@S9S_MB_2U_LIB.S9S_MB_2U(SCH_1):PAGE278_I59@PURE_QUANTA.Q_RES(CHIPS)':
 C_PATH='@s9s_mb_2u_lib.s9s_mb_2u(sch_1):page278_i59@pure_quanta.q_res(chips)',
 P_PATH='@s9s_mb_2u_lib.s9s_mb_2u(sch_1):page292_i59@pure_quanta.q_res(chips)',
 PATH='I59',
 DRAWING='@S9S_MB_2U_LIB.S9S_MB_2U(SCH_1):PAGE278',
 PHYS_PAGE='292',
 XY='(1175,8400)',
 ROT='0',
 VER='1',
 PACK_TYPE='0402LF',
 LOCATION='R2561',
 CDS_LIB='pure_quanta',
 CDS_PART_NAME='Q_RES_0402LF-0,5%,1/16W,CHIP,CA',
 WATTAGE='1/16W',
 TOLERANCE='5%',
 MATERIAL='CHIP',
 VALUE='0',
 PRIM_FILE='./archive_libs/logical/q_res/chips/chips.prt';

PART_NAME
 R2562 'Q_RES_0402LF-0,5%,1/16W,CHIP,CA':;

SECTION_NUMBER 1
 '@S9S_MB_2U_LIB.S9S_MB_2U(SCH_1):PAGE195_I535@PURE_QUANTA.Q_RES(CHIPS)':
 C_PATH='@s9s_mb_2u_lib.s9s_mb_2u(sch_1):page195_i535@pure_quanta.q_res(chips)',
 P_PATH='@s9s_mb_2u_lib.s9s_mb_2u(sch_1):page206_i535@pure_quanta.q_res(chips)',
 PATH='I535',
 DRAWING='@S9S_MB_2U_LIB.S9S_MB_2U(SCH_1):PAGE195',
 PHYS_PAGE='206',
 XY='(-5300,2000)',
 ROT='0',
 VER='1',
 PACK_TYPE='0402LF',
 LOCATION='R2562',
 CDS_LIB='pure_quanta',
 CDS_PART_NAME='Q_RES_0402LF-0,5%,1/16W,CHIP,CA',
 WATTAGE='1/16W',
 TOLERANCE='5%',
 MATERIAL='CHIP',
 VALUE='0',
 PRIM_FILE='./archive_libs/logical/q_res/chips/chips.prt';

PART_NAME
 R2563 'Q_RES_0402LF-0,5%,1/16W,CHIP,CA':;

SECTION_NUMBER 1
 '@S9S_MB_2U_LIB.S9S_MB_2U(SCH_1):PAGE278_I57@PURE_QUANTA.Q_RES(CHIPS)':
 C_PATH='@s9s_mb_2u_lib.s9s_mb_2u(sch_1):page278_i57@pure_quanta.q_res(chips)',
 P_PATH='@s9s_mb_2u_lib.s9s_mb_2u(sch_1):page292_i57@pure_quanta.q_res(chips)',
 PATH='I57',
 DRAWING='@S9S_MB_2U_LIB.S9S_MB_2U(SCH_1):PAGE278',
 PHYS_PAGE='292',
 XY='(1175,7850)',
 ROT='0',
 VER='1',
 PACK_TYPE='0402LF',
 LOCATION='R2563',
 CDS_LIB='pure_quanta',
 CDS_PART_NAME='Q_RES_0402LF-0,5%,1/16W,CHIP,CA',
 WATTAGE='1/16W',
 TOLERANCE='5%',
 MATERIAL='CHIP',
 VALUE='0',
 PRIM_FILE='./archive_libs/logical/q_res/chips/chips.prt';

PART_NAME
 R2565 'Q_RES_0402LF-0,5%,1/16W,CHIP,CA':;

SECTION_NUMBER 1
 '@S9S_MB_2U_LIB.S9S_MB_2U(SCH_1):PAGE219_I61@PURE_QUANTA.Q_RES(CHIPS)':
 C_PATH='@s9s_mb_2u_lib.s9s_mb_2u(sch_1):page219_i61@pure_quanta.q_res(chips)',
 P_PATH='@s9s_mb_2u_lib.s9s_mb_2u(sch_1):page231_i61@pure_quanta.q_res(chips)',
 PATH='I61',
 DRAWING='@S9S_MB_2U_LIB.S9S_MB_2U(SCH_1):PAGE219',
 PHYS_PAGE='231',
 XY='(3400,2625)',
 ROT='0',
 VER='1',
 PACK_TYPE='0402LF',
 CDS_LIB='pure_quanta',
 CDS_PART_NAME='Q_RES_0402LF-0,5%,1/16W,CHIP,CA',
 WATTAGE='1/16W',
 TOLERANCE='5%',
 MATERIAL='CHIP',
 VALUE='0',
 PRIM_FILE='./archive_libs/logical/q_res/chips/chips.prt';

PART_NAME
 R2566 'Q_RES_0402LF-0,5%,1/16W,CHIP,CA':;

SECTION_NUMBER 1
 '@S9S_MB_2U_LIB.S9S_MB_2U(SCH_1):PAGE219_I62@PURE_QUANTA.Q_RES(CHIPS)':
 C_PATH='@s9s_mb_2u_lib.s9s_mb_2u(sch_1):page219_i62@pure_quanta.q_res(chips)',
 P_PATH='@s9s_mb_2u_lib.s9s_mb_2u(sch_1):page231_i62@pure_quanta.q_res(chips)',
 PATH='I62',
 DRAWING='@S9S_MB_2U_LIB.S9S_MB_2U(SCH_1):PAGE219',
 PHYS_PAGE='231',
 XY='(3400,2675)',
 ROT='0',
 VER='1',
 PACK_TYPE='0402LF',
 CDS_LIB='pure_quanta',
 CDS_PART_NAME='Q_RES_0402LF-0,5%,1/16W,CHIP,CA',
 WATTAGE='1/16W',
 TOLERANCE='5%',
 MATERIAL='CHIP',
 VALUE='0',
 PRIM_FILE='./archive_libs/logical/q_res/chips/chips.prt';

PART_NAME
 R2568 'Q_RES_0402LF-1K,1%,1/16W,CHIP,A':;

SECTION_NUMBER 1
 '@S9S_MB_2U_LIB.S9S_MB_2U(SCH_1):PAGE278_I50@PURE_QUANTA.Q_RES(CHIPS)':
 C_PATH='@s9s_mb_2u_lib.s9s_mb_2u(sch_1):page278_i50@pure_quanta.q_res(chips)',
 P_PATH='@s9s_mb_2u_lib.s9s_mb_2u(sch_1):page292_i50@pure_quanta.q_res(chips)',
 PATH='I50',
 DRAWING='@S9S_MB_2U_LIB.S9S_MB_2U(SCH_1):PAGE278',
 PHYS_PAGE='292',
 XY='(1350,5150)',
 ROT='0',
 VER='1',
 PACK_TYPE='0402LF',
 LOCATION='R2568',
 CDS_LIB='pure_quanta',
 CDS_PART_NAME='Q_RES_0402LF-1K,1%,1/16W,CHIP,A',
 WATTAGE='1/16W',
 TOLERANCE='1%',
 MATERIAL='CHIP',
 VALUE='1K',
 PRIM_FILE='./archive_libs/logical/q_res/chips/chips.prt';

PART_NAME
 R2569 'Q_RES_0402LF-1K,1%,1/16W,CHIP,A':;

SECTION_NUMBER 1
 '@S9S_MB_2U_LIB.S9S_MB_2U(SCH_1):PAGE278_I49@PURE_QUANTA.Q_RES(CHIPS)':
 C_PATH='@s9s_mb_2u_lib.s9s_mb_2u(sch_1):page278_i49@pure_quanta.q_res(chips)',
 P_PATH='@s9s_mb_2u_lib.s9s_mb_2u(sch_1):page292_i49@pure_quanta.q_res(chips)',
 PATH='I49',
 DRAWING='@S9S_MB_2U_LIB.S9S_MB_2U(SCH_1):PAGE278',
 PHYS_PAGE='292',
 XY='(1350,5050)',
 ROT='0',
 VER='1',
 PACK_TYPE='0402LF',
 LOCATION='R2569',
 CDS_LIB='pure_quanta',
 CDS_PART_NAME='Q_RES_0402LF-1K,1%,1/16W,CHIP,A',
 WATTAGE='1/16W',
 TOLERANCE='1%',
 MATERIAL='CHIP',
 VALUE='1K',
 PRIM_FILE='./archive_libs/logical/q_res/chips/chips.prt';

PART_NAME
 R2570 'Q_RES_0402LF-0,5%,1/16W,CHIP,CA':;

SECTION_NUMBER 1
 '@S9S_MB_2U_LIB.S9S_MB_2U(SCH_1):PAGE278_I31@PURE_QUANTA.Q_RES(CHIPS)':
 C_PATH='@s9s_mb_2u_lib.s9s_mb_2u(sch_1):page278_i31@pure_quanta.q_res(chips)',
 P_PATH='@s9s_mb_2u_lib.s9s_mb_2u(sch_1):page292_i31@pure_quanta.q_res(chips)',
 PATH='I31',
 DRAWING='@S9S_MB_2U_LIB.S9S_MB_2U(SCH_1):PAGE278',
 PHYS_PAGE='292',
 XY='(1350,4750)',
 ROT='0',
 VER='1',
 PACK_TYPE='0402LF',
 LOCATION='R2570',
 CDS_LIB='pure_quanta',
 CDS_PART_NAME='Q_RES_0402LF-0,5%,1/16W,CHIP,CA',
 WATTAGE='1/16W',
 TOLERANCE='5%',
 MATERIAL='CHIP',
 VALUE='0',
 PRIM_FILE='./archive_libs/logical/q_res/chips/chips.prt';

PART_NAME
 R2571 'Q_RES_0402LF-1K,1%,1/16W,CHIP,A':;

SECTION_NUMBER 1
 '@S9S_MB_2U_LIB.S9S_MB_2U(SCH_1):PAGE278_I30@PURE_QUANTA.Q_RES(CHIPS)':
 C_PATH='@s9s_mb_2u_lib.s9s_mb_2u(sch_1):page278_i30@pure_quanta.q_res(chips)',
 P_PATH='@s9s_mb_2u_lib.s9s_mb_2u(sch_1):page292_i30@pure_quanta.q_res(chips)',
 PATH='I30',
 DRAWING='@S9S_MB_2U_LIB.S9S_MB_2U(SCH_1):PAGE278',
 PHYS_PAGE='292',
 XY='(1350,4500)',
 ROT='0',
 VER='1',
 PACK_TYPE='0402LF',
 LOCATION='R2571',
 CDS_LIB='pure_quanta',
 CDS_PART_NAME='Q_RES_0402LF-1K,1%,1/16W,CHIP,A',
 WATTAGE='1/16W',
 TOLERANCE='1%',
 MATERIAL='CHIP',
 VALUE='1K',
 PRIM_FILE='./archive_libs/logical/q_res/chips/chips.prt';

PART_NAME
 R2572 'Q_RES_0402LF-0,5%,1/16W,CHIP,CA':;

SECTION_NUMBER 1
 '@S9S_MB_2U_LIB.S9S_MB_2U(SCH_1):PAGE278_I29@PURE_QUANTA.Q_RES(CHIPS)':
 C_PATH='@s9s_mb_2u_lib.s9s_mb_2u(sch_1):page278_i29@pure_quanta.q_res(chips)',
 P_PATH='@s9s_mb_2u_lib.s9s_mb_2u(sch_1):page292_i29@pure_quanta.q_res(chips)',
 PATH='I29',
 DRAWING='@S9S_MB_2U_LIB.S9S_MB_2U(SCH_1):PAGE278',
 PHYS_PAGE='292',
 XY='(1350,4350)',
 ROT='0',
 VER='1',
 PACK_TYPE='0402LF',
 LOCATION='R2572',
 CDS_LIB='pure_quanta',
 CDS_PART_NAME='Q_RES_0402LF-0,5%,1/16W,CHIP,CA',
 WATTAGE='1/16W',
 TOLERANCE='5%',
 MATERIAL='CHIP',
 VALUE='0',
 PRIM_FILE='./archive_libs/logical/q_res/chips/chips.prt';

PART_NAME
 R2573 'Q_RES_0402LF-1K,1%,1/16W,CHIP,A':;

SECTION_NUMBER 1
 '@S9S_MB_2U_LIB.S9S_MB_2U(SCH_1):PAGE278_I73@PURE_QUANTA.Q_RES(CHIPS)':
 C_PATH='@s9s_mb_2u_lib.s9s_mb_2u(sch_1):page278_i73@pure_quanta.q_res(chips)',
 P_PATH='@s9s_mb_2u_lib.s9s_mb_2u(sch_1):page292_i73@pure_quanta.q_res(chips)',
 PATH='I73',
 DRAWING='@S9S_MB_2U_LIB.S9S_MB_2U(SCH_1):PAGE278',
 PHYS_PAGE='292',
 XY='(6275,4900)',
 ROT='0',
 VER='2',
 PACK_TYPE='0402LF',
 LOCATION='R2573',
 CDS_LIB='pure_quanta',
 CDS_PART_NAME='Q_RES_0402LF-1K,1%,1/16W,CHIP,A',
 WATTAGE='1/16W',
 TOLERANCE='1%',
 MATERIAL='CHIP',
 VALUE='1K',
 PRIM_FILE='./archive_libs/logical/q_res/chips/chips.prt';

PART_NAME
 R2574 'Q_RES_0402LF-0,5%,1/16W,CHIP,CA':;

SECTION_NUMBER 1
 '@S9S_MB_2U_LIB.S9S_MB_2U(SCH_1):PAGE278_I70@PURE_QUANTA.Q_RES(CHIPS)':
 C_PATH='@s9s_mb_2u_lib.s9s_mb_2u(sch_1):page278_i70@pure_quanta.q_res(chips)',
 P_PATH='@s9s_mb_2u_lib.s9s_mb_2u(sch_1):page292_i70@pure_quanta.q_res(chips)',
 PATH='I70',
 DRAWING='@S9S_MB_2U_LIB.S9S_MB_2U(SCH_1):PAGE278',
 PHYS_PAGE='292',
 XY='(5675,4650)',
 ROT='0',
 VER='1',
 PACK_TYPE='0402LF',
 LOCATION='R2574',
 CDS_LIB='pure_quanta',
 CDS_PART_NAME='Q_RES_0402LF-0,5%,1/16W,CHIP,CA',
 WATTAGE='1/16W',
 TOLERANCE='5%',
 MATERIAL='CHIP',
 VALUE='0',
 PRIM_FILE='./archive_libs/logical/q_res/chips/chips.prt';

PART_NAME
 R2575 'Q_RES_0402LF-1K,1%,1/16W,CHIP,A':;

SECTION_NUMBER 1
 '@S9S_MB_2U_LIB.S9S_MB_2U(SCH_1):PAGE282_I46@PURE_QUANTA.Q_RES(CHIPS)':
 C_PATH='@s9s_mb_2u_lib.s9s_mb_2u(sch_1):page282_i46@pure_quanta.q_res(chips)',
 P_PATH='@s9s_mb_2u_lib.s9s_mb_2u(sch_1):page296_i46@pure_quanta.q_res(chips)',
 PATH='I46',
 DRAWING='@S9S_MB_2U_LIB.S9S_MB_2U(SCH_1):PAGE282',
 PHYS_PAGE='296',
 XY='(-5325,5600)',
 ROT='0',
 VER='1',
 PACK_TYPE='0402LF',
 LOCATION='R2575',
 CDS_LIB='pure_quanta',
 CDS_PART_NAME='Q_RES_0402LF-1K,1%,1/16W,CHIP,A',
 WATTAGE='1/16W',
 TOLERANCE='1%',
 MATERIAL='CHIP',
 VALUE='1K',
 PRIM_FILE='./archive_libs/logical/q_res/chips/chips.prt';

PART_NAME
 R2576 'Q_RES_0402LF-0,5%,1/16W,CHIP,CA':;

SECTION_NUMBER 1
 '@S9S_MB_2U_LIB.S9S_MB_2U(SCH_1):PAGE282_I44@PURE_QUANTA.Q_RES(CHIPS)':
 C_PATH='@s9s_mb_2u_lib.s9s_mb_2u(sch_1):page282_i44@pure_quanta.q_res(chips)',
 P_PATH='@s9s_mb_2u_lib.s9s_mb_2u(sch_1):page296_i44@pure_quanta.q_res(chips)',
 PATH='I44',
 DRAWING='@S9S_MB_2U_LIB.S9S_MB_2U(SCH_1):PAGE282',
 PHYS_PAGE='296',
 XY='(-5325,5450)',
 ROT='0',
 VER='1',
 PACK_TYPE='0402LF',
 LOCATION='R2576',
 CDS_LIB='pure_quanta',
 CDS_PART_NAME='Q_RES_0402LF-0,5%,1/16W,CHIP,CA',
 WATTAGE='1/16W',
 TOLERANCE='5%',
 MATERIAL='CHIP',
 VALUE='0',
 PRIM_FILE='./archive_libs/logical/q_res/chips/chips.prt';

PART_NAME
 R2577 'Q_RES_0402LF-0,5%,1/16W,CHIP,CA':;

SECTION_NUMBER 1
 '@S9S_MB_2U_LIB.S9S_MB_2U(SCH_1):PAGE282_I43@PURE_QUANTA.Q_RES(CHIPS)':
 C_PATH='@s9s_mb_2u_lib.s9s_mb_2u(sch_1):page282_i43@pure_quanta.q_res(chips)',
 P_PATH='@s9s_mb_2u_lib.s9s_mb_2u(sch_1):page296_i43@pure_quanta.q_res(chips)',
 PATH='I43',
 DRAWING='@S9S_MB_2U_LIB.S9S_MB_2U(SCH_1):PAGE282',
 PHYS_PAGE='296',
 XY='(-5325,5300)',
 ROT='0',
 VER='1',
 PACK_TYPE='0402LF',
 LOCATION='R2577',
 CDS_LIB='pure_quanta',
 CDS_PART_NAME='Q_RES_0402LF-0,5%,1/16W,CHIP,CA',
 WATTAGE='1/16W',
 TOLERANCE='5%',
 MATERIAL='CHIP',
 VALUE='0',
 PRIM_FILE='./archive_libs/logical/q_res/chips/chips.prt';

PART_NAME
 R2578 'Q_RES_0402LF-150,1%,1/16W,CHIPA':;

SECTION_NUMBER 1
 '@S9S_MB_2U_LIB.S9S_MB_2U(SCH_1):PAGE282_I42@PURE_QUANTA.Q_RES(CHIPS)':
 C_PATH='@s9s_mb_2u_lib.s9s_mb_2u(sch_1):page282_i42@pure_quanta.q_res(chips)',
 P_PATH='@s9s_mb_2u_lib.s9s_mb_2u(sch_1):page296_i42@pure_quanta.q_res(chips)',
 PATH='I42',
 DRAWING='@S9S_MB_2U_LIB.S9S_MB_2U(SCH_1):PAGE282',
 PHYS_PAGE='296',
 XY='(-5325,5000)',
 ROT='0',
 VER='1',
 PACK_TYPE='0402LF',
 LOCATION='R2578',
 CDS_LIB='pure_quanta',
 CDS_PART_NAME='Q_RES_0402LF-150,1%,1/16W,CHIPA',
 WATTAGE='1/16W',
 TOLERANCE='1%',
 MATERIAL='CHIP',
 VALUE='150',
 PRIM_FILE='./archive_libs/logical/q_res/chips/chips.prt';

PART_NAME
 R2579 'Q_RES_0402LF-0,5%,1/16W,CHIP,CA':;

SECTION_NUMBER 1
 '@S9S_MB_2U_LIB.S9S_MB_2U(SCH_1):PAGE282_I41@PURE_QUANTA.Q_RES(CHIPS)':
 C_PATH='@s9s_mb_2u_lib.s9s_mb_2u(sch_1):page282_i41@pure_quanta.q_res(chips)',
 P_PATH='@s9s_mb_2u_lib.s9s_mb_2u(sch_1):page296_i41@pure_quanta.q_res(chips)',
 PATH='I41',
 DRAWING='@S9S_MB_2U_LIB.S9S_MB_2U(SCH_1):PAGE282',
 PHYS_PAGE='296',
 XY='(-5325,4850)',
 ROT='0',
 VER='1',
 PACK_TYPE='0402LF',
 LOCATION='R2579',
 CDS_LIB='pure_quanta',
 CDS_PART_NAME='Q_RES_0402LF-0,5%,1/16W,CHIP,CA',
 WATTAGE='1/16W',
 TOLERANCE='5%',
 MATERIAL='CHIP',
 VALUE='0',
 PRIM_FILE='./archive_libs/logical/q_res/chips/chips.prt';

PART_NAME
 R2580 'Q_RES_0402LF-0,5%,1/16W,CHIP,CA':;

SECTION_NUMBER 1
 '@S9S_MB_2U_LIB.S9S_MB_2U(SCH_1):PAGE282_I40@PURE_QUANTA.Q_RES(CHIPS)':
 C_PATH='@s9s_mb_2u_lib.s9s_mb_2u(sch_1):page282_i40@pure_quanta.q_res(chips)',
 P_PATH='@s9s_mb_2u_lib.s9s_mb_2u(sch_1):page296_i40@pure_quanta.q_res(chips)',
 PATH='I40',
 DRAWING='@S9S_MB_2U_LIB.S9S_MB_2U(SCH_1):PAGE282',
 PHYS_PAGE='296',
 XY='(-5325,4700)',
 ROT='0',
 VER='1',
 PACK_TYPE='0402LF',
 LOCATION='R2580',
 CDS_LIB='pure_quanta',
 CDS_PART_NAME='Q_RES_0402LF-0,5%,1/16W,CHIP,CA',
 WATTAGE='1/16W',
 TOLERANCE='5%',
 MATERIAL='CHIP',
 VALUE='0',
 PRIM_FILE='./archive_libs/logical/q_res/chips/chips.prt';

PART_NAME
 R2582 'Q_RES_0402LF-0,5%,1/16W,CHIP,CA':;

SECTION_NUMBER 1
 '@S9S_MB_2U_LIB.S9S_MB_2U(SCH_1):PAGE282_I38@PURE_QUANTA.Q_RES(CHIPS)':
 C_PATH='@s9s_mb_2u_lib.s9s_mb_2u(sch_1):page282_i38@pure_quanta.q_res(chips)',
 P_PATH='@s9s_mb_2u_lib.s9s_mb_2u(sch_1):page296_i38@pure_quanta.q_res(chips)',
 PATH='I38',
 DRAWING='@S9S_MB_2U_LIB.S9S_MB_2U(SCH_1):PAGE282',
 PHYS_PAGE='296',
 XY='(-5325,4150)',
 ROT='0',
 VER='1',
 PACK_TYPE='0402LF',
 LOCATION='R2582',
 SEC='1',
 CDS_LIB='pure_quanta',
 CDS_PART_NAME='Q_RES_0402LF-0,5%,1/16W,CHIP,CA',
 SEC_TYPE='0402LF',
 WATTAGE='1/16W',
 TOLERANCE='5%',
 MATERIAL='CHIP',
 VALUE='0',
 PRIM_FILE='./archive_libs/logical/q_res/chips/chips.prt';

PART_NAME
 R2583 'Q_RES_0402LF-10K,1%,1/16W,CHIPA':;

SECTION_NUMBER 1
 '@S9S_MB_2U_LIB.S9S_MB_2U(SCH_1):PAGE285_I27@PURE_QUANTA.Q_RES(CHIPS)':
 C_PATH='@s9s_mb_2u_lib.s9s_mb_2u(sch_1):page285_i27@pure_quanta.q_res(chips)',
 P_PATH='@s9s_mb_2u_lib.s9s_mb_2u(sch_1):page299_i27@pure_quanta.q_res(chips)',
 PATH='I27',
 DRAWING='@S9S_MB_2U_LIB.S9S_MB_2U(SCH_1):PAGE285',
 BOM_COST='VR_PCH',
 PHYS_PAGE='299',
 XY='(-6600,4200)',
 ROT='0',
 VER='2',
 PACK_TYPE='0402LF',
 LOCATION='R2583',
 CDS_LIB='pure_quanta',
 CDS_PART_NAME='Q_RES_0402LF-10K,1%,1/16W,CHIPA',
 WATTAGE='1/16W',
 TOLERANCE='1%',
 MATERIAL='CHIP',
 VALUE='10K',
 PRIM_FILE='./archive_libs/logical/q_res/chips/chips.prt';

PART_NAME
 R2584 'Q_RES_0402LF-10K,1%,1/16W,CHIPA':;

SECTION_NUMBER 1
 '@S9S_MB_2U_LIB.S9S_MB_2U(SCH_1):PAGE286_I31@PURE_QUANTA.Q_RES(CHIPS)':
 C_PATH='@s9s_mb_2u_lib.s9s_mb_2u(sch_1):page286_i31@pure_quanta.q_res(chips)',
 P_PATH='@s9s_mb_2u_lib.s9s_mb_2u(sch_1):page300_i31@pure_quanta.q_res(chips)',
 PATH='I31',
 DRAWING='@S9S_MB_2U_LIB.S9S_MB_2U(SCH_1):PAGE286',
 BOM_COST='VR_PCH',
 PHYS_PAGE='300',
 XY='(6350,8075)',
 ROT='0',
 VER='2',
 PACK_TYPE='0402LF',
 LOCATION='R2584',
 CDS_LIB='pure_quanta',
 CDS_PART_NAME='Q_RES_0402LF-10K,1%,1/16W,CHIPA',
 WATTAGE='1/16W',
 TOLERANCE='1%',
 MATERIAL='CHIP',
 VALUE='10K',
 PRIM_FILE='./archive_libs/logical/q_res/chips/chips.prt';

PART_NAME
 R2585 'Q_RES_0402LF-31.6K,1%,1/16W,CHA':;

SECTION_NUMBER 1
 '@S9S_MB_2U_LIB.S9S_MB_2U(SCH_1):PAGE303_I7@PURE_QUANTA.Q_RES(CHIPS)':
 C_PATH='@s9s_mb_2u_lib.s9s_mb_2u(sch_1):page303_i7@pure_quanta.q_res(chips)',
 P_PATH='@s9s_mb_2u_lib.s9s_mb_2u(sch_1):page301_i7@pure_quanta.q_res(chips)',
 PATH='I7',
 DRAWING='@S9S_MB_2U_LIB.S9S_MB_2U(SCH_1):PAGE303',
 PHYS_PAGE='301',
 XY='(-15100,750)',
 ROT='0',
 VER='2',
 PACK_TYPE='0402LF',
 LOCATION='R2585',
 CDS_LIB='pure_quanta',
 CDS_PART_NAME='Q_RES_0402LF-31.6K,1%,1/16W,CHA',
 WATTAGE='1/16W',
 TOLERANCE='1%',
 MATERIAL='CHIP',
 VALUE='31.6K',
 PRIM_FILE='./archive_libs/logical/q_res/chips/chips.prt';

PART_NAME
 R2586 'Q_RES_0402LF-0,5%,1/16W,CHIP,CA':
 ROOM='HSC1_BOM1';

SECTION_NUMBER 1
 '@S9S_MB_2U_LIB.S9S_MB_2U(SCH_1):PAGE303_I44@PURE_QUANTA.Q_RES(CHIPS)':
 C_PATH='@s9s_mb_2u_lib.s9s_mb_2u(sch_1):page303_i44@pure_quanta.q_res(chips)',
 P_PATH='@s9s_mb_2u_lib.s9s_mb_2u(sch_1):page301_i44@pure_quanta.q_res(chips)',
 PATH='I44',
 DRAWING='@S9S_MB_2U_LIB.S9S_MB_2U(SCH_1):PAGE303',
 PHYS_PAGE='301',
 XY='(-14825,3350)',
 ROT='0',
 VER='1',
 PACK_TYPE='0402LF',
 LOCATION='R2586',
 CDS_LIB='pure_quanta',
 CDS_PART_NAME='Q_RES_0402LF-0,5%,1/16W,CHIP,CA',
 WATTAGE='1/16W',
 TOLERANCE='5%',
 MATERIAL='CHIP',
 ROOM='HSC1_BOM1',
 VALUE='0',
 PRIM_FILE='./archive_libs/logical/q_res/chips/chips.prt';

PART_NAME
 R2587 'Q_RES_0402LF-4.7K,1%,1/16W,CHIA':
 ROOM='HSC1_BOM1';

SECTION_NUMBER 1
 '@S9S_MB_2U_LIB.S9S_MB_2U(SCH_1):PAGE303_I93@PURE_QUANTA.Q_RES(CHIPS)':
 C_PATH='@s9s_mb_2u_lib.s9s_mb_2u(sch_1):page303_i93@pure_quanta.q_res(chips)',
 P_PATH='@s9s_mb_2u_lib.s9s_mb_2u(sch_1):page301_i93@pure_quanta.q_res(chips)',
 PATH='I93',
 DRAWING='@S9S_MB_2U_LIB.S9S_MB_2U(SCH_1):PAGE303',
 PHYS_PAGE='301',
 XY='(-9725,4600)',
 ROT='0',
 VER='2',
 PACK_TYPE='0402LF',
 LOCATION='R2587',
 CDS_LIB='pure_quanta',
 CDS_PART_NAME='Q_RES_0402LF-4.7K,1%,1/16W,CHIA',
 WATTAGE='1/16W',
 TOLERANCE='1%',
 MATERIAL='CHIP',
 ROOM='HSC1_BOM1',
 VALUE='4.7K',
 PRIM_FILE='./archive_libs/logical/q_res/chips/chips.prt';

PART_NAME
 R2588 'Q_RES_0402LF-22,1%,1/16W,CHIP,A':
 ROOM='HSC1_BOM1';

SECTION_NUMBER 1
 '@S9S_MB_2U_LIB.S9S_MB_2U(SCH_1):PAGE303_I81@PURE_QUANTA.Q_RES(CHIPS)':
 C_PATH='@s9s_mb_2u_lib.s9s_mb_2u(sch_1):page303_i81@pure_quanta.q_res(chips)',
 P_PATH='@s9s_mb_2u_lib.s9s_mb_2u(sch_1):page301_i81@pure_quanta.q_res(chips)',
 PATH='I81',
 DRAWING='@S9S_MB_2U_LIB.S9S_MB_2U(SCH_1):PAGE303',
 PHYS_PAGE='301',
 XY='(-10675,4275)',
 ROT='0',
 VER='1',
 PACK_TYPE='0402LF',
 LOCATION='R2588',
 CDS_LIB='pure_quanta',
 CDS_PART_NAME='Q_RES_0402LF-22,1%,1/16W,CHIP,A',
 WATTAGE='1/16W',
 TOLERANCE='1%',
 MATERIAL='CHIP',
 ROOM='HSC1_BOM1',
 VALUE='22',
 PRIM_FILE='./archive_libs/logical/q_res/chips/chips.prt';

PART_NAME
 R2589 'Q_RES_0402LF-1K,1%,1/16W,CHIP,A':;

SECTION_NUMBER 1
 '@S9S_MB_2U_LIB.S9S_MB_2U(SCH_1):PAGE252_I20@PURE_QUANTA.Q_RES(CHIPS)':
 C_PATH='@s9s_mb_2u_lib.s9s_mb_2u(sch_1):page252_i20@pure_quanta.q_res(chips)',
 P_PATH='@s9s_mb_2u_lib.s9s_mb_2u(sch_1):page266_i20@pure_quanta.q_res(chips)',
 PATH='I20',
 DRAWING='@S9S_MB_2U_LIB.S9S_MB_2U(SCH_1):PAGE252',
 PHYS_PAGE='266',
 XY='(-5250,2550)',
 ROT='0',
 VER='1',
 PACK_TYPE='0402LF',
 LOCATION='R2589',
 CDS_LIB='pure_quanta',
 CDS_PART_NAME='Q_RES_0402LF-1K,1%,1/16W,CHIP,A',
 WATTAGE='1/16W',
 TOLERANCE='1%',
 MATERIAL='CHIP',
 VALUE='1K',
 PRIM_FILE='./archive_libs/logical/q_res/chips/chips.prt';

PART_NAME
 R2590 'Q_RES_0402LF-100,1%,1/16W,CHIPA':;

SECTION_NUMBER 1
 '@S9S_MB_2U_LIB.S9S_MB_2U(SCH_1):PAGE252_I124@PURE_QUANTA.Q_RES(CHIPS)':
 C_PATH='@s9s_mb_2u_lib.s9s_mb_2u(sch_1):page252_i124@pure_quanta.q_res(chips)',
 P_PATH='@s9s_mb_2u_lib.s9s_mb_2u(sch_1):page266_i124@pure_quanta.q_res(chips)',
 PATH='I124',
 DRAWING='@S9S_MB_2U_LIB.S9S_MB_2U(SCH_1):PAGE252',
 PHYS_PAGE='266',
 XY='(950,2200)',
 ROT='0',
 VER='1',
 PACK_TYPE='0402LF',
 LOCATION='R2590',
 CDS_LIB='pure_quanta',
 CDS_PART_NAME='Q_RES_0402LF-100,1%,1/16W,CHIPA',
 WATTAGE='1/16W',
 TOLERANCE='1%',
 MATERIAL='CHIP',
 VALUE='100',
 PRIM_FILE='./archive_libs/logical/q_res/chips/chips.prt';

PART_NAME
 R2591 'Q_RES_0402LF-0,5%,1/16W,CHIP,CA':;

SECTION_NUMBER 1
 '@S9S_MB_2U_LIB.S9S_MB_2U(SCH_1):PAGE252_I48@PURE_QUANTA.Q_RES(CHIPS)':
 C_PATH='@s9s_mb_2u_lib.s9s_mb_2u(sch_1):page252_i48@pure_quanta.q_res(chips)',
 P_PATH='@s9s_mb_2u_lib.s9s_mb_2u(sch_1):page266_i48@pure_quanta.q_res(chips)',
 PATH='I48',
 DRAWING='@S9S_MB_2U_LIB.S9S_MB_2U(SCH_1):PAGE252',
 PHYS_PAGE='266',
 XY='(-5125,6400)',
 ROT='0',
 VER='1',
 PACK_TYPE='0402LF',
 LOCATION='R2591',
 CDS_LIB='pure_quanta',
 CDS_PART_NAME='Q_RES_0402LF-0,5%,1/16W,CHIP,CA',
 WATTAGE='1/16W',
 TOLERANCE='5%',
 MATERIAL='CHIP',
 VALUE='0',
 PRIM_FILE='./archive_libs/logical/q_res/chips/chips.prt';

PART_NAME
 R2593 'Q_RES_0402LF-100,1%,1/16W,CHIPA':;

SECTION_NUMBER 1
 '@S9S_MB_2U_LIB.S9S_MB_2U(SCH_1):PAGE282_I29@PURE_QUANTA.Q_RES(CHIPS)':
 C_PATH='@s9s_mb_2u_lib.s9s_mb_2u(sch_1):page282_i29@pure_quanta.q_res(chips)',
 P_PATH='@s9s_mb_2u_lib.s9s_mb_2u(sch_1):page296_i29@pure_quanta.q_res(chips)',
 PATH='I29',
 DRAWING='@S9S_MB_2U_LIB.S9S_MB_2U(SCH_1):PAGE282',
 PHYS_PAGE='296',
 XY='(-6800,5075)',
 ROT='0',
 VER='1',
 PACK_TYPE='0402LF',
 LOCATION='R2593',
 CDS_LIB='pure_quanta',
 CDS_PART_NAME='Q_RES_0402LF-100,1%,1/16W,CHIPA',
 WATTAGE='1/16W',
 TOLERANCE='1%',
 MATERIAL='CHIP',
 VALUE='100',
 PRIM_FILE='./archive_libs/logical/q_res/chips/chips.prt';

PART_NAME
 R2594 'Q_RES_0402LF-0,5%,1/16W,CHIP,CA':;

SECTION_NUMBER 1
 '@S9S_MB_2U_LIB.S9S_MB_2U(SCH_1):PAGE260_I55@PURE_QUANTA.Q_RES(CHIPS)':
 C_PATH='@s9s_mb_2u_lib.s9s_mb_2u(sch_1):page260_i55@pure_quanta.q_res(chips)',
 P_PATH='@s9s_mb_2u_lib.s9s_mb_2u(sch_1):page274_i55@pure_quanta.q_res(chips)',
 PATH='I55',
 DRAWING='@S9S_MB_2U_LIB.S9S_MB_2U(SCH_1):PAGE260',
 PHYS_PAGE='274',
 XY='(-9200,7425)',
 ROT='0',
 VER='1',
 PACK_TYPE='0402LF',
 LOCATION='R2594',
 CDS_LIB='pure_quanta',
 CDS_PART_NAME='Q_RES_0402LF-0,5%,1/16W,CHIP,CA',
 WATTAGE='1/16W',
 TOLERANCE='5%',
 MATERIAL='CHIP',
 VALUE='0',
 PRIM_FILE='./archive_libs/logical/q_res/chips/chips.prt';

PART_NAME
 R2595 'Q_RES_0402LF-0,5%,1/16W,CHIP,CA':;

SECTION_NUMBER 1
 '@S9S_MB_2U_LIB.S9S_MB_2U(SCH_1):PAGE260_I58@PURE_QUANTA.Q_RES(CHIPS)':
 C_PATH='@s9s_mb_2u_lib.s9s_mb_2u(sch_1):page260_i58@pure_quanta.q_res(chips)',
 P_PATH='@s9s_mb_2u_lib.s9s_mb_2u(sch_1):page274_i58@pure_quanta.q_res(chips)',
 PATH='I58',
 DRAWING='@S9S_MB_2U_LIB.S9S_MB_2U(SCH_1):PAGE260',
 PHYS_PAGE='274',
 XY='(-9200,7575)',
 ROT='0',
 VER='1',
 PACK_TYPE='0402LF',
 LOCATION='R2595',
 CDS_LIB='pure_quanta',
 CDS_PART_NAME='Q_RES_0402LF-0,5%,1/16W,CHIP,CA',
 WATTAGE='1/16W',
 TOLERANCE='5%',
 MATERIAL='CHIP',
 VALUE='0',
 PRIM_FILE='./archive_libs/logical/q_res/chips/chips.prt';

PART_NAME
 R2596 'Q_RES_0402LF-150,1%,1/16W,CHIPA':;

SECTION_NUMBER 1
 '@S9S_MB_2U_LIB.S9S_MB_2U(SCH_1):PAGE260_I56@PURE_QUANTA.Q_RES(CHIPS)':
 C_PATH='@s9s_mb_2u_lib.s9s_mb_2u(sch_1):page260_i56@pure_quanta.q_res(chips)',
 P_PATH='@s9s_mb_2u_lib.s9s_mb_2u(sch_1):page274_i56@pure_quanta.q_res(chips)',
 PATH='I56',
 DRAWING='@S9S_MB_2U_LIB.S9S_MB_2U(SCH_1):PAGE260',
 PHYS_PAGE='274',
 XY='(-9200,7125)',
 ROT='0',
 VER='1',
 PACK_TYPE='0402LF',
 LOCATION='R2596',
 CDS_LIB='pure_quanta',
 CDS_PART_NAME='Q_RES_0402LF-150,1%,1/16W,CHIPA',
 WATTAGE='1/16W',
 TOLERANCE='1%',
 MATERIAL='CHIP',
 VALUE='150',
 PRIM_FILE='./archive_libs/logical/q_res/chips/chips.prt';

PART_NAME
 R2597 'Q_RES_0402LF-0,5%,1/16W,CHIP,CA':;

SECTION_NUMBER 1
 '@S9S_MB_2U_LIB.S9S_MB_2U(SCH_1):PAGE260_I78@PURE_QUANTA.Q_RES(CHIPS)':
 C_PATH='@s9s_mb_2u_lib.s9s_mb_2u(sch_1):page260_i78@pure_quanta.q_res(chips)',
 P_PATH='@s9s_mb_2u_lib.s9s_mb_2u(sch_1):page274_i78@pure_quanta.q_res(chips)',
 PATH='I78',
 DRAWING='@S9S_MB_2U_LIB.S9S_MB_2U(SCH_1):PAGE260',
 PHYS_PAGE='274',
 XY='(-4700,3075)',
 ROT='0',
 VER='1',
 PACK_TYPE='0402LF',
 LOCATION='R2597',
 CDS_LIB='pure_quanta',
 CDS_PART_NAME='Q_RES_0402LF-0,5%,1/16W,CHIP,CA',
 WATTAGE='1/16W',
 TOLERANCE='5%',
 MATERIAL='CHIP',
 VALUE='0',
 PRIM_FILE='./archive_libs/logical/q_res/chips/chips.prt';

PART_NAME
 R2656 'Q_RES_0402LF-100,1%,1/16W,EMPTA':;

SECTION_NUMBER 1
 '@S9S_MB_2U_LIB.S9S_MB_2U(SCH_1):PAGE147_I11@PURE_QUANTA.Q_RES(CHIPS)':
 C_PATH='@s9s_mb_2u_lib.s9s_mb_2u(sch_1):page147_i11@pure_quanta.q_res(chips)',
 P_PATH='@s9s_mb_2u_lib.s9s_mb_2u(sch_1):page144_i11@pure_quanta.q_res(chips)',
 PATH='I11',
 DRAWING='@S9S_MB_2U_LIB.S9S_MB_2U(SCH_1):PAGE147',
 PHYS_PAGE='144',
 XY='(550,4275)',
 ROT='0',
 VER='1',
 PACK_TYPE='0402LF',
 CDS_LIB='pure_quanta',
 CDS_PART_NAME='Q_RES_0402LF-100,1%,1/16W,EMPTA',
 WATTAGE='1/16W',
 TOLERANCE='1%',
 MATERIAL='EMPTY',
 VALUE='100',
 PRIM_FILE='./archive_libs/logical/q_res/chips/chips.prt';

PART_NAME
 R2659 'Q_RES_0402LF-0,5%,1/16W,CHIP,CA':;

SECTION_NUMBER 1
 '@S9S_MB_2U_LIB.S9S_MB_2U(SCH_1):PAGE196_I27@PURE_QUANTA.Q_RES(CHIPS)':
 C_PATH='@s9s_mb_2u_lib.s9s_mb_2u(sch_1):page196_i27@pure_quanta.q_res(chips)',
 P_PATH='@s9s_mb_2u_lib.s9s_mb_2u(sch_1):page207_i27@pure_quanta.q_res(chips)',
 PATH='I27',
 DRAWING='@S9S_MB_2U_LIB.S9S_MB_2U(SCH_1):PAGE196',
 PHYS_PAGE='207',
 XY='(-125,-2875)',
 ROT='0',
 VER='1',
 PACK_TYPE='0402LF',
 CDS_LIB='pure_quanta',
 CDS_PART_NAME='Q_RES_0402LF-0,5%,1/16W,CHIP,CA',
 WATTAGE='1/16W',
 TOLERANCE='5%',
 MATERIAL='CHIP',
 VALUE='0',
 PRIM_FILE='./archive_libs/logical/q_res/chips/chips.prt';

PART_NAME
 R2660 'Q_RES_0402LF-0,5%,1/16W,CHIP,CA':;

SECTION_NUMBER 1
 '@S9S_MB_2U_LIB.S9S_MB_2U(SCH_1):PAGE196_I28@PURE_QUANTA.Q_RES(CHIPS)':
 C_PATH='@s9s_mb_2u_lib.s9s_mb_2u(sch_1):page196_i28@pure_quanta.q_res(chips)',
 P_PATH='@s9s_mb_2u_lib.s9s_mb_2u(sch_1):page207_i28@pure_quanta.q_res(chips)',
 PATH='I28',
 DRAWING='@S9S_MB_2U_LIB.S9S_MB_2U(SCH_1):PAGE196',
 PHYS_PAGE='207',
 XY='(-125,-3025)',
 ROT='0',
 VER='1',
 PACK_TYPE='0402LF',
 CDS_LIB='pure_quanta',
 CDS_PART_NAME='Q_RES_0402LF-0,5%,1/16W,CHIP,CA',
 WATTAGE='1/16W',
 TOLERANCE='5%',
 MATERIAL='CHIP',
 VALUE='0',
 PRIM_FILE='./archive_libs/logical/q_res/chips/chips.prt';

PART_NAME
 R2661 'Q_RES_0402LF-33.2,1%,1/16W,CHIA':;

SECTION_NUMBER 1
 '@S9S_MB_2U_LIB.S9S_MB_2U(SCH_1):PAGE314_I135@PURE_QUANTA.Q_RES(CHIPS)':
 C_PATH='@s9s_mb_2u_lib.s9s_mb_2u(sch_1):page314_i135@pure_quanta.q_res(chips)',
 P_PATH='@s9s_mb_2u_lib.s9s_mb_2u(sch_1):page213_i135@pure_quanta.q_res(chips)',
 PATH='I135',
 DRAWING='@S9S_MB_2U_LIB.S9S_MB_2U(SCH_1):PAGE314',
 PHYS_PAGE='213',
 XY='(2725,-25)',
 ROT='0',
 VER='1',
 PACK_TYPE='0402LF',
 LOCATION='R2661',
 CDS_LIB='pure_quanta',
 CDS_PART_NAME='Q_RES_0402LF-33.2,1%,1/16W,CHIA',
 WATTAGE='1/16W',
 TOLERANCE='1%',
 MATERIAL='CHIP',
 VALUE='33.2',
 PRIM_FILE='./archive_libs/logical/q_res/chips/chips.prt';

PART_NAME
 R2662 'Q_RES_0402LF-33.2,1%,1/16W,CHIA':;

SECTION_NUMBER 1
 '@S9S_MB_2U_LIB.S9S_MB_2U(SCH_1):PAGE314_I115@PURE_QUANTA.Q_RES(CHIPS)':
 C_PATH='@s9s_mb_2u_lib.s9s_mb_2u(sch_1):page314_i115@pure_quanta.q_res(chips)',
 P_PATH='@s9s_mb_2u_lib.s9s_mb_2u(sch_1):page213_i115@pure_quanta.q_res(chips)',
 PATH='I115',
 DRAWING='@S9S_MB_2U_LIB.S9S_MB_2U(SCH_1):PAGE314',
 PHYS_PAGE='213',
 XY='(2725,-150)',
 ROT='0',
 VER='1',
 PACK_TYPE='0402LF',
 LOCATION='R2662',
 CDS_LIB='pure_quanta',
 CDS_PART_NAME='Q_RES_0402LF-33.2,1%,1/16W,CHIA',
 WATTAGE='1/16W',
 TOLERANCE='1%',
 MATERIAL='CHIP',
 VALUE='33.2',
 PRIM_FILE='./archive_libs/logical/q_res/chips/chips.prt';

PART_NAME
 R2663 'Q_RES_0402LF-33.2,1%,1/16W,CHIA':;

SECTION_NUMBER 1
 '@S9S_MB_2U_LIB.S9S_MB_2U(SCH_1):PAGE314_I114@PURE_QUANTA.Q_RES(CHIPS)':
 C_PATH='@s9s_mb_2u_lib.s9s_mb_2u(sch_1):page314_i114@pure_quanta.q_res(chips)',
 P_PATH='@s9s_mb_2u_lib.s9s_mb_2u(sch_1):page213_i114@pure_quanta.q_res(chips)',
 PATH='I114',
 DRAWING='@S9S_MB_2U_LIB.S9S_MB_2U(SCH_1):PAGE314',
 PHYS_PAGE='213',
 XY='(2725,-275)',
 ROT='0',
 VER='1',
 PACK_TYPE='0402LF',
 LOCATION='R2663',
 CDS_LIB='pure_quanta',
 CDS_PART_NAME='Q_RES_0402LF-33.2,1%,1/16W,CHIA',
 WATTAGE='1/16W',
 TOLERANCE='1%',
 MATERIAL='CHIP',
 VALUE='33.2',
 PRIM_FILE='./archive_libs/logical/q_res/chips/chips.prt';

PART_NAME
 R2664 'Q_RES_0402LF-33.2,1%,1/16W,CHIA':;

SECTION_NUMBER 1
 '@S9S_MB_2U_LIB.S9S_MB_2U(SCH_1):PAGE314_I113@PURE_QUANTA.Q_RES(CHIPS)':
 C_PATH='@s9s_mb_2u_lib.s9s_mb_2u(sch_1):page314_i113@pure_quanta.q_res(chips)',
 P_PATH='@s9s_mb_2u_lib.s9s_mb_2u(sch_1):page213_i113@pure_quanta.q_res(chips)',
 PATH='I113',
 DRAWING='@S9S_MB_2U_LIB.S9S_MB_2U(SCH_1):PAGE314',
 PHYS_PAGE='213',
 XY='(2725,-400)',
 ROT='0',
 VER='1',
 PACK_TYPE='0402LF',
 LOCATION='R2664',
 CDS_LIB='pure_quanta',
 CDS_PART_NAME='Q_RES_0402LF-33.2,1%,1/16W,CHIA',
 WATTAGE='1/16W',
 TOLERANCE='1%',
 MATERIAL='CHIP',
 VALUE='33.2',
 PRIM_FILE='./archive_libs/logical/q_res/chips/chips.prt';

PART_NAME
 R2666 'Q_RES_0402LF-10K,1%,1/16W,CHIPA':;

SECTION_NUMBER 1
 '@S9S_MB_2U_LIB.S9S_MB_2U(SCH_1):PAGE222_I16@PURE_QUANTA.Q_RES(CHIPS)':
 C_PATH='@s9s_mb_2u_lib.s9s_mb_2u(sch_1):page222_i16@pure_quanta.q_res(chips)',
 P_PATH='@s9s_mb_2u_lib.s9s_mb_2u(sch_1):page234_i16@pure_quanta.q_res(chips)',
 PATH='I16',
 DRAWING='@S9S_MB_2U_LIB.S9S_MB_2U(SCH_1):PAGE222',
 PHYS_PAGE='234',
 XY='(-4825,4300)',
 ROT='0',
 VER='2',
 PACK_TYPE='0402LF',
 CDS_LIB='pure_quanta',
 CDS_PART_NAME='Q_RES_0402LF-10K,1%,1/16W,CHIPA',
 WATTAGE='1/16W',
 TOLERANCE='1%',
 MATERIAL='CHIP',
 VALUE='10K',
 PRIM_FILE='./archive_libs/logical/q_res/chips/chips.prt';

PART_NAME
 R2667 'Q_RES_0402LF-10K,1%,1/16W,CHIPA':;

SECTION_NUMBER 1
 '@S9S_MB_2U_LIB.S9S_MB_2U(SCH_1):PAGE222_I59@PURE_QUANTA.Q_RES(CHIPS)':
 C_PATH='@s9s_mb_2u_lib.s9s_mb_2u(sch_1):page222_i59@pure_quanta.q_res(chips)',
 P_PATH='@s9s_mb_2u_lib.s9s_mb_2u(sch_1):page234_i59@pure_quanta.q_res(chips)',
 PATH='I59',
 DRAWING='@S9S_MB_2U_LIB.S9S_MB_2U(SCH_1):PAGE222',
 PHYS_PAGE='234',
 XY='(-3150,9125)',
 ROT='0',
 VER='2',
 PACK_TYPE='0402LF',
 CDS_LIB='pure_quanta',
 CDS_PART_NAME='Q_RES_0402LF-10K,1%,1/16W,CHIPA',
 WATTAGE='1/16W',
 TOLERANCE='1%',
 MATERIAL='CHIP',
 VALUE='10K',
 PRIM_FILE='./archive_libs/logical/q_res/chips/chips.prt';

PART_NAME
 R2668 'Q_RES_0402LF-4.7K,5%,1/16W,EMPA':;

SECTION_NUMBER 1
 '@S9S_MB_2U_LIB.S9S_MB_2U(SCH_1):PAGE222_I75@PURE_QUANTA.Q_RES(CHIPS)':
 C_PATH='@s9s_mb_2u_lib.s9s_mb_2u(sch_1):page222_i75@pure_quanta.q_res(chips)',
 P_PATH='@s9s_mb_2u_lib.s9s_mb_2u(sch_1):page234_i75@pure_quanta.q_res(chips)',
 PATH='I75',
 DRAWING='@S9S_MB_2U_LIB.S9S_MB_2U(SCH_1):PAGE222',
 PHYS_PAGE='234',
 XY='(-700,5025)',
 ROT='0',
 VER='2',
 PACK_TYPE='0402LF',
 CDS_LIB='pure_quanta',
 CDS_PART_NAME='Q_RES_0402LF-4.7K,5%,1/16W,EMPA',
 WATTAGE='1/16W',
 TOLERANCE='5%',
 MATERIAL='EMPTY',
 VALUE='4.7K',
 PRIM_FILE='./archive_libs/logical/q_res/chips/chips.prt';

PART_NAME
 R2669 'Q_RES_0402LF-10K,1%,1/16W,CHIPA':;

SECTION_NUMBER 1
 '@S9S_MB_2U_LIB.S9S_MB_2U(SCH_1):PAGE222_I61@PURE_QUANTA.Q_RES(CHIPS)':
 C_PATH='@s9s_mb_2u_lib.s9s_mb_2u(sch_1):page222_i61@pure_quanta.q_res(chips)',
 P_PATH='@s9s_mb_2u_lib.s9s_mb_2u(sch_1):page234_i61@pure_quanta.q_res(chips)',
 PATH='I61',
 DRAWING='@S9S_MB_2U_LIB.S9S_MB_2U(SCH_1):PAGE222',
 PHYS_PAGE='234',
 XY='(-2900,9125)',
 ROT='0',
 VER='2',
 PACK_TYPE='0402LF',
 CDS_LIB='pure_quanta',
 CDS_PART_NAME='Q_RES_0402LF-10K,1%,1/16W,CHIPA',
 WATTAGE='1/16W',
 TOLERANCE='1%',
 MATERIAL='CHIP',
 VALUE='10K',
 PRIM_FILE='./archive_libs/logical/q_res/chips/chips.prt';

PART_NAME
 R2670 'Q_RES_0402LF-4.7K,5%,1/16W,EMPA':;

SECTION_NUMBER 1
 '@S9S_MB_2U_LIB.S9S_MB_2U(SCH_1):PAGE222_I77@PURE_QUANTA.Q_RES(CHIPS)':
 C_PATH='@s9s_mb_2u_lib.s9s_mb_2u(sch_1):page222_i77@pure_quanta.q_res(chips)',
 P_PATH='@s9s_mb_2u_lib.s9s_mb_2u(sch_1):page234_i77@pure_quanta.q_res(chips)',
 PATH='I77',
 DRAWING='@S9S_MB_2U_LIB.S9S_MB_2U(SCH_1):PAGE222',
 PHYS_PAGE='234',
 XY='(-450,5025)',
 ROT='0',
 VER='2',
 PACK_TYPE='0402LF',
 CDS_LIB='pure_quanta',
 CDS_PART_NAME='Q_RES_0402LF-4.7K,5%,1/16W,EMPA',
 WATTAGE='1/16W',
 TOLERANCE='5%',
 MATERIAL='EMPTY',
 VALUE='4.7K',
 PRIM_FILE='./archive_libs/logical/q_res/chips/chips.prt';

PART_NAME
 R2671 'Q_RES_0402LF-33.2,1%,1/16W,CHIA':;

SECTION_NUMBER 1
 '@S9S_MB_2U_LIB.S9S_MB_2U(SCH_1):PAGE222_I65@PURE_QUANTA.Q_RES(CHIPS)':
 C_PATH='@s9s_mb_2u_lib.s9s_mb_2u(sch_1):page222_i65@pure_quanta.q_res(chips)',
 P_PATH='@s9s_mb_2u_lib.s9s_mb_2u(sch_1):page234_i65@pure_quanta.q_res(chips)',
 PATH='I65',
 DRAWING='@S9S_MB_2U_LIB.S9S_MB_2U(SCH_1):PAGE222',
 PHYS_PAGE='234',
 XY='(-2600,8800)',
 ROT='0',
 VER='1',
 PACK_TYPE='0402LF',
 CDS_LIB='pure_quanta',
 CDS_PART_NAME='Q_RES_0402LF-33.2,1%,1/16W,CHIA',
 WATTAGE='1/16W',
 TOLERANCE='1%',
 MATERIAL='CHIP',
 VALUE='33.2',
 PRIM_FILE='./archive_libs/logical/q_res/chips/chips.prt';

PART_NAME
 R2672 'Q_RES_0402LF-33.2,1%,1/16W,CHIA':;

SECTION_NUMBER 1
 '@S9S_MB_2U_LIB.S9S_MB_2U(SCH_1):PAGE222_I64@PURE_QUANTA.Q_RES(CHIPS)':
 C_PATH='@s9s_mb_2u_lib.s9s_mb_2u(sch_1):page222_i64@pure_quanta.q_res(chips)',
 P_PATH='@s9s_mb_2u_lib.s9s_mb_2u(sch_1):page234_i64@pure_quanta.q_res(chips)',
 PATH='I64',
 DRAWING='@S9S_MB_2U_LIB.S9S_MB_2U(SCH_1):PAGE222',
 PHYS_PAGE='234',
 XY='(-2600,8700)',
 ROT='0',
 VER='1',
 PACK_TYPE='0402LF',
 CDS_LIB='pure_quanta',
 CDS_PART_NAME='Q_RES_0402LF-33.2,1%,1/16W,CHIA',
 WATTAGE='1/16W',
 TOLERANCE='1%',
 MATERIAL='CHIP',
 VALUE='33.2',
 PRIM_FILE='./archive_libs/logical/q_res/chips/chips.prt';

PART_NAME
 R2674 'Q_RES_0402LF-27.4,1%,1/16W,CHIA':;

SECTION_NUMBER 1
 '@S9S_MB_2U_LIB.S9S_MB_2U(SCH_1):PAGE222_I71@PURE_QUANTA.Q_RES(CHIPS)':
 C_PATH='@s9s_mb_2u_lib.s9s_mb_2u(sch_1):page222_i71@pure_quanta.q_res(chips)',
 P_PATH='@s9s_mb_2u_lib.s9s_mb_2u(sch_1):page234_i71@pure_quanta.q_res(chips)',
 PATH='I71',
 DRAWING='@S9S_MB_2U_LIB.S9S_MB_2U(SCH_1):PAGE222',
 PHYS_PAGE='234',
 XY='(-150,4550)',
 ROT='0',
 VER='1',
 PACK_TYPE='0402LF',
 CDS_LIB='pure_quanta',
 CDS_PART_NAME='Q_RES_0402LF-27.4,1%,1/16W,CHIA',
 WATTAGE='1/16W',
 TOLERANCE='1%',
 MATERIAL='CHIP',
 VALUE='27.4',
 PRIM_FILE='./archive_libs/logical/q_res/chips/chips.prt';

PART_NAME
 R2675 'Q_RES_0402LF-33.2,1%,1/16W,CHIA':;

SECTION_NUMBER 1
 '@S9S_MB_2U_LIB.S9S_MB_2U(SCH_1):PAGE222_I72@PURE_QUANTA.Q_RES(CHIPS)':
 C_PATH='@s9s_mb_2u_lib.s9s_mb_2u(sch_1):page222_i72@pure_quanta.q_res(chips)',
 P_PATH='@s9s_mb_2u_lib.s9s_mb_2u(sch_1):page234_i72@pure_quanta.q_res(chips)',
 PATH='I72',
 DRAWING='@S9S_MB_2U_LIB.S9S_MB_2U(SCH_1):PAGE222',
 PHYS_PAGE='234',
 XY='(-150,4650)',
 ROT='0',
 VER='1',
 PACK_TYPE='0402LF',
 CDS_LIB='pure_quanta',
 CDS_PART_NAME='Q_RES_0402LF-33.2,1%,1/16W,CHIA',
 WATTAGE='1/16W',
 TOLERANCE='1%',
 MATERIAL='CHIP',
 VALUE='33.2',
 PRIM_FILE='./archive_libs/logical/q_res/chips/chips.prt';

PART_NAME
 R2676 'Q_RES_0402LF-0,5%,1/16W,CHIP,CA':;

SECTION_NUMBER 1
 '@S9S_MB_2U_LIB.S9S_MB_2U(SCH_1):PAGE222_I19@PURE_QUANTA.Q_RES(CHIPS)':
 C_PATH='@s9s_mb_2u_lib.s9s_mb_2u(sch_1):page222_i19@pure_quanta.q_res(chips)',
 P_PATH='@s9s_mb_2u_lib.s9s_mb_2u(sch_1):page234_i19@pure_quanta.q_res(chips)',
 PATH='I19',
 DRAWING='@S9S_MB_2U_LIB.S9S_MB_2U(SCH_1):PAGE222',
 PHYS_PAGE='234',
 XY='(-4050,4750)',
 ROT='0',
 VER='1',
 PACK_TYPE='0402LF',
 CDS_LIB='pure_quanta',
 CDS_PART_NAME='Q_RES_0402LF-0,5%,1/16W,CHIP,CA',
 WATTAGE='1/16W',
 TOLERANCE='5%',
 MATERIAL='CHIP',
 VALUE='0',
 PRIM_FILE='./archive_libs/logical/q_res/chips/chips.prt';

PART_NAME
 R2693 'Q_RES_0402LF-1K,1%,1/16W,EMPTYA':;

SECTION_NUMBER 1
 '@S9S_MB_2U_LIB.S9S_MB_2U(SCH_1):PAGE214_I76@PURE_QUANTA.Q_RES(CHIPS)':
 C_PATH='@s9s_mb_2u_lib.s9s_mb_2u(sch_1):page214_i76@pure_quanta.q_res(chips)',
 P_PATH='@s9s_mb_2u_lib.s9s_mb_2u(sch_1):page227_i76@pure_quanta.q_res(chips)',
 PATH='I76',
 DRAWING='@S9S_MB_2U_LIB.S9S_MB_2U(SCH_1):PAGE214',
 PHYS_PAGE='227',
 XY='(5100,3375)',
 ROT='0',
 VER='2',
 PACK_TYPE='0402LF',
 CDS_LIB='pure_quanta',
 CDS_PART_NAME='Q_RES_0402LF-1K,1%,1/16W,EMPTYA',
 WATTAGE='1/16W',
 TOLERANCE='1%',
 MATERIAL='EMPTY',
 VALUE='1K',
 PRIM_FILE='./archive_libs/logical/q_res/chips/chips.prt';

PART_NAME
 R2694 'Q_RES_0402LF-1K,1%,1/16W,CHIP,A':;

SECTION_NUMBER 1
 '@S9S_MB_2U_LIB.S9S_MB_2U(SCH_1):PAGE214_I77@PURE_QUANTA.Q_RES(CHIPS)':
 C_PATH='@s9s_mb_2u_lib.s9s_mb_2u(sch_1):page214_i77@pure_quanta.q_res(chips)',
 P_PATH='@s9s_mb_2u_lib.s9s_mb_2u(sch_1):page227_i77@pure_quanta.q_res(chips)',
 PATH='I77',
 DRAWING='@S9S_MB_2U_LIB.S9S_MB_2U(SCH_1):PAGE214',
 PHYS_PAGE='227',
 XY='(5100,2775)',
 ROT='0',
 VER='2',
 PACK_TYPE='0402LF',
 CDS_LIB='pure_quanta',
 CDS_PART_NAME='Q_RES_0402LF-1K,1%,1/16W,CHIP,A',
 WATTAGE='1/16W',
 TOLERANCE='1%',
 MATERIAL='CHIP',
 VALUE='1K',
 PRIM_FILE='./archive_libs/logical/q_res/chips/chips.prt';

PART_NAME
 R2695 'Q_RES_0402LF-1K,1%,1/16W,EMPTYA':;

SECTION_NUMBER 1
 '@S9S_MB_2U_LIB.S9S_MB_2U(SCH_1):PAGE214_I74@PURE_QUANTA.Q_RES(CHIPS)':
 C_PATH='@s9s_mb_2u_lib.s9s_mb_2u(sch_1):page214_i74@pure_quanta.q_res(chips)',
 P_PATH='@s9s_mb_2u_lib.s9s_mb_2u(sch_1):page227_i74@pure_quanta.q_res(chips)',
 PATH='I74',
 DRAWING='@S9S_MB_2U_LIB.S9S_MB_2U(SCH_1):PAGE214',
 PHYS_PAGE='227',
 XY='(5350,3375)',
 ROT='0',
 VER='2',
 PACK_TYPE='0402LF',
 CDS_LIB='pure_quanta',
 CDS_PART_NAME='Q_RES_0402LF-1K,1%,1/16W,EMPTYA',
 WATTAGE='1/16W',
 TOLERANCE='1%',
 MATERIAL='EMPTY',
 VALUE='1K',
 PRIM_FILE='./archive_libs/logical/q_res/chips/chips.prt';

PART_NAME
 R2696 'Q_RES_0402LF-1K,1%,1/16W,CHIP,A':;

SECTION_NUMBER 1
 '@S9S_MB_2U_LIB.S9S_MB_2U(SCH_1):PAGE214_I75@PURE_QUANTA.Q_RES(CHIPS)':
 C_PATH='@s9s_mb_2u_lib.s9s_mb_2u(sch_1):page214_i75@pure_quanta.q_res(chips)',
 P_PATH='@s9s_mb_2u_lib.s9s_mb_2u(sch_1):page227_i75@pure_quanta.q_res(chips)',
 PATH='I75',
 DRAWING='@S9S_MB_2U_LIB.S9S_MB_2U(SCH_1):PAGE214',
 PHYS_PAGE='227',
 XY='(5350,2775)',
 ROT='0',
 VER='2',
 PACK_TYPE='0402LF',
 CDS_LIB='pure_quanta',
 CDS_PART_NAME='Q_RES_0402LF-1K,1%,1/16W,CHIP,A',
 WATTAGE='1/16W',
 TOLERANCE='1%',
 MATERIAL='CHIP',
 VALUE='1K',
 PRIM_FILE='./archive_libs/logical/q_res/chips/chips.prt';

PART_NAME
 R2703 'Q_RES_0402LF-0,5%,1/16W,CHIP,CA':;

SECTION_NUMBER 1
 '@S9S_MB_2U_LIB.S9S_MB_2U(SCH_1):PAGE219_I63@PURE_QUANTA.Q_RES(CHIPS)':
 C_PATH='@s9s_mb_2u_lib.s9s_mb_2u(sch_1):page219_i63@pure_quanta.q_res(chips)',
 P_PATH='@s9s_mb_2u_lib.s9s_mb_2u(sch_1):page231_i63@pure_quanta.q_res(chips)',
 PATH='I63',
 DRAWING='@S9S_MB_2U_LIB.S9S_MB_2U(SCH_1):PAGE219',
 PHYS_PAGE='231',
 XY='(3400,2725)',
 ROT='0',
 VER='1',
 PACK_TYPE='0402LF',
 CDS_LIB='pure_quanta',
 CDS_PART_NAME='Q_RES_0402LF-0,5%,1/16W,CHIP,CA',
 WATTAGE='1/16W',
 TOLERANCE='5%',
 MATERIAL='CHIP',
 VALUE='0',
 PRIM_FILE='./archive_libs/logical/q_res/chips/chips.prt';

PART_NAME
 R2704 'Q_RES_0402LF-0,5%,1/16W,CHIP,CA':;

SECTION_NUMBER 1
 '@S9S_MB_2U_LIB.S9S_MB_2U(SCH_1):PAGE219_I64@PURE_QUANTA.Q_RES(CHIPS)':
 C_PATH='@s9s_mb_2u_lib.s9s_mb_2u(sch_1):page219_i64@pure_quanta.q_res(chips)',
 P_PATH='@s9s_mb_2u_lib.s9s_mb_2u(sch_1):page231_i64@pure_quanta.q_res(chips)',
 PATH='I64',
 DRAWING='@S9S_MB_2U_LIB.S9S_MB_2U(SCH_1):PAGE219',
 PHYS_PAGE='231',
 XY='(3400,2775)',
 ROT='0',
 VER='1',
 PACK_TYPE='0402LF',
 CDS_LIB='pure_quanta',
 CDS_PART_NAME='Q_RES_0402LF-0,5%,1/16W,CHIP,CA',
 WATTAGE='1/16W',
 TOLERANCE='5%',
 MATERIAL='CHIP',
 VALUE='0',
 PRIM_FILE='./archive_libs/logical/q_res/chips/chips.prt';

PART_NAME
 R2705 'Q_RES_0402LF-0,5%,1/16W,EMPTY,A':;

SECTION_NUMBER 1
 '@S9S_MB_2U_LIB.S9S_MB_2U(SCH_1):PAGE222_I55@PURE_QUANTA.Q_RES(CHIPS)':
 C_PATH='@s9s_mb_2u_lib.s9s_mb_2u(sch_1):page222_i55@pure_quanta.q_res(chips)',
 P_PATH='@s9s_mb_2u_lib.s9s_mb_2u(sch_1):page234_i55@pure_quanta.q_res(chips)',
 PATH='I55',
 DRAWING='@S9S_MB_2U_LIB.S9S_MB_2U(SCH_1):PAGE222',
 PHYS_PAGE='234',
 XY='(-4650,8350)',
 ROT='0',
 VER='1',
 PACK_TYPE='0402LF',
 CDS_LIB='pure_quanta',
 CDS_PART_NAME='Q_RES_0402LF-0,5%,1/16W,EMPTY,A',
 WATTAGE='1/16W',
 TOLERANCE='5%',
 MATERIAL='EMPTY',
 VALUE='0',
 PRIM_FILE='./archive_libs/logical/q_res/chips/chips.prt';

PART_NAME
 R2706 'Q_RES_0402LF-0,5%,1/16W,CHIP,CA':;

SECTION_NUMBER 1
 '@S9S_MB_2U_LIB.S9S_MB_2U(SCH_1):PAGE222_I30@PURE_QUANTA.Q_RES(CHIPS)':
 C_PATH='@s9s_mb_2u_lib.s9s_mb_2u(sch_1):page222_i30@pure_quanta.q_res(chips)',
 P_PATH='@s9s_mb_2u_lib.s9s_mb_2u(sch_1):page234_i30@pure_quanta.q_res(chips)',
 PATH='I30',
 DRAWING='@S9S_MB_2U_LIB.S9S_MB_2U(SCH_1):PAGE222',
 PHYS_PAGE='234',
 XY='(-2325,3900)',
 ROT='0',
 VER='1',
 PACK_TYPE='0402LF',
 CDS_LIB='pure_quanta',
 CDS_PART_NAME='Q_RES_0402LF-0,5%,1/16W,CHIP,CA',
 WATTAGE='1/16W',
 TOLERANCE='5%',
 MATERIAL='CHIP',
 VALUE='0',
 PRIM_FILE='./archive_libs/logical/q_res/chips/chips.prt';

PART_NAME
 R2707 'Q_RES_0402LF-0,5%,1/16W,CHIP,CA':;

SECTION_NUMBER 1
 '@S9S_MB_2U_LIB.S9S_MB_2U(SCH_1):PAGE222_I44@PURE_QUANTA.Q_RES(CHIPS)':
 C_PATH='@s9s_mb_2u_lib.s9s_mb_2u(sch_1):page222_i44@pure_quanta.q_res(chips)',
 P_PATH='@s9s_mb_2u_lib.s9s_mb_2u(sch_1):page234_i44@pure_quanta.q_res(chips)',
 PATH='I44',
 DRAWING='@S9S_MB_2U_LIB.S9S_MB_2U(SCH_1):PAGE222',
 PHYS_PAGE='234',
 XY='(-6125,8900)',
 ROT='0',
 VER='1',
 PACK_TYPE='0402LF',
 CDS_LIB='pure_quanta',
 CDS_PART_NAME='Q_RES_0402LF-0,5%,1/16W,CHIP,CA',
 WATTAGE='1/16W',
 TOLERANCE='5%',
 MATERIAL='CHIP',
 VALUE='0',
 PRIM_FILE='./archive_libs/logical/q_res/chips/chips.prt';

PART_NAME
 R2724 'Q_RES_0402LF-0,5%,1/16W,EMPTY,A':;

SECTION_NUMBER 1
 '@S9S_MB_2U_LIB.S9S_MB_2U(SCH_1):PAGE222_I54@PURE_QUANTA.Q_RES(CHIPS)':
 C_PATH='@s9s_mb_2u_lib.s9s_mb_2u(sch_1):page222_i54@pure_quanta.q_res(chips)',
 P_PATH='@s9s_mb_2u_lib.s9s_mb_2u(sch_1):page234_i54@pure_quanta.q_res(chips)',
 PATH='I54',
 DRAWING='@S9S_MB_2U_LIB.S9S_MB_2U(SCH_1):PAGE222',
 PHYS_PAGE='234',
 XY='(-4650,8275)',
 ROT='0',
 VER='1',
 PACK_TYPE='0402LF',
 CDS_LIB='pure_quanta',
 CDS_PART_NAME='Q_RES_0402LF-0,5%,1/16W,EMPTY,A',
 WATTAGE='1/16W',
 TOLERANCE='5%',
 MATERIAL='EMPTY',
 VALUE='0',
 PRIM_FILE='./archive_libs/logical/q_res/chips/chips.prt';

PART_NAME
 R2725 'Q_RES_0402LF-0,5%,1/16W,CHIP,CA':;

SECTION_NUMBER 1
 '@S9S_MB_2U_LIB.S9S_MB_2U(SCH_1):PAGE222_I29@PURE_QUANTA.Q_RES(CHIPS)':
 C_PATH='@s9s_mb_2u_lib.s9s_mb_2u(sch_1):page222_i29@pure_quanta.q_res(chips)',
 P_PATH='@s9s_mb_2u_lib.s9s_mb_2u(sch_1):page234_i29@pure_quanta.q_res(chips)',
 PATH='I29',
 DRAWING='@S9S_MB_2U_LIB.S9S_MB_2U(SCH_1):PAGE222',
 PHYS_PAGE='234',
 XY='(-2325,3825)',
 ROT='0',
 VER='1',
 PACK_TYPE='0402LF',
 CDS_LIB='pure_quanta',
 CDS_PART_NAME='Q_RES_0402LF-0,5%,1/16W,CHIP,CA',
 WATTAGE='1/16W',
 TOLERANCE='5%',
 MATERIAL='CHIP',
 VALUE='0',
 PRIM_FILE='./archive_libs/logical/q_res/chips/chips.prt';

PART_NAME
 R2726 'Q_RES_0402LF-33.2,1%,1/16W,CHIA':;

SECTION_NUMBER 1
 '@S9S_MB_2U_LIB.S9S_MB_2U(SCH_1):PAGE114_I32@PURE_QUANTA.Q_RES(CHIPS)':
 C_PATH='@s9s_mb_2u_lib.s9s_mb_2u(sch_1):page114_i32@pure_quanta.q_res(chips)',
 P_PATH='@s9s_mb_2u_lib.s9s_mb_2u(sch_1):page114_i32@pure_quanta.q_res(chips)',
 PATH='I32',
 DRAWING='@S9S_MB_2U_LIB.S9S_MB_2U(SCH_1):PAGE114',
 PHYS_PAGE='114',
 XY='(-9375,6500)',
 ROT='0',
 VER='1',
 PACK_TYPE='0402LF',
 CDS_LIB='pure_quanta',
 CDS_PART_NAME='Q_RES_0402LF-33.2,1%,1/16W,CHIA',
 WATTAGE='1/16W',
 TOLERANCE='1%',
 MATERIAL='CHIP',
 VALUE='33.2',
 PRIM_FILE='./archive_libs/logical/q_res/chips/chips.prt';

PART_NAME
 R2727 'Q_RES_0402LF-33.2,1%,1/16W,CHIA':;

SECTION_NUMBER 1
 '@S9S_MB_2U_LIB.S9S_MB_2U(SCH_1):PAGE114_I31@PURE_QUANTA.Q_RES(CHIPS)':
 C_PATH='@s9s_mb_2u_lib.s9s_mb_2u(sch_1):page114_i31@pure_quanta.q_res(chips)',
 P_PATH='@s9s_mb_2u_lib.s9s_mb_2u(sch_1):page114_i31@pure_quanta.q_res(chips)',
 PATH='I31',
 DRAWING='@S9S_MB_2U_LIB.S9S_MB_2U(SCH_1):PAGE114',
 PHYS_PAGE='114',
 XY='(-9375,6450)',
 ROT='0',
 VER='1',
 PACK_TYPE='0402LF',
 CDS_LIB='pure_quanta',
 CDS_PART_NAME='Q_RES_0402LF-33.2,1%,1/16W,CHIA',
 WATTAGE='1/16W',
 TOLERANCE='1%',
 MATERIAL='CHIP',
 VALUE='33.2',
 PRIM_FILE='./archive_libs/logical/q_res/chips/chips.prt';

PART_NAME
 R2728 'Q_RES_0402LF-33.2,1%,1/16W,CHIA':;

SECTION_NUMBER 1
 '@S9S_MB_2U_LIB.S9S_MB_2U(SCH_1):PAGE114_I30@PURE_QUANTA.Q_RES(CHIPS)':
 C_PATH='@s9s_mb_2u_lib.s9s_mb_2u(sch_1):page114_i30@pure_quanta.q_res(chips)',
 P_PATH='@s9s_mb_2u_lib.s9s_mb_2u(sch_1):page114_i30@pure_quanta.q_res(chips)',
 PATH='I30',
 DRAWING='@S9S_MB_2U_LIB.S9S_MB_2U(SCH_1):PAGE114',
 PHYS_PAGE='114',
 XY='(-9375,6275)',
 ROT='0',
 VER='1',
 PACK_TYPE='0402LF',
 CDS_LIB='pure_quanta',
 CDS_PART_NAME='Q_RES_0402LF-33.2,1%,1/16W,CHIA',
 WATTAGE='1/16W',
 TOLERANCE='1%',
 MATERIAL='CHIP',
 VALUE='33.2',
 PRIM_FILE='./archive_libs/logical/q_res/chips/chips.prt';

PART_NAME
 R2729 'Q_RES_0402LF-33.2,1%,1/16W,CHIA':;

SECTION_NUMBER 1
 '@S9S_MB_2U_LIB.S9S_MB_2U(SCH_1):PAGE114_I28@PURE_QUANTA.Q_RES(CHIPS)':
 C_PATH='@s9s_mb_2u_lib.s9s_mb_2u(sch_1):page114_i28@pure_quanta.q_res(chips)',
 P_PATH='@s9s_mb_2u_lib.s9s_mb_2u(sch_1):page114_i28@pure_quanta.q_res(chips)',
 PATH='I28',
 DRAWING='@S9S_MB_2U_LIB.S9S_MB_2U(SCH_1):PAGE114',
 PHYS_PAGE='114',
 XY='(-9375,5950)',
 ROT='0',
 VER='1',
 PACK_TYPE='0402LF',
 CDS_LIB='pure_quanta',
 CDS_PART_NAME='Q_RES_0402LF-33.2,1%,1/16W,CHIA',
 WATTAGE='1/16W',
 TOLERANCE='1%',
 MATERIAL='CHIP',
 VALUE='33.2',
 PRIM_FILE='./archive_libs/logical/q_res/chips/chips.prt';

PART_NAME
 R2730 'Q_RES_0402LF-33.2,1%,1/16W,CHIA':;

SECTION_NUMBER 1
 '@S9S_MB_2U_LIB.S9S_MB_2U(SCH_1):PAGE114_I27@PURE_QUANTA.Q_RES(CHIPS)':
 C_PATH='@s9s_mb_2u_lib.s9s_mb_2u(sch_1):page114_i27@pure_quanta.q_res(chips)',
 P_PATH='@s9s_mb_2u_lib.s9s_mb_2u(sch_1):page114_i27@pure_quanta.q_res(chips)',
 PATH='I27',
 DRAWING='@S9S_MB_2U_LIB.S9S_MB_2U(SCH_1):PAGE114',
 PHYS_PAGE='114',
 XY='(-9375,5900)',
 ROT='0',
 VER='1',
 PACK_TYPE='0402LF',
 CDS_LIB='pure_quanta',
 CDS_PART_NAME='Q_RES_0402LF-33.2,1%,1/16W,CHIA',
 WATTAGE='1/16W',
 TOLERANCE='1%',
 MATERIAL='CHIP',
 VALUE='33.2',
 PRIM_FILE='./archive_libs/logical/q_res/chips/chips.prt';

PART_NAME
 R2731 'Q_RES_0402LF-33.2,1%,1/16W,CHIA':;

SECTION_NUMBER 1
 '@S9S_MB_2U_LIB.S9S_MB_2U(SCH_1):PAGE114_I25@PURE_QUANTA.Q_RES(CHIPS)':
 C_PATH='@s9s_mb_2u_lib.s9s_mb_2u(sch_1):page114_i25@pure_quanta.q_res(chips)',
 P_PATH='@s9s_mb_2u_lib.s9s_mb_2u(sch_1):page114_i25@pure_quanta.q_res(chips)',
 PATH='I25',
 DRAWING='@S9S_MB_2U_LIB.S9S_MB_2U(SCH_1):PAGE114',
 PHYS_PAGE='114',
 XY='(-9375,5725)',
 ROT='0',
 VER='1',
 PACK_TYPE='0402LF',
 CDS_LIB='pure_quanta',
 CDS_PART_NAME='Q_RES_0402LF-33.2,1%,1/16W,CHIA',
 WATTAGE='1/16W',
 TOLERANCE='1%',
 MATERIAL='CHIP',
 VALUE='33.2',
 PRIM_FILE='./archive_libs/logical/q_res/chips/chips.prt';

PART_NAME
 R2732 'Q_RES_0402LF-33.2,1%,1/16W,CHIA':;

SECTION_NUMBER 1
 '@S9S_MB_2U_LIB.S9S_MB_2U(SCH_1):PAGE114_I22@PURE_QUANTA.Q_RES(CHIPS)':
 C_PATH='@s9s_mb_2u_lib.s9s_mb_2u(sch_1):page114_i22@pure_quanta.q_res(chips)',
 P_PATH='@s9s_mb_2u_lib.s9s_mb_2u(sch_1):page114_i22@pure_quanta.q_res(chips)',
 PATH='I22',
 DRAWING='@S9S_MB_2U_LIB.S9S_MB_2U(SCH_1):PAGE114',
 PHYS_PAGE='114',
 XY='(-9375,5175)',
 ROT='0',
 VER='1',
 PACK_TYPE='0402LF',
 CDS_LIB='pure_quanta',
 CDS_PART_NAME='Q_RES_0402LF-33.2,1%,1/16W,CHIA',
 WATTAGE='1/16W',
 TOLERANCE='1%',
 MATERIAL='CHIP',
 VALUE='33.2',
 PRIM_FILE='./archive_libs/logical/q_res/chips/chips.prt';

PART_NAME
 R2733 'Q_RES_0402LF-33.2,1%,1/16W,CHIA':;

SECTION_NUMBER 1
 '@S9S_MB_2U_LIB.S9S_MB_2U(SCH_1):PAGE114_I21@PURE_QUANTA.Q_RES(CHIPS)':
 C_PATH='@s9s_mb_2u_lib.s9s_mb_2u(sch_1):page114_i21@pure_quanta.q_res(chips)',
 P_PATH='@s9s_mb_2u_lib.s9s_mb_2u(sch_1):page114_i21@pure_quanta.q_res(chips)',
 PATH='I21',
 DRAWING='@S9S_MB_2U_LIB.S9S_MB_2U(SCH_1):PAGE114',
 PHYS_PAGE='114',
 XY='(-9375,5125)',
 ROT='0',
 VER='1',
 PACK_TYPE='0402LF',
 CDS_LIB='pure_quanta',
 CDS_PART_NAME='Q_RES_0402LF-33.2,1%,1/16W,CHIA',
 WATTAGE='1/16W',
 TOLERANCE='1%',
 MATERIAL='CHIP',
 VALUE='33.2',
 PRIM_FILE='./archive_libs/logical/q_res/chips/chips.prt';

PART_NAME
 R2734 'Q_RES_0402LF-33.2,1%,1/16W,CHIA':;

SECTION_NUMBER 1
 '@S9S_MB_2U_LIB.S9S_MB_2U(SCH_1):PAGE114_I18@PURE_QUANTA.Q_RES(CHIPS)':
 C_PATH='@s9s_mb_2u_lib.s9s_mb_2u(sch_1):page114_i18@pure_quanta.q_res(chips)',
 P_PATH='@s9s_mb_2u_lib.s9s_mb_2u(sch_1):page114_i18@pure_quanta.q_res(chips)',
 PATH='I18',
 DRAWING='@S9S_MB_2U_LIB.S9S_MB_2U(SCH_1):PAGE114',
 PHYS_PAGE='114',
 XY='(-9375,4625)',
 ROT='0',
 VER='1',
 PACK_TYPE='0402LF',
 CDS_LIB='pure_quanta',
 CDS_PART_NAME='Q_RES_0402LF-33.2,1%,1/16W,CHIA',
 WATTAGE='1/16W',
 TOLERANCE='1%',
 MATERIAL='CHIP',
 VALUE='33.2',
 PRIM_FILE='./archive_libs/logical/q_res/chips/chips.prt';

PART_NAME
 R2735 'Q_RES_0402LF-33.2,1%,1/16W,CHIA':;

SECTION_NUMBER 1
 '@S9S_MB_2U_LIB.S9S_MB_2U(SCH_1):PAGE114_I17@PURE_QUANTA.Q_RES(CHIPS)':
 C_PATH='@s9s_mb_2u_lib.s9s_mb_2u(sch_1):page114_i17@pure_quanta.q_res(chips)',
 P_PATH='@s9s_mb_2u_lib.s9s_mb_2u(sch_1):page114_i17@pure_quanta.q_res(chips)',
 PATH='I17',
 DRAWING='@S9S_MB_2U_LIB.S9S_MB_2U(SCH_1):PAGE114',
 PHYS_PAGE='114',
 XY='(-9375,4575)',
 ROT='0',
 VER='1',
 PACK_TYPE='0402LF',
 CDS_LIB='pure_quanta',
 CDS_PART_NAME='Q_RES_0402LF-33.2,1%,1/16W,CHIA',
 WATTAGE='1/16W',
 TOLERANCE='1%',
 MATERIAL='CHIP',
 VALUE='33.2',
 PRIM_FILE='./archive_libs/logical/q_res/chips/chips.prt';

PART_NAME
 R2736 'Q_RES_0402LF-33.2,1%,1/16W,CHIA':;

SECTION_NUMBER 1
 '@S9S_MB_2U_LIB.S9S_MB_2U(SCH_1):PAGE114_I61@PURE_QUANTA.Q_RES(CHIPS)':
 C_PATH='@s9s_mb_2u_lib.s9s_mb_2u(sch_1):page114_i61@pure_quanta.q_res(chips)',
 P_PATH='@s9s_mb_2u_lib.s9s_mb_2u(sch_1):page114_i61@pure_quanta.q_res(chips)',
 PATH='I61',
 DRAWING='@S9S_MB_2U_LIB.S9S_MB_2U(SCH_1):PAGE114',
 PHYS_PAGE='114',
 XY='(-5700,5125)',
 ROT='0',
 VER='1',
 PACK_TYPE='0402LF',
 CDS_LIB='pure_quanta',
 CDS_PART_NAME='Q_RES_0402LF-33.2,1%,1/16W,CHIA',
 WATTAGE='1/16W',
 TOLERANCE='1%',
 MATERIAL='CHIP',
 VALUE='33.2',
 PRIM_FILE='./archive_libs/logical/q_res/chips/chips.prt';

PART_NAME
 R2738 'Q_RES_0402LF-33.2,1%,1/16W,CHIA':;

SECTION_NUMBER 1
 '@S9S_MB_2U_LIB.S9S_MB_2U(SCH_1):PAGE212_I127@PURE_QUANTA.Q_RES(CHIPS)':
 C_PATH='@s9s_mb_2u_lib.s9s_mb_2u(sch_1):page212_i127@pure_quanta.q_res(chips)',
 P_PATH='@s9s_mb_2u_lib.s9s_mb_2u(sch_1):page223_i127@pure_quanta.q_res(chips)',
 PATH='I127',
 DRAWING='@S9S_MB_2U_LIB.S9S_MB_2U(SCH_1):PAGE212',
 PHYS_PAGE='223',
 XY='(1900,300)',
 ROT='0',
 VER='1',
 PACK_TYPE='0402LF',
 CDS_LIB='pure_quanta',
 CDS_PART_NAME='Q_RES_0402LF-33.2,1%,1/16W,CHIA',
 WATTAGE='1/16W',
 TOLERANCE='1%',
 MATERIAL='CHIP',
 VALUE='33.2',
 PRIM_FILE='./archive_libs/logical/q_res/chips/chips.prt';

PART_NAME
 R2786 'Q_RES_0402LF-0,5%,1/16W,CHIP,CA':
 ROOM='USB1_BOM1';

SECTION_NUMBER 1
 '@S9S_MB_2U_LIB.S9S_MB_2U(SCH_1):PAGE155_I79@PURE_QUANTA.Q_RES(CHIPS)':
 C_PATH='@s9s_mb_2u_lib.s9s_mb_2u(sch_1):page155_i79@pure_quanta.q_res(chips)',
 P_PATH='@s9s_mb_2u_lib.s9s_mb_2u(sch_1):page152_i79@pure_quanta.q_res(chips)',
 PATH='I79',
 DRAWING='@S9S_MB_2U_LIB.S9S_MB_2U(SCH_1):PAGE155',
 PHYS_PAGE='152',
 XY='(-2175,225)',
 ROT='0',
 VER='1',
 PACK_TYPE='0402LF',
 CDS_LIB='pure_quanta',
 CDS_PART_NAME='Q_RES_0402LF-0,5%,1/16W,CHIP,CA',
 WATTAGE='1/16W',
 TOLERANCE='5%',
 MATERIAL='CHIP',
 ROOM='USB1_BOM1',
 VALUE='0',
 PRIM_FILE='./archive_libs/logical/q_res/chips/chips.prt';

PART_NAME
 R2787 'Q_RES_0402LF-0,5%,1/16W,CHIP,CA':
 ROOM='USB1_BOM1';

SECTION_NUMBER 1
 '@S9S_MB_2U_LIB.S9S_MB_2U(SCH_1):PAGE155_I78@PURE_QUANTA.Q_RES(CHIPS)':
 C_PATH='@s9s_mb_2u_lib.s9s_mb_2u(sch_1):page155_i78@pure_quanta.q_res(chips)',
 P_PATH='@s9s_mb_2u_lib.s9s_mb_2u(sch_1):page152_i78@pure_quanta.q_res(chips)',
 PATH='I78',
 DRAWING='@S9S_MB_2U_LIB.S9S_MB_2U(SCH_1):PAGE155',
 PHYS_PAGE='152',
 XY='(-2175,175)',
 ROT='0',
 VER='1',
 PACK_TYPE='0402LF',
 CDS_LIB='pure_quanta',
 CDS_PART_NAME='Q_RES_0402LF-0,5%,1/16W,CHIP,CA',
 WATTAGE='1/16W',
 TOLERANCE='5%',
 MATERIAL='CHIP',
 ROOM='USB1_BOM1',
 VALUE='0',
 PRIM_FILE='./archive_libs/logical/q_res/chips/chips.prt';

PART_NAME
 R2788 'Q_RES_0402LF-0,5%,1/16W,EMPTY,A':
 ROOM='USB1_BOM2';

SECTION_NUMBER 1
 '@S9S_MB_2U_LIB.S9S_MB_2U(SCH_1):PAGE155_I99@PURE_QUANTA.Q_RES(CHIPS)':
 C_PATH='@s9s_mb_2u_lib.s9s_mb_2u(sch_1):page155_i99@pure_quanta.q_res(chips)',
 P_PATH='@s9s_mb_2u_lib.s9s_mb_2u(sch_1):page152_i99@pure_quanta.q_res(chips)',
 PATH='I99',
 DRAWING='@S9S_MB_2U_LIB.S9S_MB_2U(SCH_1):PAGE155',
 PHYS_PAGE='152',
 XY='(-2025,375)',
 ROT='0',
 VER='2',
 PACK_TYPE='0402LF',
 CDS_LIB='pure_quanta',
 CDS_PART_NAME='Q_RES_0402LF-0,5%,1/16W,EMPTY,A',
 WATTAGE='1/16W',
 TOLERANCE='5%',
 MATERIAL='EMPTY',
 ROOM='USB1_BOM2',
 VALUE='0',
 PRIM_FILE='./archive_libs/logical/q_res/chips/chips.prt';

PART_NAME
 R2789 'Q_RES_0402LF-0,5%,1/16W,EMPTY,A':
 ROOM='USB1_BOM2';

SECTION_NUMBER 1
 '@S9S_MB_2U_LIB.S9S_MB_2U(SCH_1):PAGE155_I98@PURE_QUANTA.Q_RES(CHIPS)':
 C_PATH='@s9s_mb_2u_lib.s9s_mb_2u(sch_1):page155_i98@pure_quanta.q_res(chips)',
 P_PATH='@s9s_mb_2u_lib.s9s_mb_2u(sch_1):page152_i98@pure_quanta.q_res(chips)',
 PATH='I98',
 DRAWING='@S9S_MB_2U_LIB.S9S_MB_2U(SCH_1):PAGE155',
 PHYS_PAGE='152',
 XY='(-1950,375)',
 ROT='0',
 VER='2',
 PACK_TYPE='0402LF',
 CDS_LIB='pure_quanta',
 CDS_PART_NAME='Q_RES_0402LF-0,5%,1/16W,EMPTY,A',
 WATTAGE='1/16W',
 TOLERANCE='5%',
 MATERIAL='EMPTY',
 ROOM='USB1_BOM2',
 VALUE='0',
 PRIM_FILE='./archive_libs/logical/q_res/chips/chips.prt';

PART_NAME
 R2790 'Q_RES_0402LF-0,5%,1/16W,EMPTY,A':
 ROOM='USB1_BOM2';

SECTION_NUMBER 1
 '@S9S_MB_2U_LIB.S9S_MB_2U(SCH_1):PAGE155_I96@PURE_QUANTA.Q_RES(CHIPS)':
 C_PATH='@s9s_mb_2u_lib.s9s_mb_2u(sch_1):page155_i96@pure_quanta.q_res(chips)',
 P_PATH='@s9s_mb_2u_lib.s9s_mb_2u(sch_1):page152_i96@pure_quanta.q_res(chips)',
 PATH='I96',
 DRAWING='@S9S_MB_2U_LIB.S9S_MB_2U(SCH_1):PAGE155',
 PHYS_PAGE='152',
 XY='(2725,3650)',
 ROT='0',
 VER='2',
 PACK_TYPE='0402LF',
 CDS_LIB='pure_quanta',
 CDS_PART_NAME='Q_RES_0402LF-0,5%,1/16W,EMPTY,A',
 WATTAGE='1/16W',
 TOLERANCE='5%',
 MATERIAL='EMPTY',
 ROOM='USB1_BOM2',
 VALUE='0',
 PRIM_FILE='./archive_libs/logical/q_res/chips/chips.prt';

PART_NAME
 R2791 'Q_RES_0402LF-0,5%,1/16W,EMPTY,A':
 ROOM='USB1_BOM2';

SECTION_NUMBER 1
 '@S9S_MB_2U_LIB.S9S_MB_2U(SCH_1):PAGE155_I97@PURE_QUANTA.Q_RES(CHIPS)':
 C_PATH='@s9s_mb_2u_lib.s9s_mb_2u(sch_1):page155_i97@pure_quanta.q_res(chips)',
 P_PATH='@s9s_mb_2u_lib.s9s_mb_2u(sch_1):page152_i97@pure_quanta.q_res(chips)',
 PATH='I97',
 DRAWING='@S9S_MB_2U_LIB.S9S_MB_2U(SCH_1):PAGE155',
 PHYS_PAGE='152',
 XY='(2825,3650)',
 ROT='0',
 VER='2',
 PACK_TYPE='0402LF',
 CDS_LIB='pure_quanta',
 CDS_PART_NAME='Q_RES_0402LF-0,5%,1/16W,EMPTY,A',
 WATTAGE='1/16W',
 TOLERANCE='5%',
 MATERIAL='EMPTY',
 ROOM='USB1_BOM2',
 VALUE='0',
 PRIM_FILE='./archive_libs/logical/q_res/chips/chips.prt';

PART_NAME
 R2792 'Q_RES_0402LF-0,5%,1/16W,CHIP,CA':;

SECTION_NUMBER 1
 '@S9S_MB_2U_LIB.S9S_MB_2U(SCH_1):PAGE312_I178@PURE_QUANTA.Q_RES(CHIPS)':
 C_PATH='@s9s_mb_2u_lib.s9s_mb_2u(sch_1):page312_i178@pure_quanta.q_res(chips)',
 P_PATH='@s9s_mb_2u_lib.s9s_mb_2u(sch_1):page215_i178@pure_quanta.q_res(chips)',
 PATH='I178',
 DRAWING='@S9S_MB_2U_LIB.S9S_MB_2U(SCH_1):PAGE312',
 PHYS_PAGE='215',
 XY='(-575,-1575)',
 ROT='0',
 VER='1',
 PACK_TYPE='0402LF',
 CDS_LIB='pure_quanta',
 CDS_PART_NAME='Q_RES_0402LF-0,5%,1/16W,CHIP,CA',
 WATTAGE='1/16W',
 TOLERANCE='5%',
 MATERIAL='CHIP',
 VALUE='0',
 PRIM_FILE='./archive_libs/logical/q_res/chips/chips.prt';

PART_NAME
 R2796 'Q_RES_0402LF-33.2,1%,1/16W,CHIA':;

SECTION_NUMBER 1
 '@S9S_MB_2U_LIB.S9S_MB_2U(SCH_1):PAGE233_I10@PURE_QUANTA.Q_RES(CHIPS)':
 C_PATH='@s9s_mb_2u_lib.s9s_mb_2u(sch_1):page233_i10@pure_quanta.q_res(chips)',
 P_PATH='@s9s_mb_2u_lib.s9s_mb_2u(sch_1):page245_i10@pure_quanta.q_res(chips)',
 PATH='I10',
 DRAWING='@S9S_MB_2U_LIB.S9S_MB_2U(SCH_1):PAGE233',
 PHYS_PAGE='245',
 XY='(-4100,-2025)',
 ROT='0',
 VER='1',
 PACK_TYPE='0402LF',
 LOCATION='R2796',
 CDS_LIB='pure_quanta',
 CDS_PART_NAME='Q_RES_0402LF-33.2,1%,1/16W,CHIA',
 WATTAGE='1/16W',
 TOLERANCE='1%',
 MATERIAL='CHIP',
 VALUE='33.2',
 PRIM_FILE='./archive_libs/logical/q_res/chips/chips.prt';

PART_NAME
 R2800 'Q_RES_0402LF-0,5%,1/16W,EMPTY,A':;

SECTION_NUMBER 1
 '@S9S_MB_2U_LIB.S9S_MB_2U(SCH_1):PAGE233_I15@PURE_QUANTA.Q_RES(CHIPS)':
 C_PATH='@s9s_mb_2u_lib.s9s_mb_2u(sch_1):page233_i15@pure_quanta.q_res(chips)',
 P_PATH='@s9s_mb_2u_lib.s9s_mb_2u(sch_1):page245_i15@pure_quanta.q_res(chips)',
 PATH='I15',
 DRAWING='@S9S_MB_2U_LIB.S9S_MB_2U(SCH_1):PAGE233',
 PHYS_PAGE='245',
 XY='(-2575,-2575)',
 ROT='0',
 VER='1',
 PACK_TYPE='0402LF',
 CDS_LIB='pure_quanta',
 CDS_PART_NAME='Q_RES_0402LF-0,5%,1/16W,EMPTY,A',
 WATTAGE='1/16W',
 TOLERANCE='5%',
 MATERIAL='EMPTY',
 VALUE='0',
 PRIM_FILE='./archive_libs/logical/q_res/chips/chips.prt';

PART_NAME
 R2801 'Q_RES_0402LF-0,5%,1/16W,EMPTY,A':;

SECTION_NUMBER 1
 '@S9S_MB_2U_LIB.S9S_MB_2U(SCH_1):PAGE233_I14@PURE_QUANTA.Q_RES(CHIPS)':
 C_PATH='@s9s_mb_2u_lib.s9s_mb_2u(sch_1):page233_i14@pure_quanta.q_res(chips)',
 P_PATH='@s9s_mb_2u_lib.s9s_mb_2u(sch_1):page245_i14@pure_quanta.q_res(chips)',
 PATH='I14',
 DRAWING='@S9S_MB_2U_LIB.S9S_MB_2U(SCH_1):PAGE233',
 PHYS_PAGE='245',
 XY='(-2575,-2650)',
 ROT='0',
 VER='1',
 PACK_TYPE='0402LF',
 CDS_LIB='pure_quanta',
 CDS_PART_NAME='Q_RES_0402LF-0,5%,1/16W,EMPTY,A',
 WATTAGE='1/16W',
 TOLERANCE='5%',
 MATERIAL='EMPTY',
 VALUE='0',
 PRIM_FILE='./archive_libs/logical/q_res/chips/chips.prt';

PART_NAME
 R2802 'Q_RES_0402LF-0,5%,1/16W,CHIP,CA':;

SECTION_NUMBER 1
 '@S9S_MB_2U_LIB.S9S_MB_2U(SCH_1):PAGE233_I39@PURE_QUANTA.Q_RES(CHIPS)':
 C_PATH='@s9s_mb_2u_lib.s9s_mb_2u(sch_1):page233_i39@pure_quanta.q_res(chips)',
 P_PATH='@s9s_mb_2u_lib.s9s_mb_2u(sch_1):page245_i39@pure_quanta.q_res(chips)',
 PATH='I39',
 DRAWING='@S9S_MB_2U_LIB.S9S_MB_2U(SCH_1):PAGE233',
 PHYS_PAGE='245',
 XY='(-1600,1950)',
 ROT='0',
 VER='1',
 PACK_TYPE='0402LF',
 CDS_LIB='pure_quanta',
 CDS_PART_NAME='Q_RES_0402LF-0,5%,1/16W,CHIP,CA',
 WATTAGE='1/16W',
 TOLERANCE='5%',
 MATERIAL='CHIP',
 VALUE='0',
 PRIM_FILE='./archive_libs/logical/q_res/chips/chips.prt';

PART_NAME
 R2803 'Q_RES_0402LF-0,5%,1/16W,CHIP,CA':;

SECTION_NUMBER 1
 '@S9S_MB_2U_LIB.S9S_MB_2U(SCH_1):PAGE233_I38@PURE_QUANTA.Q_RES(CHIPS)':
 C_PATH='@s9s_mb_2u_lib.s9s_mb_2u(sch_1):page233_i38@pure_quanta.q_res(chips)',
 P_PATH='@s9s_mb_2u_lib.s9s_mb_2u(sch_1):page245_i38@pure_quanta.q_res(chips)',
 PATH='I38',
 DRAWING='@S9S_MB_2U_LIB.S9S_MB_2U(SCH_1):PAGE233',
 PHYS_PAGE='245',
 XY='(-1600,1900)',
 ROT='0',
 VER='1',
 PACK_TYPE='0402LF',
 CDS_LIB='pure_quanta',
 CDS_PART_NAME='Q_RES_0402LF-0,5%,1/16W,CHIP,CA',
 WATTAGE='1/16W',
 TOLERANCE='5%',
 MATERIAL='CHIP',
 VALUE='0',
 PRIM_FILE='./archive_libs/logical/q_res/chips/chips.prt';

PART_NAME
 R2805 'Q_RES_0402LF-4.7K,5%,1/16W,EMPA':;

SECTION_NUMBER 1
 '@S9S_MB_2U_LIB.S9S_MB_2U(SCH_1):PAGE233_I22@PURE_QUANTA.Q_RES(CHIPS)':
 C_PATH='@s9s_mb_2u_lib.s9s_mb_2u(sch_1):page233_i22@pure_quanta.q_res(chips)',
 P_PATH='@s9s_mb_2u_lib.s9s_mb_2u(sch_1):page245_i22@pure_quanta.q_res(chips)',
 PATH='I22',
 DRAWING='@S9S_MB_2U_LIB.S9S_MB_2U(SCH_1):PAGE233',
 PHYS_PAGE='245',
 XY='(-1250,-1675)',
 ROT='0',
 VER='2',
 PACK_TYPE='0402LF',
 CDS_LIB='pure_quanta',
 CDS_PART_NAME='Q_RES_0402LF-4.7K,5%,1/16W,EMPA',
 WATTAGE='1/16W',
 TOLERANCE='5%',
 MATERIAL='EMPTY',
 VALUE='4.7K',
 PRIM_FILE='./archive_libs/logical/q_res/chips/chips.prt';

PART_NAME
 R2807 'Q_RES_0402LF-4.7K,5%,1/16W,EMPA':;

SECTION_NUMBER 1
 '@S9S_MB_2U_LIB.S9S_MB_2U(SCH_1):PAGE233_I24@PURE_QUANTA.Q_RES(CHIPS)':
 C_PATH='@s9s_mb_2u_lib.s9s_mb_2u(sch_1):page233_i24@pure_quanta.q_res(chips)',
 P_PATH='@s9s_mb_2u_lib.s9s_mb_2u(sch_1):page245_i24@pure_quanta.q_res(chips)',
 PATH='I24',
 DRAWING='@S9S_MB_2U_LIB.S9S_MB_2U(SCH_1):PAGE233',
 PHYS_PAGE='245',
 XY='(-1000,-1700)',
 ROT='0',
 VER='2',
 PACK_TYPE='0402LF',
 CDS_LIB='pure_quanta',
 CDS_PART_NAME='Q_RES_0402LF-4.7K,5%,1/16W,EMPA',
 WATTAGE='1/16W',
 TOLERANCE='5%',
 MATERIAL='EMPTY',
 VALUE='4.7K',
 PRIM_FILE='./archive_libs/logical/q_res/chips/chips.prt';

PART_NAME
 R2811 'Q_RES_0402LF-33.2,1%,1/16W,CHIA':;

SECTION_NUMBER 1
 '@S9S_MB_2U_LIB.S9S_MB_2U(SCH_1):PAGE233_I21@PURE_QUANTA.Q_RES(CHIPS)':
 C_PATH='@s9s_mb_2u_lib.s9s_mb_2u(sch_1):page233_i21@pure_quanta.q_res(chips)',
 P_PATH='@s9s_mb_2u_lib.s9s_mb_2u(sch_1):page245_i21@pure_quanta.q_res(chips)',
 PATH='I21',
 DRAWING='@S9S_MB_2U_LIB.S9S_MB_2U(SCH_1):PAGE233',
 PHYS_PAGE='245',
 XY='(-525,-2125)',
 ROT='0',
 VER='1',
 PACK_TYPE='0402LF',
 CDS_LIB='pure_quanta',
 CDS_PART_NAME='Q_RES_0402LF-33.2,1%,1/16W,CHIA',
 WATTAGE='1/16W',
 TOLERANCE='1%',
 MATERIAL='CHIP',
 VALUE='33.2',
 PRIM_FILE='./archive_libs/logical/q_res/chips/chips.prt';

PART_NAME
 R2812 'Q_RES_0402LF-33.2,1%,1/16W,CHIA':;

SECTION_NUMBER 1
 '@S9S_MB_2U_LIB.S9S_MB_2U(SCH_1):PAGE233_I20@PURE_QUANTA.Q_RES(CHIPS)':
 C_PATH='@s9s_mb_2u_lib.s9s_mb_2u(sch_1):page233_i20@pure_quanta.q_res(chips)',
 P_PATH='@s9s_mb_2u_lib.s9s_mb_2u(sch_1):page245_i20@pure_quanta.q_res(chips)',
 PATH='I20',
 DRAWING='@S9S_MB_2U_LIB.S9S_MB_2U(SCH_1):PAGE233',
 PHYS_PAGE='245',
 XY='(-525,-2225)',
 ROT='0',
 VER='1',
 PACK_TYPE='0402LF',
 CDS_LIB='pure_quanta',
 CDS_PART_NAME='Q_RES_0402LF-33.2,1%,1/16W,CHIA',
 WATTAGE='1/16W',
 TOLERANCE='1%',
 MATERIAL='CHIP',
 VALUE='33.2',
 PRIM_FILE='./archive_libs/logical/q_res/chips/chips.prt';

PART_NAME
 R2815 'Q_RES_0402LF-100K,1%,1/16W,EMPA':;

SECTION_NUMBER 1
 '@S9S_MB_2U_LIB.S9S_MB_2U(SCH_1):PAGE140_I68@PURE_QUANTA.Q_RES(CHIPS)':
 C_PATH='@s9s_mb_2u_lib.s9s_mb_2u(sch_1):page140_i68@pure_quanta.q_res(chips)',
 P_PATH='@s9s_mb_2u_lib.s9s_mb_2u(sch_1):page151_i68@pure_quanta.q_res(chips)',
 PATH='I68',
 DRAWING='@S9S_MB_2U_LIB.S9S_MB_2U(SCH_1):PAGE140',
 PHYS_PAGE='151',
 XY='(0,3275)',
 ROT='0',
 VER='2',
 PACK_TYPE='0402LF',
 CDS_LIB='pure_quanta',
 CDS_PART_NAME='Q_RES_0402LF-100K,1%,1/16W,EMPA',
 WATTAGE='1/16W',
 TOLERANCE='1%',
 MATERIAL='EMPTY',
 VALUE='100K',
 PRIM_FILE='./archive_libs/logical/q_res/chips/chips.prt';

PART_NAME
 R2820 'Q_RES_0402LF-4.7K,5%,1/16W,EMPA':;

SECTION_NUMBER 1
 '@S9S_MB_2U_LIB.S9S_MB_2U(SCH_1):PAGE140_I78@PURE_QUANTA.Q_RES(CHIPS)':
 C_PATH='@s9s_mb_2u_lib.s9s_mb_2u(sch_1):page140_i78@pure_quanta.q_res(chips)',
 P_PATH='@s9s_mb_2u_lib.s9s_mb_2u(sch_1):page151_i78@pure_quanta.q_res(chips)',
 PATH='I78',
 DRAWING='@S9S_MB_2U_LIB.S9S_MB_2U(SCH_1):PAGE140',
 PHYS_PAGE='151',
 XY='(2500,3225)',
 ROT='0',
 VER='2',
 PACK_TYPE='0402LF',
 CDS_LIB='pure_quanta',
 CDS_PART_NAME='Q_RES_0402LF-4.7K,5%,1/16W,EMPA',
 WATTAGE='1/16W',
 TOLERANCE='5%',
 MATERIAL='EMPTY',
 VALUE='4.7K',
 PRIM_FILE='./archive_libs/logical/q_res/chips/chips.prt';

PART_NAME
 R2828 'Q_RES_0402LF-100K,1%,1/16W,CHIA':;

SECTION_NUMBER 1
 '@S9S_MB_2U_LIB.S9S_MB_2U(SCH_1):PAGE145_I66@PURE_QUANTA.Q_RES(CHIPS)':
 C_PATH='@s9s_mb_2u_lib.s9s_mb_2u(sch_1):page145_i66@pure_quanta.q_res(chips)',
 P_PATH='@s9s_mb_2u_lib.s9s_mb_2u(sch_1):page148_i66@pure_quanta.q_res(chips)',
 PATH='I66',
 DRAWING='@S9S_MB_2U_LIB.S9S_MB_2U(SCH_1):PAGE145',
 PHYS_PAGE='148',
 XY='(-4675,6225)',
 ROT='0',
 VER='2',
 PACK_TYPE='0402LF',
 CDS_LIB='pure_quanta',
 CDS_PART_NAME='Q_RES_0402LF-100K,1%,1/16W,CHIA',
 WATTAGE='1/16W',
 TOLERANCE='1%',
 MATERIAL='CHIP',
 VALUE='100K',
 PRIM_FILE='./archive_libs/logical/q_res/chips/chips.prt';

PART_NAME
 R2829 'Q_RES_0402LF-100K,1%,1/16W,EMPA':;

SECTION_NUMBER 1
 '@S9S_MB_2U_LIB.S9S_MB_2U(SCH_1):PAGE145_I58@PURE_QUANTA.Q_RES(CHIPS)':
 C_PATH='@s9s_mb_2u_lib.s9s_mb_2u(sch_1):page145_i58@pure_quanta.q_res(chips)',
 P_PATH='@s9s_mb_2u_lib.s9s_mb_2u(sch_1):page148_i58@pure_quanta.q_res(chips)',
 PATH='I58',
 DRAWING='@S9S_MB_2U_LIB.S9S_MB_2U(SCH_1):PAGE145',
 PHYS_PAGE='148',
 XY='(-4650,5750)',
 ROT='0',
 VER='2',
 PACK_TYPE='0402LF',
 CDS_LIB='pure_quanta',
 CDS_PART_NAME='Q_RES_0402LF-100K,1%,1/16W,EMPA',
 WATTAGE='1/16W',
 TOLERANCE='1%',
 MATERIAL='EMPTY',
 VALUE='100K',
 PRIM_FILE='./archive_libs/logical/q_res/chips/chips.prt';

PART_NAME
 R2830 'Q_RES_0402LF-100K,1%,1/16W,CHIA':;

SECTION_NUMBER 1
 '@S9S_MB_2U_LIB.S9S_MB_2U(SCH_1):PAGE145_I68@PURE_QUANTA.Q_RES(CHIPS)':
 C_PATH='@s9s_mb_2u_lib.s9s_mb_2u(sch_1):page145_i68@pure_quanta.q_res(chips)',
 P_PATH='@s9s_mb_2u_lib.s9s_mb_2u(sch_1):page148_i68@pure_quanta.q_res(chips)',
 PATH='I68',
 DRAWING='@S9S_MB_2U_LIB.S9S_MB_2U(SCH_1):PAGE145',
 PHYS_PAGE='148',
 XY='(-4700,7625)',
 ROT='0',
 VER='2',
 PACK_TYPE='0402LF',
 CDS_LIB='pure_quanta',
 CDS_PART_NAME='Q_RES_0402LF-100K,1%,1/16W,CHIA',
 WATTAGE='1/16W',
 TOLERANCE='1%',
 MATERIAL='CHIP',
 VALUE='100K',
 PRIM_FILE='./archive_libs/logical/q_res/chips/chips.prt';

PART_NAME
 R2831 'Q_RES_0402LF-100K,1%,1/16W,EMPA':;

SECTION_NUMBER 1
 '@S9S_MB_2U_LIB.S9S_MB_2U(SCH_1):PAGE145_I56@PURE_QUANTA.Q_RES(CHIPS)':
 C_PATH='@s9s_mb_2u_lib.s9s_mb_2u(sch_1):page145_i56@pure_quanta.q_res(chips)',
 P_PATH='@s9s_mb_2u_lib.s9s_mb_2u(sch_1):page148_i56@pure_quanta.q_res(chips)',
 PATH='I56',
 DRAWING='@S9S_MB_2U_LIB.S9S_MB_2U(SCH_1):PAGE145',
 PHYS_PAGE='148',
 XY='(-4675,7150)',
 ROT='0',
 VER='2',
 PACK_TYPE='0402LF',
 CDS_LIB='pure_quanta',
 CDS_PART_NAME='Q_RES_0402LF-100K,1%,1/16W,EMPA',
 WATTAGE='1/16W',
 TOLERANCE='1%',
 MATERIAL='EMPTY',
 VALUE='100K',
 PRIM_FILE='./archive_libs/logical/q_res/chips/chips.prt';

PART_NAME
 R2832 'Q_RES_0402LF-100K,1%,1/16W,CHIA':;

SECTION_NUMBER 1
 '@S9S_MB_2U_LIB.S9S_MB_2U(SCH_1):PAGE145_I67@PURE_QUANTA.Q_RES(CHIPS)':
 C_PATH='@s9s_mb_2u_lib.s9s_mb_2u(sch_1):page145_i67@pure_quanta.q_res(chips)',
 P_PATH='@s9s_mb_2u_lib.s9s_mb_2u(sch_1):page148_i67@pure_quanta.q_res(chips)',
 PATH='I67',
 DRAWING='@S9S_MB_2U_LIB.S9S_MB_2U(SCH_1):PAGE145',
 PHYS_PAGE='148',
 XY='(-4625,4875)',
 ROT='0',
 VER='2',
 PACK_TYPE='0402LF',
 CDS_LIB='pure_quanta',
 CDS_PART_NAME='Q_RES_0402LF-100K,1%,1/16W,CHIA',
 WATTAGE='1/16W',
 TOLERANCE='1%',
 MATERIAL='CHIP',
 VALUE='100K',
 PRIM_FILE='./archive_libs/logical/q_res/chips/chips.prt';

PART_NAME
 R2833 'Q_RES_0402LF-100K,1%,1/16W,EMPA':;

SECTION_NUMBER 1
 '@S9S_MB_2U_LIB.S9S_MB_2U(SCH_1):PAGE145_I60@PURE_QUANTA.Q_RES(CHIPS)':
 C_PATH='@s9s_mb_2u_lib.s9s_mb_2u(sch_1):page145_i60@pure_quanta.q_res(chips)',
 P_PATH='@s9s_mb_2u_lib.s9s_mb_2u(sch_1):page148_i60@pure_quanta.q_res(chips)',
 PATH='I60',
 DRAWING='@S9S_MB_2U_LIB.S9S_MB_2U(SCH_1):PAGE145',
 PHYS_PAGE='148',
 XY='(-4600,4400)',
 ROT='0',
 VER='2',
 PACK_TYPE='0402LF',
 CDS_LIB='pure_quanta',
 CDS_PART_NAME='Q_RES_0402LF-100K,1%,1/16W,EMPA',
 WATTAGE='1/16W',
 TOLERANCE='1%',
 MATERIAL='EMPTY',
 VALUE='100K',
 PRIM_FILE='./archive_libs/logical/q_res/chips/chips.prt';

PART_NAME
 R2834 'Q_RES_0402LF-4.7K,5%,1/16W,CHIA':;

SECTION_NUMBER 1
 '@S9S_MB_2U_LIB.S9S_MB_2U(SCH_1):PAGE145_I18@PURE_QUANTA.Q_RES(CHIPS)':
 C_PATH='@s9s_mb_2u_lib.s9s_mb_2u(sch_1):page145_i18@pure_quanta.q_res(chips)',
 P_PATH='@s9s_mb_2u_lib.s9s_mb_2u(sch_1):page148_i18@pure_quanta.q_res(chips)',
 PATH='I18',
 DRAWING='@S9S_MB_2U_LIB.S9S_MB_2U(SCH_1):PAGE145',
 PHYS_PAGE='148',
 XY='(-3475,6450)',
 ROT='0',
 VER='2',
 PACK_TYPE='0402LF',
 CDS_LIB='pure_quanta',
 CDS_PART_NAME='Q_RES_0402LF-4.7K,5%,1/16W,CHIA',
 WATTAGE='1/16W',
 TOLERANCE='5%',
 MATERIAL='CHIP',
 VALUE='4.7K',
 PRIM_FILE='./archive_libs/logical/q_res/chips/chips.prt';

PART_NAME
 R2835 'Q_RES_0402LF-4.7K,5%,1/16W,CHIA':;

SECTION_NUMBER 1
 '@S9S_MB_2U_LIB.S9S_MB_2U(SCH_1):PAGE145_I14@PURE_QUANTA.Q_RES(CHIPS)':
 C_PATH='@s9s_mb_2u_lib.s9s_mb_2u(sch_1):page145_i14@pure_quanta.q_res(chips)',
 P_PATH='@s9s_mb_2u_lib.s9s_mb_2u(sch_1):page148_i14@pure_quanta.q_res(chips)',
 PATH='I14',
 DRAWING='@S9S_MB_2U_LIB.S9S_MB_2U(SCH_1):PAGE145',
 PHYS_PAGE='148',
 XY='(-3525,8000)',
 ROT='0',
 VER='2',
 PACK_TYPE='0402LF',
 CDS_LIB='pure_quanta',
 CDS_PART_NAME='Q_RES_0402LF-4.7K,5%,1/16W,CHIA',
 WATTAGE='1/16W',
 TOLERANCE='5%',
 MATERIAL='CHIP',
 VALUE='4.7K',
 PRIM_FILE='./archive_libs/logical/q_res/chips/chips.prt';

PART_NAME
 R2836 'Q_RES_0402LF-4.7K,5%,1/16W,CHIA':;

SECTION_NUMBER 1
 '@S9S_MB_2U_LIB.S9S_MB_2U(SCH_1):PAGE145_I19@PURE_QUANTA.Q_RES(CHIPS)':
 C_PATH='@s9s_mb_2u_lib.s9s_mb_2u(sch_1):page145_i19@pure_quanta.q_res(chips)',
 P_PATH='@s9s_mb_2u_lib.s9s_mb_2u(sch_1):page148_i19@pure_quanta.q_res(chips)',
 PATH='I19',
 DRAWING='@S9S_MB_2U_LIB.S9S_MB_2U(SCH_1):PAGE145',
 PHYS_PAGE='148',
 XY='(-3450,5100)',
 ROT='0',
 VER='2',
 PACK_TYPE='0402LF',
 CDS_LIB='pure_quanta',
 CDS_PART_NAME='Q_RES_0402LF-4.7K,5%,1/16W,CHIA',
 WATTAGE='1/16W',
 TOLERANCE='5%',
 MATERIAL='CHIP',
 VALUE='4.7K',
 PRIM_FILE='./archive_libs/logical/q_res/chips/chips.prt';

PART_NAME
 R2837 'Q_RES_0402LF-100K,1%,1/16W,EMPA':;

SECTION_NUMBER 1
 '@S9S_MB_2U_LIB.S9S_MB_2U(SCH_1):PAGE145_I80@PURE_QUANTA.Q_RES(CHIPS)':
 C_PATH='@s9s_mb_2u_lib.s9s_mb_2u(sch_1):page145_i80@pure_quanta.q_res(chips)',
 P_PATH='@s9s_mb_2u_lib.s9s_mb_2u(sch_1):page148_i80@pure_quanta.q_res(chips)',
 PATH='I80',
 DRAWING='@S9S_MB_2U_LIB.S9S_MB_2U(SCH_1):PAGE145',
 PHYS_PAGE='148',
 XY='(-150,7700)',
 ROT='0',
 VER='2',
 PACK_TYPE='0402LF',
 CDS_LIB='pure_quanta',
 CDS_PART_NAME='Q_RES_0402LF-100K,1%,1/16W,EMPA',
 WATTAGE='1/16W',
 TOLERANCE='1%',
 MATERIAL='EMPTY',
 VALUE='100K',
 PRIM_FILE='./archive_libs/logical/q_res/chips/chips.prt';

PART_NAME
 R2838 'Q_RES_0402LF-100K,1%,1/16W,CHIA':;

SECTION_NUMBER 1
 '@S9S_MB_2U_LIB.S9S_MB_2U(SCH_1):PAGE145_I62@PURE_QUANTA.Q_RES(CHIPS)':
 C_PATH='@s9s_mb_2u_lib.s9s_mb_2u(sch_1):page145_i62@pure_quanta.q_res(chips)',
 P_PATH='@s9s_mb_2u_lib.s9s_mb_2u(sch_1):page148_i62@pure_quanta.q_res(chips)',
 PATH='I62',
 DRAWING='@S9S_MB_2U_LIB.S9S_MB_2U(SCH_1):PAGE145',
 PHYS_PAGE='148',
 XY='(-125,7275)',
 ROT='0',
 VER='2',
 PACK_TYPE='0402LF',
 CDS_LIB='pure_quanta',
 CDS_PART_NAME='Q_RES_0402LF-100K,1%,1/16W,CHIA',
 WATTAGE='1/16W',
 TOLERANCE='1%',
 MATERIAL='CHIP',
 VALUE='100K',
 PRIM_FILE='./archive_libs/logical/q_res/chips/chips.prt';

PART_NAME
 R2841 'Q_RES_0402LF-4.7K,5%,1/16W,CHIA':;

SECTION_NUMBER 1
 '@S9S_MB_2U_LIB.S9S_MB_2U(SCH_1):PAGE145_I24@PURE_QUANTA.Q_RES(CHIPS)':
 C_PATH='@s9s_mb_2u_lib.s9s_mb_2u(sch_1):page145_i24@pure_quanta.q_res(chips)',
 P_PATH='@s9s_mb_2u_lib.s9s_mb_2u(sch_1):page148_i24@pure_quanta.q_res(chips)',
 PATH='I24',
 DRAWING='@S9S_MB_2U_LIB.S9S_MB_2U(SCH_1):PAGE145',
 PHYS_PAGE='148',
 XY='(1100,7925)',
 ROT='0',
 VER='2',
 PACK_TYPE='0402LF',
 CDS_LIB='pure_quanta',
 CDS_PART_NAME='Q_RES_0402LF-4.7K,5%,1/16W,CHIA',
 WATTAGE='1/16W',
 TOLERANCE='5%',
 MATERIAL='CHIP',
 VALUE='4.7K',
 PRIM_FILE='./archive_libs/logical/q_res/chips/chips.prt';

PART_NAME
 R2842 'Q_RES_0402LF-4.7K,5%,1/16W,CHIA':;

SECTION_NUMBER 1
 '@S9S_MB_2U_LIB.S9S_MB_2U(SCH_1):PAGE145_I30@PURE_QUANTA.Q_RES(CHIPS)':
 C_PATH='@s9s_mb_2u_lib.s9s_mb_2u(sch_1):page145_i30@pure_quanta.q_res(chips)',
 P_PATH='@s9s_mb_2u_lib.s9s_mb_2u(sch_1):page148_i30@pure_quanta.q_res(chips)',
 PATH='I30',
 DRAWING='@S9S_MB_2U_LIB.S9S_MB_2U(SCH_1):PAGE145',
 PHYS_PAGE='148',
 XY='(1100,6625)',
 ROT='0',
 VER='2',
 PACK_TYPE='0402LF',
 CDS_LIB='pure_quanta',
 CDS_PART_NAME='Q_RES_0402LF-4.7K,5%,1/16W,CHIA',
 WATTAGE='1/16W',
 TOLERANCE='5%',
 MATERIAL='CHIP',
 VALUE='4.7K',
 PRIM_FILE='./archive_libs/logical/q_res/chips/chips.prt';

PART_NAME
 R2843 'Q_RES_0402LF-4.7K,1%,1/16W,CHIA':;

SECTION_NUMBER 1
 '@S9S_MB_2U_LIB.S9S_MB_2U(SCH_1):PAGE239_I162@PURE_QUANTA.Q_RES(CHIPS)':
 C_PATH='@s9s_mb_2u_lib.s9s_mb_2u(sch_1):page239_i162@pure_quanta.q_res(chips)',
 P_PATH='@s9s_mb_2u_lib.s9s_mb_2u(sch_1):page250_i162@pure_quanta.q_res(chips)',
 PATH='I162',
 DRAWING='@S9S_MB_2U_LIB.S9S_MB_2U(SCH_1):PAGE239',
 PHYS_PAGE='250',
 XY='(-1000,3625)',
 ROT='0',
 VER='2',
 PACK_TYPE='0402LF',
 CDS_LIB='pure_quanta',
 CDS_PART_NAME='Q_RES_0402LF-4.7K,1%,1/16W,CHIA',
 WATTAGE='1/16W',
 TOLERANCE='1%',
 MATERIAL='CHIP',
 VALUE='4.7K',
 PRIM_FILE='./archive_libs/logical/q_res/chips/chips.prt';

PART_NAME
 R2844 'Q_RES_0402LF-33.2,1%,1/16W,CHIA':;

SECTION_NUMBER 1
 '@S9S_MB_2U_LIB.S9S_MB_2U(SCH_1):PAGE314_I112@PURE_QUANTA.Q_RES(CHIPS)':
 C_PATH='@s9s_mb_2u_lib.s9s_mb_2u(sch_1):page314_i112@pure_quanta.q_res(chips)',
 P_PATH='@s9s_mb_2u_lib.s9s_mb_2u(sch_1):page213_i112@pure_quanta.q_res(chips)',
 PATH='I112',
 DRAWING='@S9S_MB_2U_LIB.S9S_MB_2U(SCH_1):PAGE314',
 PHYS_PAGE='213',
 XY='(2725,-525)',
 ROT='0',
 VER='1',
 PACK_TYPE='0402LF',
 LOCATION='R2844',
 CDS_LIB='pure_quanta',
 CDS_PART_NAME='Q_RES_0402LF-33.2,1%,1/16W,CHIA',
 WATTAGE='1/16W',
 TOLERANCE='1%',
 MATERIAL='CHIP',
 VALUE='33.2',
 PRIM_FILE='./archive_libs/logical/q_res/chips/chips.prt';

PART_NAME
 R2845 'Q_RES_0402LF-33.2,1%,1/16W,CHIA':;

SECTION_NUMBER 1
 '@S9S_MB_2U_LIB.S9S_MB_2U(SCH_1):PAGE314_I136@PURE_QUANTA.Q_RES(CHIPS)':
 C_PATH='@s9s_mb_2u_lib.s9s_mb_2u(sch_1):page314_i136@pure_quanta.q_res(chips)',
 P_PATH='@s9s_mb_2u_lib.s9s_mb_2u(sch_1):page213_i136@pure_quanta.q_res(chips)',
 PATH='I136',
 DRAWING='@S9S_MB_2U_LIB.S9S_MB_2U(SCH_1):PAGE314',
 PHYS_PAGE='213',
 XY='(2725,300)',
 ROT='0',
 VER='1',
 PACK_TYPE='0402LF',
 LOCATION='R2845',
 CDS_LIB='pure_quanta',
 CDS_PART_NAME='Q_RES_0402LF-33.2,1%,1/16W,CHIA',
 WATTAGE='1/16W',
 TOLERANCE='1%',
 MATERIAL='CHIP',
 VALUE='33.2',
 PRIM_FILE='./archive_libs/logical/q_res/chips/chips.prt';

PART_NAME
 R2846 'Q_RES_0402LF-33.2,1%,1/16W,CHIA':;

SECTION_NUMBER 1
 '@S9S_MB_2U_LIB.S9S_MB_2U(SCH_1):PAGE314_I134@PURE_QUANTA.Q_RES(CHIPS)':
 C_PATH='@s9s_mb_2u_lib.s9s_mb_2u(sch_1):page314_i134@pure_quanta.q_res(chips)',
 P_PATH='@s9s_mb_2u_lib.s9s_mb_2u(sch_1):page213_i134@pure_quanta.q_res(chips)',
 PATH='I134',
 DRAWING='@S9S_MB_2U_LIB.S9S_MB_2U(SCH_1):PAGE314',
 PHYS_PAGE='213',
 XY='(2725,125)',
 ROT='0',
 VER='1',
 PACK_TYPE='0402LF',
 LOCATION='R2846',
 CDS_LIB='pure_quanta',
 CDS_PART_NAME='Q_RES_0402LF-33.2,1%,1/16W,CHIA',
 WATTAGE='1/16W',
 TOLERANCE='1%',
 MATERIAL='CHIP',
 VALUE='33.2',
 PRIM_FILE='./archive_libs/logical/q_res/chips/chips.prt';

PART_NAME
 R2847 'Q_RES_0402LF-33.2,1%,1/16W,CHIA':;

SECTION_NUMBER 1
 '@S9S_MB_2U_LIB.S9S_MB_2U(SCH_1):PAGE314_I107@PURE_QUANTA.Q_RES(CHIPS)':
 C_PATH='@s9s_mb_2u_lib.s9s_mb_2u(sch_1):page314_i107@pure_quanta.q_res(chips)',
 P_PATH='@s9s_mb_2u_lib.s9s_mb_2u(sch_1):page213_i107@pure_quanta.q_res(chips)',
 PATH='I107',
 DRAWING='@S9S_MB_2U_LIB.S9S_MB_2U(SCH_1):PAGE314',
 PHYS_PAGE='213',
 XY='(2725,-1225)',
 ROT='0',
 VER='1',
 PACK_TYPE='0402LF',
 LOCATION='R2847',
 CDS_LIB='pure_quanta',
 CDS_PART_NAME='Q_RES_0402LF-33.2,1%,1/16W,CHIA',
 WATTAGE='1/16W',
 TOLERANCE='1%',
 MATERIAL='CHIP',
 VALUE='33.2',
 PRIM_FILE='./archive_libs/logical/q_res/chips/chips.prt';

PART_NAME
 R2848 'Q_RES_0402LF-0,5%,1/16W,CHIP,CA':;

SECTION_NUMBER 1
 '@S9S_MB_2U_LIB.S9S_MB_2U(SCH_1):PAGE214_I34@PURE_QUANTA.Q_RES(CHIPS)':
 C_PATH='@s9s_mb_2u_lib.s9s_mb_2u(sch_1):page214_i34@pure_quanta.q_res(chips)',
 P_PATH='@s9s_mb_2u_lib.s9s_mb_2u(sch_1):page227_i34@pure_quanta.q_res(chips)',
 PATH='I34',
 DRAWING='@S9S_MB_2U_LIB.S9S_MB_2U(SCH_1):PAGE214',
 PHYS_PAGE='227',
 XY='(8675,3750)',
 ROT='0',
 VER='1',
 PACK_TYPE='0402LF',
 CDS_LIB='pure_quanta',
 CDS_PART_NAME='Q_RES_0402LF-0,5%,1/16W,CHIP,CA',
 WATTAGE='1/16W',
 TOLERANCE='5%',
 MATERIAL='CHIP',
 VALUE='0',
 PRIM_FILE='./archive_libs/logical/q_res/chips/chips.prt';

PART_NAME
 R2893 'Q_RES_0402LF-0,5%,1/16W,EMPTY,A':;

SECTION_NUMBER 1
 '@S9S_MB_2U_LIB.S9S_MB_2U(SCH_1):PAGE222_I38@PURE_QUANTA.Q_RES(CHIPS)':
 C_PATH='@s9s_mb_2u_lib.s9s_mb_2u(sch_1):page222_i38@pure_quanta.q_res(chips)',
 P_PATH='@s9s_mb_2u_lib.s9s_mb_2u(sch_1):page234_i38@pure_quanta.q_res(chips)',
 PATH='I38',
 DRAWING='@S9S_MB_2U_LIB.S9S_MB_2U(SCH_1):PAGE222',
 PHYS_PAGE='234',
 XY='(-2275,6975)',
 ROT='0',
 VER='1',
 PACK_TYPE='0402LF',
 CDS_LIB='pure_quanta',
 CDS_PART_NAME='Q_RES_0402LF-0,5%,1/16W,EMPTY,A',
 WATTAGE='1/16W',
 TOLERANCE='5%',
 MATERIAL='EMPTY',
 VALUE='0',
 PRIM_FILE='./archive_libs/logical/q_res/chips/chips.prt';

PART_NAME
 R2894 'Q_RES_0402LF-0,5%,1/16W,EMPTY,A':;

SECTION_NUMBER 1
 '@S9S_MB_2U_LIB.S9S_MB_2U(SCH_1):PAGE222_I33@PURE_QUANTA.Q_RES(CHIPS)':
 C_PATH='@s9s_mb_2u_lib.s9s_mb_2u(sch_1):page222_i33@pure_quanta.q_res(chips)',
 P_PATH='@s9s_mb_2u_lib.s9s_mb_2u(sch_1):page234_i33@pure_quanta.q_res(chips)',
 PATH='I33',
 DRAWING='@S9S_MB_2U_LIB.S9S_MB_2U(SCH_1):PAGE222',
 PHYS_PAGE='234',
 XY='(-2275,6900)',
 ROT='0',
 VER='1',
 PACK_TYPE='0402LF',
 CDS_LIB='pure_quanta',
 CDS_PART_NAME='Q_RES_0402LF-0,5%,1/16W,EMPTY,A',
 WATTAGE='1/16W',
 TOLERANCE='5%',
 MATERIAL='EMPTY',
 VALUE='0',
 PRIM_FILE='./archive_libs/logical/q_res/chips/chips.prt';

PART_NAME
 R2897 'Q_RES_0402LF-33.2,1%,1/16W,CHIA':;

SECTION_NUMBER 1
 '@S9S_MB_2U_LIB.S9S_MB_2U(SCH_1):PAGE222_I78@PURE_QUANTA.Q_RES(CHIPS)':
 C_PATH='@s9s_mb_2u_lib.s9s_mb_2u(sch_1):page222_i78@pure_quanta.q_res(chips)',
 P_PATH='@s9s_mb_2u_lib.s9s_mb_2u(sch_1):page234_i78@pure_quanta.q_res(chips)',
 PATH='I78',
 DRAWING='@S9S_MB_2U_LIB.S9S_MB_2U(SCH_1):PAGE222',
 PHYS_PAGE='234',
 XY='(-225,7425)',
 ROT='0',
 VER='1',
 PACK_TYPE='0402LF',
 CDS_LIB='pure_quanta',
 CDS_PART_NAME='Q_RES_0402LF-33.2,1%,1/16W,CHIA',
 WATTAGE='1/16W',
 TOLERANCE='1%',
 MATERIAL='CHIP',
 VALUE='33.2',
 PRIM_FILE='./archive_libs/logical/q_res/chips/chips.prt';

PART_NAME
 R2898 'Q_RES_0402LF-33.2,1%,1/16W,CHIA':;

SECTION_NUMBER 1
 '@S9S_MB_2U_LIB.S9S_MB_2U(SCH_1):PAGE222_I79@PURE_QUANTA.Q_RES(CHIPS)':
 C_PATH='@s9s_mb_2u_lib.s9s_mb_2u(sch_1):page222_i79@pure_quanta.q_res(chips)',
 P_PATH='@s9s_mb_2u_lib.s9s_mb_2u(sch_1):page234_i79@pure_quanta.q_res(chips)',
 PATH='I79',
 DRAWING='@S9S_MB_2U_LIB.S9S_MB_2U(SCH_1):PAGE222',
 PHYS_PAGE='234',
 XY='(-225,7325)',
 ROT='0',
 VER='1',
 PACK_TYPE='0402LF',
 CDS_LIB='pure_quanta',
 CDS_PART_NAME='Q_RES_0402LF-33.2,1%,1/16W,CHIA',
 WATTAGE='1/16W',
 TOLERANCE='1%',
 MATERIAL='CHIP',
 VALUE='33.2',
 PRIM_FILE='./archive_libs/logical/q_res/chips/chips.prt';

PART_NAME
 R2899 'Q_RES_0402LF-0,5%,1/16W,CHIP,CA':;

SECTION_NUMBER 1
 '@S9S_MB_2U_LIB.S9S_MB_2U(SCH_1):PAGE222_I53@PURE_QUANTA.Q_RES(CHIPS)':
 C_PATH='@s9s_mb_2u_lib.s9s_mb_2u(sch_1):page222_i53@pure_quanta.q_res(chips)',
 P_PATH='@s9s_mb_2u_lib.s9s_mb_2u(sch_1):page234_i53@pure_quanta.q_res(chips)',
 PATH='I53',
 DRAWING='@S9S_MB_2U_LIB.S9S_MB_2U(SCH_1):PAGE222',
 PHYS_PAGE='234',
 XY='(-4100,7525)',
 ROT='0',
 VER='1',
 PACK_TYPE='0402LF',
 CDS_LIB='pure_quanta',
 CDS_PART_NAME='Q_RES_0402LF-0,5%,1/16W,CHIP,CA',
 WATTAGE='1/16W',
 TOLERANCE='5%',
 MATERIAL='CHIP',
 VALUE='0',
 PRIM_FILE='./archive_libs/logical/q_res/chips/chips.prt';

PART_NAME
 R2900 'Q_RES_0402LF-2K,1%,1/16W,EMPTYA':
 ROOM='ADC1_BOM1';

SECTION_NUMBER 1
 '@S9S_MB_2U_LIB.S9S_MB_2U(SCH_1):PAGE239_I72@PURE_QUANTA.Q_RES(CHIPS)':
 C_PATH='@s9s_mb_2u_lib.s9s_mb_2u(sch_1):page239_i72@pure_quanta.q_res(chips)',
 P_PATH='@s9s_mb_2u_lib.s9s_mb_2u(sch_1):page250_i72@pure_quanta.q_res(chips)',
 PATH='I72',
 DRAWING='@S9S_MB_2U_LIB.S9S_MB_2U(SCH_1):PAGE239',
 PHYS_PAGE='250',
 XY='(4425,4725)',
 ROT='0',
 VER='1',
 PACK_TYPE='0402LF',
 CDS_LIB='pure_quanta',
 CDS_PART_NAME='Q_RES_0402LF-2K,1%,1/16W,EMPTYA',
 WATTAGE='1/16W',
 TOLERANCE='1%',
 MATERIAL='EMPTY',
 ROOM='ADC1_BOM1',
 VALUE='2K',
 PRIM_FILE='./archive_libs/logical/q_res/chips/chips.prt';

PART_NAME
 R2905 'Q_RES_0402LF-0,5%,1/16W,CHIP,CA':;

SECTION_NUMBER 1
 '@S9S_MB_2U_LIB.S9S_MB_2U(SCH_1):PAGE233_I34@PURE_QUANTA.Q_RES(CHIPS)':
 C_PATH='@s9s_mb_2u_lib.s9s_mb_2u(sch_1):page233_i34@pure_quanta.q_res(chips)',
 P_PATH='@s9s_mb_2u_lib.s9s_mb_2u(sch_1):page245_i34@pure_quanta.q_res(chips)',
 PATH='I34',
 DRAWING='@S9S_MB_2U_LIB.S9S_MB_2U(SCH_1):PAGE233',
 PHYS_PAGE='245',
 XY='(-5200,1900)',
 ROT='0',
 VER='1',
 PACK_TYPE='0402LF',
 CDS_LIB='pure_quanta',
 CDS_PART_NAME='Q_RES_0402LF-0,5%,1/16W,CHIP,CA',
 WATTAGE='1/16W',
 TOLERANCE='5%',
 MATERIAL='CHIP',
 VALUE='0',
 PRIM_FILE='./archive_libs/logical/q_res/chips/chips.prt';

PART_NAME
 R2906 'Q_RES_0402LF-0,5%,1/16W,CHIP,CA':;

SECTION_NUMBER 1
 '@S9S_MB_2U_LIB.S9S_MB_2U(SCH_1):PAGE233_I37@PURE_QUANTA.Q_RES(CHIPS)':
 C_PATH='@s9s_mb_2u_lib.s9s_mb_2u(sch_1):page233_i37@pure_quanta.q_res(chips)',
 P_PATH='@s9s_mb_2u_lib.s9s_mb_2u(sch_1):page245_i37@pure_quanta.q_res(chips)',
 PATH='I37',
 DRAWING='@S9S_MB_2U_LIB.S9S_MB_2U(SCH_1):PAGE233',
 PHYS_PAGE='245',
 XY='(-1600,1850)',
 ROT='0',
 VER='1',
 PACK_TYPE='0402LF',
 CDS_LIB='pure_quanta',
 CDS_PART_NAME='Q_RES_0402LF-0,5%,1/16W,CHIP,CA',
 WATTAGE='1/16W',
 TOLERANCE='5%',
 MATERIAL='CHIP',
 VALUE='0',
 PRIM_FILE='./archive_libs/logical/q_res/chips/chips.prt';

PART_NAME
 R2907 'Q_RES_0402LF-5.11K,1%,1/16W,CHA':;

SECTION_NUMBER 1
 '@S9S_MB_2U_LIB.S9S_MB_2U(SCH_1):PAGE239_I141@PURE_QUANTA.Q_RES(CHIPS)':
 C_PATH='@s9s_mb_2u_lib.s9s_mb_2u(sch_1):page239_i141@pure_quanta.q_res(chips)',
 P_PATH='@s9s_mb_2u_lib.s9s_mb_2u(sch_1):page250_i141@pure_quanta.q_res(chips)',
 PATH='I141',
 DRAWING='@S9S_MB_2U_LIB.S9S_MB_2U(SCH_1):PAGE239',
 PHYS_PAGE='250',
 XY='(-1000,5425)',
 ROT='0',
 VER='2',
 PACK_TYPE='0402LF',
 CDS_LIB='pure_quanta',
 CDS_PART_NAME='Q_RES_0402LF-5.11K,1%,1/16W,CHA',
 WATTAGE='1/16W',
 TOLERANCE='1%',
 MATERIAL='CHIP',
 VALUE='5.11K',
 PRIM_FILE='./archive_libs/logical/q_res/chips/chips.prt';

PART_NAME
 R2908 'Q_RES_0402LF-5.11K,1%,1/16W,CHA':;

SECTION_NUMBER 1
 '@S9S_MB_2U_LIB.S9S_MB_2U(SCH_1):PAGE239_I161@PURE_QUANTA.Q_RES(CHIPS)':
 C_PATH='@s9s_mb_2u_lib.s9s_mb_2u(sch_1):page239_i161@pure_quanta.q_res(chips)',
 P_PATH='@s9s_mb_2u_lib.s9s_mb_2u(sch_1):page250_i161@pure_quanta.q_res(chips)',
 PATH='I161',
 DRAWING='@S9S_MB_2U_LIB.S9S_MB_2U(SCH_1):PAGE239',
 PHYS_PAGE='250',
 XY='(-1000,4100)',
 ROT='0',
 VER='2',
 PACK_TYPE='0402LF',
 CDS_LIB='pure_quanta',
 CDS_PART_NAME='Q_RES_0402LF-5.11K,1%,1/16W,CHA',
 WATTAGE='1/16W',
 TOLERANCE='1%',
 MATERIAL='CHIP',
 VALUE='5.11K',
 PRIM_FILE='./archive_libs/logical/q_res/chips/chips.prt';

PART_NAME
 R2909 'Q_RES_0402LF-4.7K,5%,1/16W,CHIA':;

SECTION_NUMBER 1
 '@S9S_MB_2U_LIB.S9S_MB_2U(SCH_1):PAGE140_I198@PURE_QUANTA.Q_RES(CHIPS)':
 C_PATH='@s9s_mb_2u_lib.s9s_mb_2u(sch_1):page140_i198@pure_quanta.q_res(chips)',
 P_PATH='@s9s_mb_2u_lib.s9s_mb_2u(sch_1):page151_i198@pure_quanta.q_res(chips)',
 PATH='I198',
 DRAWING='@S9S_MB_2U_LIB.S9S_MB_2U(SCH_1):PAGE140',
 PHYS_PAGE='151',
 XY='(0,2150)',
 ROT='0',
 VER='2',
 PACK_TYPE='0402LF',
 LOCATION='R2909',
 CDS_LIB='pure_quanta',
 CDS_PART_NAME='Q_RES_0402LF-4.7K,5%,1/16W,CHIA',
 WATTAGE='1/16W',
 TOLERANCE='5%',
 MATERIAL='CHIP',
 VALUE='4.7K',
 PRIM_FILE='./archive_libs/logical/q_res/chips/chips.prt';

PART_NAME
 R2910 'Q_RES_0402LF-100K,1%,1/16W,EMPA':;

SECTION_NUMBER 1
 '@S9S_MB_2U_LIB.S9S_MB_2U(SCH_1):PAGE160_I187@PURE_QUANTA.Q_RES(CHIPS)':
 C_PATH='@s9s_mb_2u_lib.s9s_mb_2u(sch_1):page160_i187@pure_quanta.q_res(chips)',
 P_PATH='@s9s_mb_2u_lib.s9s_mb_2u(sch_1):page149_i187@pure_quanta.q_res(chips)',
 PATH='I187',
 DRAWING='@S9S_MB_2U_LIB.S9S_MB_2U(SCH_1):PAGE160',
 PHYS_PAGE='149',
 XY='(-7800,-125)',
 ROT='0',
 VER='2',
 PACK_TYPE='0402LF',
 CDS_LIB='pure_quanta',
 CDS_PART_NAME='Q_RES_0402LF-100K,1%,1/16W,EMPA',
 WATTAGE='1/16W',
 TOLERANCE='1%',
 MATERIAL='EMPTY',
 VALUE='100K',
 PRIM_FILE='./archive_libs/logical/q_res/chips/chips.prt';

PART_NAME
 R2911 'Q_RES_0402LF-4.7K,5%,1/16W,EMPA':;

SECTION_NUMBER 1
 '@S9S_MB_2U_LIB.S9S_MB_2U(SCH_1):PAGE140_I153@PURE_QUANTA.Q_RES(CHIPS)':
 C_PATH='@s9s_mb_2u_lib.s9s_mb_2u(sch_1):page140_i153@pure_quanta.q_res(chips)',
 P_PATH='@s9s_mb_2u_lib.s9s_mb_2u(sch_1):page151_i153@pure_quanta.q_res(chips)',
 PATH='I153',
 DRAWING='@S9S_MB_2U_LIB.S9S_MB_2U(SCH_1):PAGE140',
 PHYS_PAGE='151',
 XY='(2600,2050)',
 ROT='0',
 VER='2',
 PACK_TYPE='0402LF',
 CDS_LIB='pure_quanta',
 CDS_PART_NAME='Q_RES_0402LF-4.7K,5%,1/16W,EMPA',
 WATTAGE='1/16W',
 TOLERANCE='5%',
 MATERIAL='EMPTY',
 VALUE='4.7K',
 PRIM_FILE='./archive_libs/logical/q_res/chips/chips.prt';

PART_NAME
 R2912 'Q_RES_0402LF-4.7K,5%,1/16W,EMPA':;

SECTION_NUMBER 1
 '@S9S_MB_2U_LIB.S9S_MB_2U(SCH_1):PAGE140_I147@PURE_QUANTA.Q_RES(CHIPS)':
 C_PATH='@s9s_mb_2u_lib.s9s_mb_2u(sch_1):page140_i147@pure_quanta.q_res(chips)',
 P_PATH='@s9s_mb_2u_lib.s9s_mb_2u(sch_1):page151_i147@pure_quanta.q_res(chips)',
 PATH='I147',
 DRAWING='@S9S_MB_2U_LIB.S9S_MB_2U(SCH_1):PAGE140',
 PHYS_PAGE='151',
 XY='(2575,850)',
 ROT='0',
 VER='2',
 PACK_TYPE='0402LF',
 CDS_LIB='pure_quanta',
 CDS_PART_NAME='Q_RES_0402LF-4.7K,5%,1/16W,EMPA',
 WATTAGE='1/16W',
 TOLERANCE='5%',
 MATERIAL='EMPTY',
 VALUE='4.7K',
 PRIM_FILE='./archive_libs/logical/q_res/chips/chips.prt';

PART_NAME
 R2914 'Q_RES_0402LF-4.7K,5%,1/16W,EMPA':;

SECTION_NUMBER 1
 '@S9S_MB_2U_LIB.S9S_MB_2U(SCH_1):PAGE160_I192@PURE_QUANTA.Q_RES(CHIPS)':
 C_PATH='@s9s_mb_2u_lib.s9s_mb_2u(sch_1):page160_i192@pure_quanta.q_res(chips)',
 P_PATH='@s9s_mb_2u_lib.s9s_mb_2u(sch_1):page149_i192@pure_quanta.q_res(chips)',
 PATH='I192',
 DRAWING='@S9S_MB_2U_LIB.S9S_MB_2U(SCH_1):PAGE160',
 PHYS_PAGE='149',
 XY='(-4150,-300)',
 ROT='0',
 VER='2',
 PACK_TYPE='0402LF',
 CDS_LIB='pure_quanta',
 CDS_PART_NAME='Q_RES_0402LF-4.7K,5%,1/16W,EMPA',
 WATTAGE='1/16W',
 TOLERANCE='5%',
 MATERIAL='EMPTY',
 VALUE='4.7K',
 PRIM_FILE='./archive_libs/logical/q_res/chips/chips.prt';

PART_NAME
 R2915 'Q_RES_0402LF-4.7K,5%,1/16W,CHIA':;

SECTION_NUMBER 1
 '@S9S_MB_2U_LIB.S9S_MB_2U(SCH_1):PAGE140_I92@PURE_QUANTA.Q_RES(CHIPS)':
 C_PATH='@s9s_mb_2u_lib.s9s_mb_2u(sch_1):page140_i92@pure_quanta.q_res(chips)',
 P_PATH='@s9s_mb_2u_lib.s9s_mb_2u(sch_1):page151_i92@pure_quanta.q_res(chips)',
 PATH='I92',
 DRAWING='@S9S_MB_2U_LIB.S9S_MB_2U(SCH_1):PAGE140',
 PHYS_PAGE='151',
 XY='(25,2800)',
 ROT='0',
 VER='2',
 PACK_TYPE='0402LF',
 CDS_LIB='pure_quanta',
 CDS_PART_NAME='Q_RES_0402LF-4.7K,5%,1/16W,CHIA',
 WATTAGE='1/16W',
 TOLERANCE='5%',
 MATERIAL='CHIP',
 VALUE='4.7K',
 PRIM_FILE='./archive_libs/logical/q_res/chips/chips.prt';

PART_NAME
 R2916 'Q_RES_0402LF-4.7K,5%,1/16W,EMPA':;

SECTION_NUMBER 1
 '@S9S_MB_2U_LIB.S9S_MB_2U(SCH_1):PAGE140_I93@PURE_QUANTA.Q_RES(CHIPS)':
 C_PATH='@s9s_mb_2u_lib.s9s_mb_2u(sch_1):page140_i93@pure_quanta.q_res(chips)',
 P_PATH='@s9s_mb_2u_lib.s9s_mb_2u(sch_1):page151_i93@pure_quanta.q_res(chips)',
 PATH='I93',
 DRAWING='@S9S_MB_2U_LIB.S9S_MB_2U(SCH_1):PAGE140',
 PHYS_PAGE='151',
 XY='(25,1675)',
 ROT='0',
 VER='2',
 PACK_TYPE='0402LF',
 CDS_LIB='pure_quanta',
 CDS_PART_NAME='Q_RES_0402LF-4.7K,5%,1/16W,EMPA',
 WATTAGE='1/16W',
 TOLERANCE='5%',
 MATERIAL='EMPTY',
 VALUE='4.7K',
 PRIM_FILE='./archive_libs/logical/q_res/chips/chips.prt';

PART_NAME
 R2917 'Q_RES_0402LF-49.9,1%,1/16W,CHIA':;

SECTION_NUMBER 1
 '@S9S_MB_2U_LIB.S9S_MB_2U(SCH_1):PAGE140_I206@PURE_QUANTA.Q_RES(CHIPS)':
 C_PATH='@s9s_mb_2u_lib.s9s_mb_2u(sch_1):page140_i206@pure_quanta.q_res(chips)',
 P_PATH='@s9s_mb_2u_lib.s9s_mb_2u(sch_1):page151_i206@pure_quanta.q_res(chips)',
 PATH='I206',
 DRAWING='@S9S_MB_2U_LIB.S9S_MB_2U(SCH_1):PAGE140',
 PHYS_PAGE='151',
 XY='(2850,3000)',
 ROT='0',
 VER='1',
 PACK_TYPE='0402LF',
 LOCATION='R2917',
 CDS_LIB='pure_quanta',
 CDS_PART_NAME='Q_RES_0402LF-49.9,1%,1/16W,CHIA',
 WATTAGE='1/16W',
 TOLERANCE='1%',
 MATERIAL='CHIP',
 VALUE='49.9',
 PRIM_FILE='./archive_libs/logical/q_res/chips/chips.prt';

PART_NAME
 R2918 'Q_RES_0402LF-4.7K,5%,1/16W,CHIA':;

SECTION_NUMBER 1
 '@S9S_MB_2U_LIB.S9S_MB_2U(SCH_1):PAGE160_I188@PURE_QUANTA.Q_RES(CHIPS)':
 C_PATH='@s9s_mb_2u_lib.s9s_mb_2u(sch_1):page160_i188@pure_quanta.q_res(chips)',
 P_PATH='@s9s_mb_2u_lib.s9s_mb_2u(sch_1):page149_i188@pure_quanta.q_res(chips)',
 PATH='I188',
 DRAWING='@S9S_MB_2U_LIB.S9S_MB_2U(SCH_1):PAGE160',
 PHYS_PAGE='149',
 XY='(-7775,-600)',
 ROT='0',
 VER='2',
 PACK_TYPE='0402LF',
 CDS_LIB='pure_quanta',
 CDS_PART_NAME='Q_RES_0402LF-4.7K,5%,1/16W,CHIA',
 WATTAGE='1/16W',
 TOLERANCE='5%',
 MATERIAL='CHIP',
 VALUE='4.7K',
 PRIM_FILE='./archive_libs/logical/q_res/chips/chips.prt';

PART_NAME
 R2919 'Q_RES_0402LF-4.7K,5%,1/16W,CHIA':;

SECTION_NUMBER 1
 '@S9S_MB_2U_LIB.S9S_MB_2U(SCH_1):PAGE145_I91@PURE_QUANTA.Q_RES(CHIPS)':
 C_PATH='@s9s_mb_2u_lib.s9s_mb_2u(sch_1):page145_i91@pure_quanta.q_res(chips)',
 P_PATH='@s9s_mb_2u_lib.s9s_mb_2u(sch_1):page148_i91@pure_quanta.q_res(chips)',
 PATH='I91',
 DRAWING='@S9S_MB_2U_LIB.S9S_MB_2U(SCH_1):PAGE145',
 PHYS_PAGE='148',
 XY='(-2475,6725)',
 ROT='0',
 VER='2',
 PACK_TYPE='0402LF',
 CDS_LIB='pure_quanta',
 CDS_PART_NAME='Q_RES_0402LF-4.7K,5%,1/16W,CHIA',
 WATTAGE='1/16W',
 TOLERANCE='5%',
 MATERIAL='CHIP',
 VALUE='4.7K',
 PRIM_FILE='./archive_libs/logical/q_res/chips/chips.prt';

PART_NAME
 R2920 'Q_RES_0402LF-4.7K,5%,1/16W,CHIA':;

SECTION_NUMBER 1
 '@S9S_MB_2U_LIB.S9S_MB_2U(SCH_1):PAGE145_I84@PURE_QUANTA.Q_RES(CHIPS)':
 C_PATH='@s9s_mb_2u_lib.s9s_mb_2u(sch_1):page145_i84@pure_quanta.q_res(chips)',
 P_PATH='@s9s_mb_2u_lib.s9s_mb_2u(sch_1):page148_i84@pure_quanta.q_res(chips)',
 PATH='I84',
 DRAWING='@S9S_MB_2U_LIB.S9S_MB_2U(SCH_1):PAGE145',
 PHYS_PAGE='148',
 XY='(-2375,8125)',
 ROT='0',
 VER='2',
 PACK_TYPE='0402LF',
 CDS_LIB='pure_quanta',
 CDS_PART_NAME='Q_RES_0402LF-4.7K,5%,1/16W,CHIA',
 WATTAGE='1/16W',
 TOLERANCE='5%',
 MATERIAL='CHIP',
 VALUE='4.7K',
 PRIM_FILE='./archive_libs/logical/q_res/chips/chips.prt';

PART_NAME
 R2921 'Q_RES_0402LF-10K,1%,1/16W,EMPTA':;

SECTION_NUMBER 1
 '@S9S_MB_2U_LIB.S9S_MB_2U(SCH_1):PAGE214_I93@PURE_QUANTA.Q_RES(CHIPS)':
 C_PATH='@s9s_mb_2u_lib.s9s_mb_2u(sch_1):page214_i93@pure_quanta.q_res(chips)',
 P_PATH='@s9s_mb_2u_lib.s9s_mb_2u(sch_1):page227_i93@pure_quanta.q_res(chips)',
 PATH='I93',
 DRAWING='@S9S_MB_2U_LIB.S9S_MB_2U(SCH_1):PAGE214',
 PHYS_PAGE='227',
 XY='(5900,5925)',
 ROT='2',
 VER='2',
 PACK_TYPE='0402LF',
 CDS_LIB='pure_quanta',
 CDS_PART_NAME='Q_RES_0402LF-10K,1%,1/16W,EMPTA',
 WATTAGE='1/16W',
 TOLERANCE='1%',
 MATERIAL='EMPTY',
 VALUE='10K',
 PRIM_FILE='./archive_libs/logical/q_res/chips/chips.prt';

PART_NAME
 R2922 'Q_RES_0402LF-0,5%,1/16W,CHIP,CA':;

SECTION_NUMBER 1
 '@S9S_MB_2U_LIB.S9S_MB_2U(SCH_1):PAGE214_I95@PURE_QUANTA.Q_RES(CHIPS)':
 C_PATH='@s9s_mb_2u_lib.s9s_mb_2u(sch_1):page214_i95@pure_quanta.q_res(chips)',
 P_PATH='@s9s_mb_2u_lib.s9s_mb_2u(sch_1):page227_i95@pure_quanta.q_res(chips)',
 PATH='I95',
 DRAWING='@S9S_MB_2U_LIB.S9S_MB_2U(SCH_1):PAGE214',
 PHYS_PAGE='227',
 XY='(6250,5550)',
 ROT='0',
 VER='1',
 PACK_TYPE='0402LF',
 CDS_LIB='pure_quanta',
 CDS_PART_NAME='Q_RES_0402LF-0,5%,1/16W,CHIP,CA',
 WATTAGE='1/16W',
 TOLERANCE='5%',
 MATERIAL='CHIP',
 VALUE='0',
 PRIM_FILE='./archive_libs/logical/q_res/chips/chips.prt';

PART_NAME
 R2923 'Q_RES_0402LF-4.7K,5%,1/16W,EMPA':;

SECTION_NUMBER 1
 '@S9S_MB_2U_LIB.S9S_MB_2U(SCH_1):PAGE214_I90@PURE_QUANTA.Q_RES(CHIPS)':
 C_PATH='@s9s_mb_2u_lib.s9s_mb_2u(sch_1):page214_i90@pure_quanta.q_res(chips)',
 P_PATH='@s9s_mb_2u_lib.s9s_mb_2u(sch_1):page227_i90@pure_quanta.q_res(chips)',
 PATH='I90',
 DRAWING='@S9S_MB_2U_LIB.S9S_MB_2U(SCH_1):PAGE214',
 PHYS_PAGE='227',
 XY='(6675,6050)',
 ROT='0',
 VER='2',
 PACK_TYPE='0402LF',
 CDS_LIB='pure_quanta',
 CDS_PART_NAME='Q_RES_0402LF-4.7K,5%,1/16W,EMPA',
 WATTAGE='1/16W',
 TOLERANCE='5%',
 MATERIAL='EMPTY',
 VALUE='4.7K',
 PRIM_FILE='./archive_libs/logical/q_res/chips/chips.prt';

PART_NAME
 R2924 'Q_RES_0402LF-49.9,1%,1/16W,CHIA':;

SECTION_NUMBER 1
 '@S9S_MB_2U_LIB.S9S_MB_2U(SCH_1):PAGE140_I207@PURE_QUANTA.Q_RES(CHIPS)':
 C_PATH='@s9s_mb_2u_lib.s9s_mb_2u(sch_1):page140_i207@pure_quanta.q_res(chips)',
 P_PATH='@s9s_mb_2u_lib.s9s_mb_2u(sch_1):page151_i207@pure_quanta.q_res(chips)',
 PATH='I207',
 DRAWING='@S9S_MB_2U_LIB.S9S_MB_2U(SCH_1):PAGE140',
 PHYS_PAGE='151',
 XY='(2925,1875)',
 ROT='0',
 VER='1',
 PACK_TYPE='0402LF',
 LOCATION='R2924',
 CDS_LIB='pure_quanta',
 CDS_PART_NAME='Q_RES_0402LF-49.9,1%,1/16W,CHIA',
 WATTAGE='1/16W',
 TOLERANCE='1%',
 MATERIAL='CHIP',
 VALUE='49.9',
 PRIM_FILE='./archive_libs/logical/q_res/chips/chips.prt';

PART_NAME
 R2925 'Q_RES_0402LF-49.9,1%,1/16W,CHIA':;

SECTION_NUMBER 1
 '@S9S_MB_2U_LIB.S9S_MB_2U(SCH_1):PAGE140_I204@PURE_QUANTA.Q_RES(CHIPS)':
 C_PATH='@s9s_mb_2u_lib.s9s_mb_2u(sch_1):page140_i204@pure_quanta.q_res(chips)',
 P_PATH='@s9s_mb_2u_lib.s9s_mb_2u(sch_1):page151_i204@pure_quanta.q_res(chips)',
 PATH='I204',
 DRAWING='@S9S_MB_2U_LIB.S9S_MB_2U(SCH_1):PAGE140',
 PHYS_PAGE='151',
 XY='(2825,600)',
 ROT='0',
 VER='1',
 PACK_TYPE='0402LF',
 LOCATION='R2925',
 CDS_LIB='pure_quanta',
 CDS_PART_NAME='Q_RES_0402LF-49.9,1%,1/16W,CHIA',
 WATTAGE='1/16W',
 TOLERANCE='1%',
 MATERIAL='CHIP',
 VALUE='49.9',
 PRIM_FILE='./archive_libs/logical/q_res/chips/chips.prt';

PART_NAME
 R2926 'Q_RES_0402LF-4.7K,5%,1/16W,CHIA':;

SECTION_NUMBER 1
 '@S9S_MB_2U_LIB.S9S_MB_2U(SCH_1):PAGE140_I121@PURE_QUANTA.Q_RES(CHIPS)':
 C_PATH='@s9s_mb_2u_lib.s9s_mb_2u(sch_1):page140_i121@pure_quanta.q_res(chips)',
 P_PATH='@s9s_mb_2u_lib.s9s_mb_2u(sch_1):page151_i121@pure_quanta.q_res(chips)',
 PATH='I121',
 DRAWING='@S9S_MB_2U_LIB.S9S_MB_2U(SCH_1):PAGE140',
 PHYS_PAGE='151',
 XY='(2525,2700)',
 ROT='0',
 VER='2',
 PACK_TYPE='0402LF',
 CDS_LIB='pure_quanta',
 CDS_PART_NAME='Q_RES_0402LF-4.7K,5%,1/16W,CHIA',
 WATTAGE='1/16W',
 TOLERANCE='5%',
 MATERIAL='CHIP',
 VALUE='4.7K',
 PRIM_FILE='./archive_libs/logical/q_res/chips/chips.prt';

PART_NAME
 R2927 'Q_RES_0402LF-100K,1%,1/16W,CHIA':;

SECTION_NUMBER 1
 '@S9S_MB_2U_LIB.S9S_MB_2U(SCH_1):PAGE140_I203@PURE_QUANTA.Q_RES(CHIPS)':
 C_PATH='@s9s_mb_2u_lib.s9s_mb_2u(sch_1):page140_i203@pure_quanta.q_res(chips)',
 P_PATH='@s9s_mb_2u_lib.s9s_mb_2u(sch_1):page151_i203@pure_quanta.q_res(chips)',
 PATH='I203',
 DRAWING='@S9S_MB_2U_LIB.S9S_MB_2U(SCH_1):PAGE140',
 PHYS_PAGE='151',
 XY='(2625,1575)',
 ROT='0',
 VER='2',
 PACK_TYPE='0402LF',
 LOCATION='R2927',
 CDS_LIB='pure_quanta',
 CDS_PART_NAME='Q_RES_0402LF-100K,1%,1/16W,CHIA',
 WATTAGE='1/16W',
 TOLERANCE='1%',
 MATERIAL='CHIP',
 VALUE='100K',
 PRIM_FILE='./archive_libs/logical/q_res/chips/chips.prt';

PART_NAME
 R2932 'Q_RES_0402LF-4.7K,5%,1/16W,CHIA':;

SECTION_NUMBER 1
 '@S9S_MB_2U_LIB.S9S_MB_2U(SCH_1):PAGE160_I195@PURE_QUANTA.Q_RES(CHIPS)':
 C_PATH='@s9s_mb_2u_lib.s9s_mb_2u(sch_1):page160_i195@pure_quanta.q_res(chips)',
 P_PATH='@s9s_mb_2u_lib.s9s_mb_2u(sch_1):page149_i195@pure_quanta.q_res(chips)',
 PATH='I195',
 DRAWING='@S9S_MB_2U_LIB.S9S_MB_2U(SCH_1):PAGE160',
 PHYS_PAGE='149',
 XY='(-4125,-800)',
 ROT='0',
 VER='2',
 PACK_TYPE='0402LF',
 CDS_LIB='pure_quanta',
 CDS_PART_NAME='Q_RES_0402LF-4.7K,5%,1/16W,CHIA',
 WATTAGE='1/16W',
 TOLERANCE='5%',
 MATERIAL='CHIP',
 VALUE='4.7K',
 PRIM_FILE='./archive_libs/logical/q_res/chips/chips.prt';

PART_NAME
 R2933 'Q_RES_0402LF-4.7K,5%,1/16W,CHIA':;

SECTION_NUMBER 1
 '@S9S_MB_2U_LIB.S9S_MB_2U(SCH_1):PAGE145_I97@PURE_QUANTA.Q_RES(CHIPS)':
 C_PATH='@s9s_mb_2u_lib.s9s_mb_2u(sch_1):page145_i97@pure_quanta.q_res(chips)',
 P_PATH='@s9s_mb_2u_lib.s9s_mb_2u(sch_1):page148_i97@pure_quanta.q_res(chips)',
 PATH='I97',
 DRAWING='@S9S_MB_2U_LIB.S9S_MB_2U(SCH_1):PAGE145',
 PHYS_PAGE='148',
 XY='(-2500,5350)',
 ROT='0',
 VER='2',
 PACK_TYPE='0402LF',
 CDS_LIB='pure_quanta',
 CDS_PART_NAME='Q_RES_0402LF-4.7K,5%,1/16W,CHIA',
 WATTAGE='1/16W',
 TOLERANCE='5%',
 MATERIAL='CHIP',
 VALUE='4.7K',
 PRIM_FILE='./archive_libs/logical/q_res/chips/chips.prt';

PART_NAME
 R2934 'Q_RES_0402LF-4.7K,5%,1/16W,CHIA':;

SECTION_NUMBER 1
 '@S9S_MB_2U_LIB.S9S_MB_2U(SCH_1):PAGE145_I101@PURE_QUANTA.Q_RES(CHIPS)':
 C_PATH='@s9s_mb_2u_lib.s9s_mb_2u(sch_1):page145_i101@pure_quanta.q_res(chips)',
 P_PATH='@s9s_mb_2u_lib.s9s_mb_2u(sch_1):page148_i101@pure_quanta.q_res(chips)',
 PATH='I101',
 DRAWING='@S9S_MB_2U_LIB.S9S_MB_2U(SCH_1):PAGE145',
 PHYS_PAGE='148',
 XY='(1925,8175)',
 ROT='0',
 VER='2',
 PACK_TYPE='0402LF',
 CDS_LIB='pure_quanta',
 CDS_PART_NAME='Q_RES_0402LF-4.7K,5%,1/16W,CHIA',
 WATTAGE='1/16W',
 TOLERANCE='5%',
 MATERIAL='CHIP',
 VALUE='4.7K',
 PRIM_FILE='./archive_libs/logical/q_res/chips/chips.prt';

PART_NAME
 R2935 'Q_RES_0402LF-4.7K,5%,1/16W,CHIA':;

SECTION_NUMBER 1
 '@S9S_MB_2U_LIB.S9S_MB_2U(SCH_1):PAGE145_I109@PURE_QUANTA.Q_RES(CHIPS)':
 C_PATH='@s9s_mb_2u_lib.s9s_mb_2u(sch_1):page145_i109@pure_quanta.q_res(chips)',
 P_PATH='@s9s_mb_2u_lib.s9s_mb_2u(sch_1):page148_i109@pure_quanta.q_res(chips)',
 PATH='I109',
 DRAWING='@S9S_MB_2U_LIB.S9S_MB_2U(SCH_1):PAGE145',
 PHYS_PAGE='148',
 XY='(2025,6875)',
 ROT='0',
 VER='2',
 PACK_TYPE='0402LF',
 CDS_LIB='pure_quanta',
 CDS_PART_NAME='Q_RES_0402LF-4.7K,5%,1/16W,CHIA',
 WATTAGE='1/16W',
 TOLERANCE='5%',
 MATERIAL='CHIP',
 VALUE='4.7K',
 PRIM_FILE='./archive_libs/logical/q_res/chips/chips.prt';

PART_NAME
 R2936 'Q_RES_0402LF-100K,1%,1/16W,EMPA':;

SECTION_NUMBER 1
 '@S9S_MB_2U_LIB.S9S_MB_2U(SCH_1):PAGE140_I162@PURE_QUANTA.Q_RES(CHIPS)':
 C_PATH='@s9s_mb_2u_lib.s9s_mb_2u(sch_1):page140_i162@pure_quanta.q_res(chips)',
 P_PATH='@s9s_mb_2u_lib.s9s_mb_2u(sch_1):page151_i162@pure_quanta.q_res(chips)',
 PATH='I162',
 DRAWING='@S9S_MB_2U_LIB.S9S_MB_2U(SCH_1):PAGE140',
 PHYS_PAGE='151',
 XY='(-75,875)',
 ROT='0',
 VER='2',
 PACK_TYPE='0402LF',
 CDS_LIB='pure_quanta',
 CDS_PART_NAME='Q_RES_0402LF-100K,1%,1/16W,EMPA',
 WATTAGE='1/16W',
 TOLERANCE='1%',
 MATERIAL='EMPTY',
 VALUE='100K',
 PRIM_FILE='./archive_libs/logical/q_res/chips/chips.prt';

PART_NAME
 R2937 'Q_RES_0402LF-4.7K,5%,1/16W,CHIA':;

SECTION_NUMBER 1
 '@S9S_MB_2U_LIB.S9S_MB_2U(SCH_1):PAGE140_I160@PURE_QUANTA.Q_RES(CHIPS)':
 C_PATH='@s9s_mb_2u_lib.s9s_mb_2u(sch_1):page140_i160@pure_quanta.q_res(chips)',
 P_PATH='@s9s_mb_2u_lib.s9s_mb_2u(sch_1):page151_i160@pure_quanta.q_res(chips)',
 PATH='I160',
 DRAWING='@S9S_MB_2U_LIB.S9S_MB_2U(SCH_1):PAGE140',
 PHYS_PAGE='151',
 XY='(-50,400)',
 ROT='0',
 VER='2',
 PACK_TYPE='0402LF',
 CDS_LIB='pure_quanta',
 CDS_PART_NAME='Q_RES_0402LF-4.7K,5%,1/16W,CHIA',
 WATTAGE='1/16W',
 TOLERANCE='5%',
 MATERIAL='CHIP',
 VALUE='4.7K',
 PRIM_FILE='./archive_libs/logical/q_res/chips/chips.prt';

PART_NAME
 R2939 'Q_RES_0402LF-33.2,1%,1/16W,CHIA':;

SECTION_NUMBER 1
 '@S9S_MB_2U_LIB.S9S_MB_2U(SCH_1):PAGE314_I106@PURE_QUANTA.Q_RES(CHIPS)':
 C_PATH='@s9s_mb_2u_lib.s9s_mb_2u(sch_1):page314_i106@pure_quanta.q_res(chips)',
 P_PATH='@s9s_mb_2u_lib.s9s_mb_2u(sch_1):page213_i106@pure_quanta.q_res(chips)',
 PATH='I106',
 DRAWING='@S9S_MB_2U_LIB.S9S_MB_2U(SCH_1):PAGE314',
 PHYS_PAGE='213',
 XY='(2725,-1400)',
 ROT='0',
 VER='1',
 PACK_TYPE='0402LF',
 LOCATION='R2939',
 CDS_LIB='pure_quanta',
 CDS_PART_NAME='Q_RES_0402LF-33.2,1%,1/16W,CHIA',
 WATTAGE='1/16W',
 TOLERANCE='1%',
 MATERIAL='CHIP',
 VALUE='33.2',
 PRIM_FILE='./archive_libs/logical/q_res/chips/chips.prt';

PART_NAME
 R2940 'Q_RES_0402LF-4.7K,5%,1/16W,EMPA':;

SECTION_NUMBER 1
 '@S9S_MB_2U_LIB.S9S_MB_2U(SCH_1):PAGE230_I28@PURE_QUANTA.Q_RES(CHIPS)':
 C_PATH='@s9s_mb_2u_lib.s9s_mb_2u(sch_1):page230_i28@pure_quanta.q_res(chips)',
 P_PATH='@s9s_mb_2u_lib.s9s_mb_2u(sch_1):page246_i28@pure_quanta.q_res(chips)',
 PATH='I28',
 DRAWING='@S9S_MB_2U_LIB.S9S_MB_2U(SCH_1):PAGE230',
 PHYS_PAGE='246',
 XY='(-1800,3100)',
 ROT='0',
 VER='2',
 PACK_TYPE='0402LF',
 CDS_LIB='pure_quanta',
 CDS_PART_NAME='Q_RES_0402LF-4.7K,5%,1/16W,EMPA',
 WATTAGE='1/16W',
 TOLERANCE='5%',
 MATERIAL='EMPTY',
 VALUE='4.7K',
 PRIM_FILE='./archive_libs/logical/q_res/chips/chips.prt';

PART_NAME
 R2941 'Q_RES_0402LF-100K,1%,1/16W,CHIA':;

SECTION_NUMBER 1
 '@S9S_MB_2U_LIB.S9S_MB_2U(SCH_1):PAGE230_I29@PURE_QUANTA.Q_RES(CHIPS)':
 C_PATH='@s9s_mb_2u_lib.s9s_mb_2u(sch_1):page230_i29@pure_quanta.q_res(chips)',
 P_PATH='@s9s_mb_2u_lib.s9s_mb_2u(sch_1):page246_i29@pure_quanta.q_res(chips)',
 PATH='I29',
 DRAWING='@S9S_MB_2U_LIB.S9S_MB_2U(SCH_1):PAGE230',
 PHYS_PAGE='246',
 XY='(-1775,2625)',
 ROT='0',
 VER='2',
 PACK_TYPE='0402LF',
 CDS_LIB='pure_quanta',
 CDS_PART_NAME='Q_RES_0402LF-100K,1%,1/16W,CHIA',
 WATTAGE='1/16W',
 TOLERANCE='1%',
 MATERIAL='CHIP',
 VALUE='100K',
 PRIM_FILE='./archive_libs/logical/q_res/chips/chips.prt';

PART_NAME
 R2944 'Q_RES_0402LF-33.2,1%,1/16W,CHIA':;

SECTION_NUMBER 1
 '@S9S_MB_2U_LIB.S9S_MB_2U(SCH_1):PAGE230_I24@PURE_QUANTA.Q_RES(CHIPS)':
 C_PATH='@s9s_mb_2u_lib.s9s_mb_2u(sch_1):page230_i24@pure_quanta.q_res(chips)',
 P_PATH='@s9s_mb_2u_lib.s9s_mb_2u(sch_1):page246_i24@pure_quanta.q_res(chips)',
 PATH='I24',
 DRAWING='@S9S_MB_2U_LIB.S9S_MB_2U(SCH_1):PAGE230',
 PHYS_PAGE='246',
 XY='(2000,2075)',
 ROT='0',
 VER='1',
 PACK_TYPE='0402LF',
 CDS_LIB='pure_quanta',
 CDS_PART_NAME='Q_RES_0402LF-33.2,1%,1/16W,CHIA',
 WATTAGE='1/16W',
 TOLERANCE='1%',
 MATERIAL='CHIP',
 VALUE='33.2',
 PRIM_FILE='./archive_libs/logical/q_res/chips/chips.prt';

PART_NAME
 R2946 'Q_RES_0402LF-4.7K,5%,1/16W,EMPA':;

SECTION_NUMBER 1
 '@S9S_MB_2U_LIB.S9S_MB_2U(SCH_1):PAGE230_I25@PURE_QUANTA.Q_RES(CHIPS)':
 C_PATH='@s9s_mb_2u_lib.s9s_mb_2u(sch_1):page230_i25@pure_quanta.q_res(chips)',
 P_PATH='@s9s_mb_2u_lib.s9s_mb_2u(sch_1):page246_i25@pure_quanta.q_res(chips)',
 PATH='I25',
 DRAWING='@S9S_MB_2U_LIB.S9S_MB_2U(SCH_1):PAGE230',
 PHYS_PAGE='246',
 XY='(1725,2325)',
 ROT='0',
 VER='2',
 PACK_TYPE='0402LF',
 CDS_LIB='pure_quanta',
 CDS_PART_NAME='Q_RES_0402LF-4.7K,5%,1/16W,EMPA',
 WATTAGE='1/16W',
 TOLERANCE='5%',
 MATERIAL='EMPTY',
 VALUE='4.7K',
 PRIM_FILE='./archive_libs/logical/q_res/chips/chips.prt';

PART_NAME
 R2948 'Q_RES_0402LF-4.7K,5%,1/16W,EMPA':;

SECTION_NUMBER 1
 '@S9S_MB_2U_LIB.S9S_MB_2U(SCH_1):PAGE230_I30@PURE_QUANTA.Q_RES(CHIPS)':
 C_PATH='@s9s_mb_2u_lib.s9s_mb_2u(sch_1):page230_i30@pure_quanta.q_res(chips)',
 P_PATH='@s9s_mb_2u_lib.s9s_mb_2u(sch_1):page246_i30@pure_quanta.q_res(chips)',
 PATH='I30',
 DRAWING='@S9S_MB_2U_LIB.S9S_MB_2U(SCH_1):PAGE230',
 PHYS_PAGE='246',
 XY='(1750,1775)',
 ROT='0',
 VER='2',
 PACK_TYPE='0402LF',
 CDS_LIB='pure_quanta',
 CDS_PART_NAME='Q_RES_0402LF-4.7K,5%,1/16W,EMPA',
 WATTAGE='1/16W',
 TOLERANCE='5%',
 MATERIAL='EMPTY',
 VALUE='4.7K',
 PRIM_FILE='./archive_libs/logical/q_res/chips/chips.prt';

PART_NAME
 R2950 'Q_RES_0402LF-4.7K,5%,1/16W,EMPA':;

SECTION_NUMBER 1
 '@S9S_MB_2U_LIB.S9S_MB_2U(SCH_1):PAGE233_I4@PURE_QUANTA.Q_RES(CHIPS)':
 C_PATH='@s9s_mb_2u_lib.s9s_mb_2u(sch_1):page233_i4@pure_quanta.q_res(chips)',
 P_PATH='@s9s_mb_2u_lib.s9s_mb_2u(sch_1):page245_i4@pure_quanta.q_res(chips)',
 PATH='I4',
 DRAWING='@S9S_MB_2U_LIB.S9S_MB_2U(SCH_1):PAGE233',
 PHYS_PAGE='245',
 XY='(-5800,-1700)',
 ROT='0',
 VER='2',
 PACK_TYPE='0402LF',
 CDS_LIB='pure_quanta',
 CDS_PART_NAME='Q_RES_0402LF-4.7K,5%,1/16W,EMPA',
 WATTAGE='1/16W',
 TOLERANCE='5%',
 MATERIAL='EMPTY',
 VALUE='4.7K',
 PRIM_FILE='./archive_libs/logical/q_res/chips/chips.prt';

PART_NAME
 R2966 'Q_RES_0402LF-1M,1%,1/16W,CHIP,A':;

SECTION_NUMBER 1
 '@S9S_MB_2U_LIB.S9S_MB_2U(SCH_1):PAGE174_I96@PURE_QUANTA.Q_RES(CHIPS)':
 C_PATH='@s9s_mb_2u_lib.s9s_mb_2u(sch_1):page174_i96@pure_quanta.q_res(chips)',
 P_PATH='@s9s_mb_2u_lib.s9s_mb_2u(sch_1):page182_i96@pure_quanta.q_res(chips)',
 PATH='I96',
 DRAWING='@S9S_MB_2U_LIB.S9S_MB_2U(SCH_1):PAGE174',
 PHYS_PAGE='182',
 XY='(5025,2450)',
 ROT='0',
 VER='2',
 PACK_TYPE='0402LF',
 CDS_LIB='pure_quanta',
 CDS_PART_NAME='Q_RES_0402LF-1M,1%,1/16W,CHIP,A',
 WATTAGE='1/16W',
 TOLERANCE='1%',
 MATERIAL='CHIP',
 VALUE='1M',
 PRIM_FILE='./archive_libs/logical/q_res/chips/chips.prt';

PART_NAME
 R2967 'Q_RES_0402LF-0,5%,1/16W,CHIP,CA':;

SECTION_NUMBER 1
 '@S9S_MB_2U_LIB.S9S_MB_2U(SCH_1):PAGE219_I36@PURE_QUANTA.Q_RES(CHIPS)':
 C_PATH='@s9s_mb_2u_lib.s9s_mb_2u(sch_1):page219_i36@pure_quanta.q_res(chips)',
 P_PATH='@s9s_mb_2u_lib.s9s_mb_2u(sch_1):page231_i36@pure_quanta.q_res(chips)',
 PATH='I36',
 DRAWING='@S9S_MB_2U_LIB.S9S_MB_2U(SCH_1):PAGE219',
 PHYS_PAGE='231',
 XY='(600,2525)',
 ROT='2',
 VER='1',
 PACK_TYPE='0402LF',
 CDS_LIB='pure_quanta',
 CDS_PART_NAME='Q_RES_0402LF-0,5%,1/16W,CHIP,CA',
 WATTAGE='1/16W',
 TOLERANCE='5%',
 MATERIAL='CHIP',
 VALUE='0',
 PRIM_FILE='./archive_libs/logical/q_res/chips/chips.prt';

PART_NAME
 R2968 'Q_RES_0402LF-0,5%,1/16W,CHIP,CA':;

SECTION_NUMBER 1
 '@S9S_MB_2U_LIB.S9S_MB_2U(SCH_1):PAGE219_I39@PURE_QUANTA.Q_RES(CHIPS)':
 C_PATH='@s9s_mb_2u_lib.s9s_mb_2u(sch_1):page219_i39@pure_quanta.q_res(chips)',
 P_PATH='@s9s_mb_2u_lib.s9s_mb_2u(sch_1):page231_i39@pure_quanta.q_res(chips)',
 PATH='I39',
 DRAWING='@S9S_MB_2U_LIB.S9S_MB_2U(SCH_1):PAGE219',
 PHYS_PAGE='231',
 XY='(600,2575)',
 ROT='2',
 VER='1',
 PACK_TYPE='0402LF',
 CDS_LIB='pure_quanta',
 CDS_PART_NAME='Q_RES_0402LF-0,5%,1/16W,CHIP,CA',
 WATTAGE='1/16W',
 TOLERANCE='5%',
 MATERIAL='CHIP',
 VALUE='0',
 PRIM_FILE='./archive_libs/logical/q_res/chips/chips.prt';

PART_NAME
 R2969 'Q_RES_0402LF-0,5%,1/16W,CHIP,CA':;

SECTION_NUMBER 1
 '@S9S_MB_2U_LIB.S9S_MB_2U(SCH_1):PAGE128_I49@PURE_QUANTA.Q_RES(CHIPS)':
 C_PATH='@s9s_mb_2u_lib.s9s_mb_2u(sch_1):page128_i49@pure_quanta.q_res(chips)',
 P_PATH='@s9s_mb_2u_lib.s9s_mb_2u(sch_1):page128_i49@pure_quanta.q_res(chips)',
 PATH='I49',
 DRAWING='@S9S_MB_2U_LIB.S9S_MB_2U(SCH_1):PAGE128',
 PHYS_PAGE='128',
 XY='(-5325,375)',
 ROT='0',
 VER='1',
 PACK_TYPE='0402LF',
 CDS_LIB='pure_quanta',
 CDS_PART_NAME='Q_RES_0402LF-0,5%,1/16W,CHIP,CA',
 WATTAGE='1/16W',
 TOLERANCE='5%',
 MATERIAL='CHIP',
 VALUE='0',
 PRIM_FILE='./archive_libs/logical/q_res/chips/chips.prt';

PART_NAME
 R2971 'Q_RES_0402LF-0,5%,1/16W,CHIP,CA':;

SECTION_NUMBER 1
 '@S9S_MB_2U_LIB.S9S_MB_2U(SCH_1):PAGE175_I253@PURE_QUANTA.Q_RES(CHIPS)':
 C_PATH='@s9s_mb_2u_lib.s9s_mb_2u(sch_1):page175_i253@pure_quanta.q_res(chips)',
 P_PATH='@s9s_mb_2u_lib.s9s_mb_2u(sch_1):page183_i253@pure_quanta.q_res(chips)',
 PATH='I253',
 DRAWING='@S9S_MB_2U_LIB.S9S_MB_2U(SCH_1):PAGE175',
 PHYS_PAGE='183',
 XY='(2950,1650)',
 ROT='0',
 VER='1',
 PACK_TYPE='0402LF',
 CDS_LIB='pure_quanta',
 CDS_PART_NAME='Q_RES_0402LF-0,5%,1/16W,CHIP,CA',
 WATTAGE='1/16W',
 TOLERANCE='5%',
 MATERIAL='CHIP',
 VALUE='0',
 PRIM_FILE='./archive_libs/logical/q_res/chips/chips.prt';

PART_NAME
 R2972 'Q_RES_0402LF-10K,1%,1/16W,CHIPA':;

SECTION_NUMBER 1
 '@S9S_MB_2U_LIB.S9S_MB_2U(SCH_1):PAGE184_I71@PURE_QUANTA.Q_RES(CHIPS)':
 C_PATH='@s9s_mb_2u_lib.s9s_mb_2u(sch_1):page184_i71@pure_quanta.q_res(chips)',
 P_PATH='@s9s_mb_2u_lib.s9s_mb_2u(sch_1):page195_i71@pure_quanta.q_res(chips)',
 PATH='I71',
 DRAWING='@S9S_MB_2U_LIB.S9S_MB_2U(SCH_1):PAGE184',
 PHYS_PAGE='195',
 XY='(1875,5150)',
 ROT='0',
 VER='2',
 PACK_TYPE='0402LF',
 CDS_LIB='pure_quanta',
 CDS_PART_NAME='Q_RES_0402LF-10K,1%,1/16W,CHIPA',
 WATTAGE='1/16W',
 TOLERANCE='1%',
 MATERIAL='CHIP',
 VALUE='10K',
 PRIM_FILE='./archive_libs/logical/q_res/chips/chips.prt';

PART_NAME
 R2973 'Q_RES_0402LF-1K,1%,1/16W,EMPTYA':;

SECTION_NUMBER 1
 '@S9S_MB_2U_LIB.S9S_MB_2U(SCH_1):PAGE184_I69@PURE_QUANTA.Q_RES(CHIPS)':
 C_PATH='@s9s_mb_2u_lib.s9s_mb_2u(sch_1):page184_i69@pure_quanta.q_res(chips)',
 P_PATH='@s9s_mb_2u_lib.s9s_mb_2u(sch_1):page195_i69@pure_quanta.q_res(chips)',
 PATH='I69',
 DRAWING='@S9S_MB_2U_LIB.S9S_MB_2U(SCH_1):PAGE184',
 PHYS_PAGE='195',
 XY='(1875,4500)',
 ROT='0',
 VER='2',
 PACK_TYPE='0402LF',
 CDS_LIB='pure_quanta',
 CDS_PART_NAME='Q_RES_0402LF-1K,1%,1/16W,EMPTYA',
 WATTAGE='1/16W',
 TOLERANCE='1%',
 MATERIAL='EMPTY',
 VALUE='1K',
 PRIM_FILE='./archive_libs/logical/q_res/chips/chips.prt';

PART_NAME
 R2974 'Q_RES_0402LF-10K,1%,1/16W,CHIPA':;

SECTION_NUMBER 1
 '@S9S_MB_2U_LIB.S9S_MB_2U(SCH_1):PAGE184_I72@PURE_QUANTA.Q_RES(CHIPS)':
 C_PATH='@s9s_mb_2u_lib.s9s_mb_2u(sch_1):page184_i72@pure_quanta.q_res(chips)',
 P_PATH='@s9s_mb_2u_lib.s9s_mb_2u(sch_1):page195_i72@pure_quanta.q_res(chips)',
 PATH='I72',
 DRAWING='@S9S_MB_2U_LIB.S9S_MB_2U(SCH_1):PAGE184',
 PHYS_PAGE='195',
 XY='(2150,5150)',
 ROT='0',
 VER='2',
 PACK_TYPE='0402LF',
 CDS_LIB='pure_quanta',
 CDS_PART_NAME='Q_RES_0402LF-10K,1%,1/16W,CHIPA',
 WATTAGE='1/16W',
 TOLERANCE='1%',
 MATERIAL='CHIP',
 VALUE='10K',
 PRIM_FILE='./archive_libs/logical/q_res/chips/chips.prt';

PART_NAME
 R2975 'Q_RES_0402LF-1K,1%,1/16W,EMPTYA':;

SECTION_NUMBER 1
 '@S9S_MB_2U_LIB.S9S_MB_2U(SCH_1):PAGE184_I70@PURE_QUANTA.Q_RES(CHIPS)':
 C_PATH='@s9s_mb_2u_lib.s9s_mb_2u(sch_1):page184_i70@pure_quanta.q_res(chips)',
 P_PATH='@s9s_mb_2u_lib.s9s_mb_2u(sch_1):page195_i70@pure_quanta.q_res(chips)',
 PATH='I70',
 DRAWING='@S9S_MB_2U_LIB.S9S_MB_2U(SCH_1):PAGE184',
 PHYS_PAGE='195',
 XY='(2150,4500)',
 ROT='0',
 VER='2',
 PACK_TYPE='0402LF',
 CDS_LIB='pure_quanta',
 CDS_PART_NAME='Q_RES_0402LF-1K,1%,1/16W,EMPTYA',
 WATTAGE='1/16W',
 TOLERANCE='1%',
 MATERIAL='EMPTY',
 VALUE='1K',
 PRIM_FILE='./archive_libs/logical/q_res/chips/chips.prt';

PART_NAME
 R2976 'Q_RES_0402LF-10K,1%,1/16W,EMPTA':;

SECTION_NUMBER 1
 '@S9S_MB_2U_LIB.S9S_MB_2U(SCH_1):PAGE184_I13@PURE_QUANTA.Q_RES(CHIPS)':
 C_PATH='@s9s_mb_2u_lib.s9s_mb_2u(sch_1):page184_i13@pure_quanta.q_res(chips)',
 P_PATH='@s9s_mb_2u_lib.s9s_mb_2u(sch_1):page195_i13@pure_quanta.q_res(chips)',
 PATH='I13',
 DRAWING='@S9S_MB_2U_LIB.S9S_MB_2U(SCH_1):PAGE184',
 PHYS_PAGE='195',
 XY='(-950,5225)',
 ROT='0',
 VER='2',
 PACK_TYPE='0402LF',
 CDS_LIB='pure_quanta',
 CDS_PART_NAME='Q_RES_0402LF-10K,1%,1/16W,EMPTA',
 WATTAGE='1/16W',
 TOLERANCE='1%',
 MATERIAL='EMPTY',
 VALUE='10K',
 PRIM_FILE='./archive_libs/logical/q_res/chips/chips.prt';

PART_NAME
 R2977 'Q_RES_0402LF-1K,1%,1/16W,CHIP,A':;

SECTION_NUMBER 1
 '@S9S_MB_2U_LIB.S9S_MB_2U(SCH_1):PAGE184_I11@PURE_QUANTA.Q_RES(CHIPS)':
 C_PATH='@s9s_mb_2u_lib.s9s_mb_2u(sch_1):page184_i11@pure_quanta.q_res(chips)',
 P_PATH='@s9s_mb_2u_lib.s9s_mb_2u(sch_1):page195_i11@pure_quanta.q_res(chips)',
 PATH='I11',
 DRAWING='@S9S_MB_2U_LIB.S9S_MB_2U(SCH_1):PAGE184',
 PHYS_PAGE='195',
 XY='(-950,4400)',
 ROT='0',
 VER='2',
 PACK_TYPE='0402LF',
 CDS_LIB='pure_quanta',
 CDS_PART_NAME='Q_RES_0402LF-1K,1%,1/16W,CHIP,A',
 WATTAGE='1/16W',
 TOLERANCE='1%',
 MATERIAL='CHIP',
 VALUE='1K',
 PRIM_FILE='./archive_libs/logical/q_res/chips/chips.prt';

PART_NAME
 R2978 'Q_RES_0402LF-1K,1%,1/16W,EMPTYA':;

SECTION_NUMBER 1
 '@S9S_MB_2U_LIB.S9S_MB_2U(SCH_1):PAGE184_I74@PURE_QUANTA.Q_RES(CHIPS)':
 C_PATH='@s9s_mb_2u_lib.s9s_mb_2u(sch_1):page184_i74@pure_quanta.q_res(chips)',
 P_PATH='@s9s_mb_2u_lib.s9s_mb_2u(sch_1):page195_i74@pure_quanta.q_res(chips)',
 PATH='I74',
 DRAWING='@S9S_MB_2U_LIB.S9S_MB_2U(SCH_1):PAGE184',
 PHYS_PAGE='195',
 XY='(2425,4500)',
 ROT='0',
 VER='2',
 PACK_TYPE='0402LF',
 CDS_LIB='pure_quanta',
 CDS_PART_NAME='Q_RES_0402LF-1K,1%,1/16W,EMPTYA',
 WATTAGE='1/16W',
 TOLERANCE='1%',
 MATERIAL='EMPTY',
 VALUE='1K',
 PRIM_FILE='./archive_libs/logical/q_res/chips/chips.prt';

PART_NAME
 R2979 'Q_RES_0402LF-10K,1%,1/16W,EMPTA':;

SECTION_NUMBER 1
 '@S9S_MB_2U_LIB.S9S_MB_2U(SCH_1):PAGE184_I48@PURE_QUANTA.Q_RES(CHIPS)':
 C_PATH='@s9s_mb_2u_lib.s9s_mb_2u(sch_1):page184_i48@pure_quanta.q_res(chips)',
 P_PATH='@s9s_mb_2u_lib.s9s_mb_2u(sch_1):page195_i48@pure_quanta.q_res(chips)',
 PATH='I48',
 DRAWING='@S9S_MB_2U_LIB.S9S_MB_2U(SCH_1):PAGE184',
 PHYS_PAGE='195',
 XY='(-675,5225)',
 ROT='0',
 VER='2',
 PACK_TYPE='0402LF',
 CDS_LIB='pure_quanta',
 CDS_PART_NAME='Q_RES_0402LF-10K,1%,1/16W,EMPTA',
 WATTAGE='1/16W',
 TOLERANCE='1%',
 MATERIAL='EMPTY',
 VALUE='10K',
 PRIM_FILE='./archive_libs/logical/q_res/chips/chips.prt';

PART_NAME
 R2980 'Q_RES_0402LF-1K,1%,1/16W,CHIP,A':;

SECTION_NUMBER 1
 '@S9S_MB_2U_LIB.S9S_MB_2U(SCH_1):PAGE184_I26@PURE_QUANTA.Q_RES(CHIPS)':
 C_PATH='@s9s_mb_2u_lib.s9s_mb_2u(sch_1):page184_i26@pure_quanta.q_res(chips)',
 P_PATH='@s9s_mb_2u_lib.s9s_mb_2u(sch_1):page195_i26@pure_quanta.q_res(chips)',
 PATH='I26',
 DRAWING='@S9S_MB_2U_LIB.S9S_MB_2U(SCH_1):PAGE184',
 PHYS_PAGE='195',
 XY='(-675,4400)',
 ROT='0',
 VER='2',
 PACK_TYPE='0402LF',
 CDS_LIB='pure_quanta',
 CDS_PART_NAME='Q_RES_0402LF-1K,1%,1/16W,CHIP,A',
 WATTAGE='1/16W',
 TOLERANCE='1%',
 MATERIAL='CHIP',
 VALUE='1K',
 PRIM_FILE='./archive_libs/logical/q_res/chips/chips.prt';

PART_NAME
 R2982 'Q_RES_0402LF-0,5%,1/16W,CHIP,CA':;

SECTION_NUMBER 1
 '@S9S_MB_2U_LIB.S9S_MB_2U(SCH_1):PAGE214_I96@PURE_QUANTA.Q_RES(CHIPS)':
 C_PATH='@s9s_mb_2u_lib.s9s_mb_2u(sch_1):page214_i96@pure_quanta.q_res(chips)',
 P_PATH='@s9s_mb_2u_lib.s9s_mb_2u(sch_1):page227_i96@pure_quanta.q_res(chips)',
 PATH='I96',
 DRAWING='@S9S_MB_2U_LIB.S9S_MB_2U(SCH_1):PAGE214',
 PHYS_PAGE='227',
 XY='(8675,3525)',
 ROT='0',
 VER='1',
 PACK_TYPE='0402LF',
 CDS_LIB='pure_quanta',
 CDS_PART_NAME='Q_RES_0402LF-0,5%,1/16W,CHIP,CA',
 WATTAGE='1/16W',
 TOLERANCE='5%',
 MATERIAL='CHIP',
 VALUE='0',
 PRIM_FILE='./archive_libs/logical/q_res/chips/chips.prt';

PART_NAME
 R2983 'Q_RES_0402LF-0,5%,1/16W,CHIP,CA':;

SECTION_NUMBER 1
 '@S9S_MB_2U_LIB.S9S_MB_2U(SCH_1):PAGE214_I101@PURE_QUANTA.Q_RES(CHIPS)':
 C_PATH='@s9s_mb_2u_lib.s9s_mb_2u(sch_1):page214_i101@pure_quanta.q_res(chips)',
 P_PATH='@s9s_mb_2u_lib.s9s_mb_2u(sch_1):page227_i101@pure_quanta.q_res(chips)',
 PATH='I101',
 DRAWING='@S9S_MB_2U_LIB.S9S_MB_2U(SCH_1):PAGE214',
 PHYS_PAGE='227',
 XY='(8675,3325)',
 ROT='0',
 VER='1',
 PACK_TYPE='0402LF',
 CDS_LIB='pure_quanta',
 CDS_PART_NAME='Q_RES_0402LF-0,5%,1/16W,CHIP,CA',
 WATTAGE='1/16W',
 TOLERANCE='5%',
 MATERIAL='CHIP',
 VALUE='0',
 PRIM_FILE='./archive_libs/logical/q_res/chips/chips.prt';

PART_NAME
 R2984 'Q_RES_0402LF-10K,1%,1/16W,CHIPA':;

SECTION_NUMBER 1
 '@S9S_MB_2U_LIB.S9S_MB_2U(SCH_1):PAGE219_I25@PURE_QUANTA.Q_RES(CHIPS)':
 C_PATH='@s9s_mb_2u_lib.s9s_mb_2u(sch_1):page219_i25@pure_quanta.q_res(chips)',
 P_PATH='@s9s_mb_2u_lib.s9s_mb_2u(sch_1):page231_i25@pure_quanta.q_res(chips)',
 PATH='I25',
 DRAWING='@S9S_MB_2U_LIB.S9S_MB_2U(SCH_1):PAGE219',
 PHYS_PAGE='231',
 XY='(3875,-575)',
 ROT='0',
 VER='1',
 PACK_TYPE='0402LF',
 CDS_LIB='pure_quanta',
 CDS_PART_NAME='Q_RES_0402LF-10K,1%,1/16W,CHIPA',
 WATTAGE='1/16W',
 TOLERANCE='1%',
 MATERIAL='CHIP',
 VALUE='10K',
 PRIM_FILE='./archive_libs/logical/q_res/chips/chips.prt';

PART_NAME
 R2985 'Q_RES_0402LF-10K,1%,1/16W,CHIPA':;

SECTION_NUMBER 1
 '@S9S_MB_2U_LIB.S9S_MB_2U(SCH_1):PAGE219_I24@PURE_QUANTA.Q_RES(CHIPS)':
 C_PATH='@s9s_mb_2u_lib.s9s_mb_2u(sch_1):page219_i24@pure_quanta.q_res(chips)',
 P_PATH='@s9s_mb_2u_lib.s9s_mb_2u(sch_1):page231_i24@pure_quanta.q_res(chips)',
 PATH='I24',
 DRAWING='@S9S_MB_2U_LIB.S9S_MB_2U(SCH_1):PAGE219',
 PHYS_PAGE='231',
 XY='(3875,-625)',
 ROT='0',
 VER='1',
 PACK_TYPE='0402LF',
 CDS_LIB='pure_quanta',
 CDS_PART_NAME='Q_RES_0402LF-10K,1%,1/16W,CHIPA',
 WATTAGE='1/16W',
 TOLERANCE='1%',
 MATERIAL='CHIP',
 VALUE='10K',
 PRIM_FILE='./archive_libs/logical/q_res/chips/chips.prt';

PART_NAME
 R2986 'Q_RES_0402LF-0,5%,1/16W,EMPTY,A':;

SECTION_NUMBER 1
 '@S9S_MB_2U_LIB.S9S_MB_2U(SCH_1):PAGE222_I13@PURE_QUANTA.Q_RES(CHIPS)':
 C_PATH='@s9s_mb_2u_lib.s9s_mb_2u(sch_1):page222_i13@pure_quanta.q_res(chips)',
 P_PATH='@s9s_mb_2u_lib.s9s_mb_2u(sch_1):page234_i13@pure_quanta.q_res(chips)',
 PATH='I13',
 DRAWING='@S9S_MB_2U_LIB.S9S_MB_2U(SCH_1):PAGE222',
 PHYS_PAGE='234',
 XY='(-4875,5625)',
 ROT='0',
 VER='1',
 PACK_TYPE='0402LF',
 CDS_LIB='pure_quanta',
 CDS_PART_NAME='Q_RES_0402LF-0,5%,1/16W,EMPTY,A',
 WATTAGE='1/16W',
 TOLERANCE='5%',
 MATERIAL='EMPTY',
 VALUE='0',
 PRIM_FILE='./archive_libs/logical/q_res/chips/chips.prt';

PART_NAME
 R2987 'Q_RES_0402LF-0,5%,1/16W,EMPTY,A':;

SECTION_NUMBER 1
 '@S9S_MB_2U_LIB.S9S_MB_2U(SCH_1):PAGE222_I12@PURE_QUANTA.Q_RES(CHIPS)':
 C_PATH='@s9s_mb_2u_lib.s9s_mb_2u(sch_1):page222_i12@pure_quanta.q_res(chips)',
 P_PATH='@s9s_mb_2u_lib.s9s_mb_2u(sch_1):page234_i12@pure_quanta.q_res(chips)',
 PATH='I12',
 DRAWING='@S9S_MB_2U_LIB.S9S_MB_2U(SCH_1):PAGE222',
 PHYS_PAGE='234',
 XY='(-4875,5550)',
 ROT='0',
 VER='1',
 PACK_TYPE='0402LF',
 CDS_LIB='pure_quanta',
 CDS_PART_NAME='Q_RES_0402LF-0,5%,1/16W,EMPTY,A',
 WATTAGE='1/16W',
 TOLERANCE='5%',
 MATERIAL='EMPTY',
 VALUE='0',
 PRIM_FILE='./archive_libs/logical/q_res/chips/chips.prt';

PART_NAME
 R2990 'Q_RES_0402LF-33.2,1%,1/16W,CHIA':;

SECTION_NUMBER 1
 '@S9S_MB_2U_LIB.S9S_MB_2U(SCH_1):PAGE222_I26@PURE_QUANTA.Q_RES(CHIPS)':
 C_PATH='@s9s_mb_2u_lib.s9s_mb_2u(sch_1):page222_i26@pure_quanta.q_res(chips)',
 P_PATH='@s9s_mb_2u_lib.s9s_mb_2u(sch_1):page234_i26@pure_quanta.q_res(chips)',
 PATH='I26',
 DRAWING='@S9S_MB_2U_LIB.S9S_MB_2U(SCH_1):PAGE222',
 PHYS_PAGE='234',
 XY='(-2825,6075)',
 ROT='0',
 VER='1',
 PACK_TYPE='0402LF',
 CDS_LIB='pure_quanta',
 CDS_PART_NAME='Q_RES_0402LF-33.2,1%,1/16W,CHIA',
 WATTAGE='1/16W',
 TOLERANCE='1%',
 MATERIAL='CHIP',
 VALUE='33.2',
 PRIM_FILE='./archive_libs/logical/q_res/chips/chips.prt';

PART_NAME
 R2991 'Q_RES_0402LF-33.2,1%,1/16W,CHIA':;

SECTION_NUMBER 1
 '@S9S_MB_2U_LIB.S9S_MB_2U(SCH_1):PAGE222_I27@PURE_QUANTA.Q_RES(CHIPS)':
 C_PATH='@s9s_mb_2u_lib.s9s_mb_2u(sch_1):page222_i27@pure_quanta.q_res(chips)',
 P_PATH='@s9s_mb_2u_lib.s9s_mb_2u(sch_1):page234_i27@pure_quanta.q_res(chips)',
 PATH='I27',
 DRAWING='@S9S_MB_2U_LIB.S9S_MB_2U(SCH_1):PAGE222',
 PHYS_PAGE='234',
 XY='(-2825,5975)',
 ROT='0',
 VER='1',
 PACK_TYPE='0402LF',
 CDS_LIB='pure_quanta',
 CDS_PART_NAME='Q_RES_0402LF-33.2,1%,1/16W,CHIA',
 WATTAGE='1/16W',
 TOLERANCE='1%',
 MATERIAL='CHIP',
 VALUE='33.2',
 PRIM_FILE='./archive_libs/logical/q_res/chips/chips.prt';

PART_NAME
 R2992 'Q_RES_0402LF-0,5%,1/16W,CHIP,CA':;

SECTION_NUMBER 1
 '@S9S_MB_2U_LIB.S9S_MB_2U(SCH_1):PAGE222_I9@PURE_QUANTA.Q_RES(CHIPS)':
 C_PATH='@s9s_mb_2u_lib.s9s_mb_2u(sch_1):page222_i9@pure_quanta.q_res(chips)',
 P_PATH='@s9s_mb_2u_lib.s9s_mb_2u(sch_1):page234_i9@pure_quanta.q_res(chips)',
 PATH='I9',
 DRAWING='@S9S_MB_2U_LIB.S9S_MB_2U(SCH_1):PAGE222',
 PHYS_PAGE='234',
 XY='(-6175,6175)',
 ROT='0',
 VER='1',
 PACK_TYPE='0402LF',
 CDS_LIB='pure_quanta',
 CDS_PART_NAME='Q_RES_0402LF-0,5%,1/16W,CHIP,CA',
 WATTAGE='1/16W',
 TOLERANCE='5%',
 MATERIAL='CHIP',
 VALUE='0',
 PRIM_FILE='./archive_libs/logical/q_res/chips/chips.prt';

PART_NAME
 R2994 'Q_RES_0402LF-0,5%,1/16W,CHIP,CA':;

SECTION_NUMBER 1
 '@S9S_MB_2U_LIB.S9S_MB_2U(SCH_1):PAGE227_I58@PURE_QUANTA.Q_RES(CHIPS)':
 C_PATH='@s9s_mb_2u_lib.s9s_mb_2u(sch_1):page227_i58@pure_quanta.q_res(chips)',
 P_PATH='@s9s_mb_2u_lib.s9s_mb_2u(sch_1):page240_i58@pure_quanta.q_res(chips)',
 PATH='I58',
 DRAWING='@S9S_MB_2U_LIB.S9S_MB_2U(SCH_1):PAGE227',
 PHYS_PAGE='240',
 XY='(-7800,-725)',
 ROT='0',
 VER='1',
 PACK_TYPE='0402LF',
 CDS_LIB='pure_quanta',
 CDS_PART_NAME='Q_RES_0402LF-0,5%,1/16W,CHIP,CA',
 WATTAGE='1/16W',
 TOLERANCE='5%',
 MATERIAL='CHIP',
 VALUE='0',
 PRIM_FILE='./archive_libs/logical/q_res/chips/chips.prt';

PART_NAME
 R2995 'Q_RES_0402LF-33.2,1%,1/16W,CHIA':;

SECTION_NUMBER 1
 '@S9S_MB_2U_LIB.S9S_MB_2U(SCH_1):PAGE228_I228@PURE_QUANTA.Q_RES(CHIPS)':
 C_PATH='@s9s_mb_2u_lib.s9s_mb_2u(sch_1):page228_i228@pure_quanta.q_res(chips)',
 P_PATH='@s9s_mb_2u_lib.s9s_mb_2u(sch_1):page241_i228@pure_quanta.q_res(chips)',
 PATH='I228',
 DRAWING='@S9S_MB_2U_LIB.S9S_MB_2U(SCH_1):PAGE228',
 PHYS_PAGE='241',
 XY='(-300,3925)',
 ROT='0',
 VER='1',
 PACK_TYPE='0402LF',
 CDS_LIB='pure_quanta',
 CDS_PART_NAME='Q_RES_0402LF-33.2,1%,1/16W,CHIA',
 WATTAGE='1/16W',
 TOLERANCE='1%',
 MATERIAL='CHIP',
 VALUE='33.2',
 PRIM_FILE='./archive_libs/logical/q_res/chips/chips.prt';

PART_NAME
 R2996 'Q_RES_0402LF-33.2,1%,1/16W,CHIA':;

SECTION_NUMBER 1
 '@S9S_MB_2U_LIB.S9S_MB_2U(SCH_1):PAGE228_I229@PURE_QUANTA.Q_RES(CHIPS)':
 C_PATH='@s9s_mb_2u_lib.s9s_mb_2u(sch_1):page228_i229@pure_quanta.q_res(chips)',
 P_PATH='@s9s_mb_2u_lib.s9s_mb_2u(sch_1):page241_i229@pure_quanta.q_res(chips)',
 PATH='I229',
 DRAWING='@S9S_MB_2U_LIB.S9S_MB_2U(SCH_1):PAGE228',
 PHYS_PAGE='241',
 XY='(-300,3875)',
 ROT='0',
 VER='1',
 PACK_TYPE='0402LF',
 CDS_LIB='pure_quanta',
 CDS_PART_NAME='Q_RES_0402LF-33.2,1%,1/16W,CHIA',
 WATTAGE='1/16W',
 TOLERANCE='1%',
 MATERIAL='CHIP',
 VALUE='33.2',
 PRIM_FILE='./archive_libs/logical/q_res/chips/chips.prt';

PART_NAME
 R2999 'Q_RES_0402LF-2.2K,5%,1/16W,EMPA':;

SECTION_NUMBER 1
 '@S9S_MB_2U_LIB.S9S_MB_2U(SCH_1):PAGE228_I231@PURE_QUANTA.Q_RES(CHIPS)':
 C_PATH='@s9s_mb_2u_lib.s9s_mb_2u(sch_1):page228_i231@pure_quanta.q_res(chips)',
 P_PATH='@s9s_mb_2u_lib.s9s_mb_2u(sch_1):page241_i231@pure_quanta.q_res(chips)',
 PATH='I231',
 DRAWING='@S9S_MB_2U_LIB.S9S_MB_2U(SCH_1):PAGE228',
 PHYS_PAGE='241',
 XY='(5000,3700)',
 ROT='0',
 VER='1',
 PACK_TYPE='0402LF',
 CDS_LIB='pure_quanta',
 CDS_PART_NAME='Q_RES_0402LF-2.2K,5%,1/16W,EMPA',
 WATTAGE='1/16W',
 TOLERANCE='5%',
 MATERIAL='EMPTY',
 VALUE='2.2K',
 PRIM_FILE='./archive_libs/logical/q_res/chips/chips.prt';

PART_NAME
 R3004 'Q_RES_0402LF-2.2K,5%,1/16W,EMPA':;

SECTION_NUMBER 1
 '@S9S_MB_2U_LIB.S9S_MB_2U(SCH_1):PAGE228_I230@PURE_QUANTA.Q_RES(CHIPS)':
 C_PATH='@s9s_mb_2u_lib.s9s_mb_2u(sch_1):page228_i230@pure_quanta.q_res(chips)',
 P_PATH='@s9s_mb_2u_lib.s9s_mb_2u(sch_1):page241_i230@pure_quanta.q_res(chips)',
 PATH='I230',
 DRAWING='@S9S_MB_2U_LIB.S9S_MB_2U(SCH_1):PAGE228',
 PHYS_PAGE='241',
 XY='(5000,3650)',
 ROT='0',
 VER='1',
 PACK_TYPE='0402LF',
 CDS_LIB='pure_quanta',
 CDS_PART_NAME='Q_RES_0402LF-2.2K,5%,1/16W,EMPA',
 WATTAGE='1/16W',
 TOLERANCE='5%',
 MATERIAL='EMPTY',
 VALUE='2.2K',
 PRIM_FILE='./archive_libs/logical/q_res/chips/chips.prt';

PART_NAME
 R3005 'Q_RES_0402LF-18K,1%,1/16W,CHIPA':;

SECTION_NUMBER 1
 '@S9S_MB_2U_LIB.S9S_MB_2U(SCH_1):PAGE239_I168@PURE_QUANTA.Q_RES(CHIPS)':
 C_PATH='@s9s_mb_2u_lib.s9s_mb_2u(sch_1):page239_i168@pure_quanta.q_res(chips)',
 P_PATH='@s9s_mb_2u_lib.s9s_mb_2u(sch_1):page250_i168@pure_quanta.q_res(chips)',
 PATH='I168',
 DRAWING='@S9S_MB_2U_LIB.S9S_MB_2U(SCH_1):PAGE239',
 PHYS_PAGE='250',
 XY='(-1000,2950)',
 ROT='0',
 VER='2',
 PACK_TYPE='0402LF',
 CDS_LIB='pure_quanta',
 CDS_PART_NAME='Q_RES_0402LF-18K,1%,1/16W,CHIPA',
 WATTAGE='1/16W',
 TOLERANCE='1%',
 MATERIAL='CHIP',
 VALUE='18K',
 PRIM_FILE='./archive_libs/logical/q_res/chips/chips.prt';

PART_NAME
 R3023 'Q_RES_0402LF-0,5%,1/16W,CHIP,CA':;

SECTION_NUMBER 1
 '@S9S_MB_2U_LIB.S9S_MB_2U(SCH_1):PAGE117_I10@PURE_QUANTA.Q_RES(CHIPS)':
 C_PATH='@s9s_mb_2u_lib.s9s_mb_2u(sch_1):page117_i10@pure_quanta.q_res(chips)',
 P_PATH='@s9s_mb_2u_lib.s9s_mb_2u(sch_1):page117_i10@pure_quanta.q_res(chips)',
 PATH='I10',
 DRAWING='@S9S_MB_2U_LIB.S9S_MB_2U(SCH_1):PAGE117',
 PHYS_PAGE='117',
 XY='(-700,3350)',
 ROT='0',
 VER='1',
 PACK_TYPE='0402LF',
 CDS_LIB='pure_quanta',
 CDS_PART_NAME='Q_RES_0402LF-0,5%,1/16W,CHIP,CA',
 WATTAGE='1/16W',
 TOLERANCE='5%',
 MATERIAL='CHIP',
 VALUE='0',
 PRIM_FILE='./archive_libs/logical/q_res/chips/chips.prt';

PART_NAME
 R3024 'Q_RES_0402LF-240,1%,1/16W,EMPTA':;

SECTION_NUMBER 1
 '@S9S_MB_2U_LIB.S9S_MB_2U(SCH_1):PAGE119_I172@PURE_QUANTA.Q_RES(CHIPS)':
 C_PATH='@s9s_mb_2u_lib.s9s_mb_2u(sch_1):page119_i172@pure_quanta.q_res(chips)',
 P_PATH='@s9s_mb_2u_lib.s9s_mb_2u(sch_1):page119_i172@pure_quanta.q_res(chips)',
 PATH='I172',
 DRAWING='@S9S_MB_2U_LIB.S9S_MB_2U(SCH_1):PAGE119',
 PHYS_PAGE='119',
 XY='(250,125)',
 ROT='0',
 VER='1',
 PACK_TYPE='0402LF',
 CDS_LIB='pure_quanta',
 CDS_PART_NAME='Q_RES_0402LF-240,1%,1/16W,EMPTA',
 WATTAGE='1/16W',
 TOLERANCE='1%',
 MATERIAL='EMPTY',
 VALUE='240',
 PRIM_FILE='./archive_libs/logical/q_res/chips/chips.prt';

PART_NAME
 R3025 'Q_RES_0402LF-1K,1%,1/16W,EMPTYA':;

SECTION_NUMBER 1
 '@S9S_MB_2U_LIB.S9S_MB_2U(SCH_1):PAGE137_I102@PURE_QUANTA.Q_RES(CHIPS)':
 C_PATH='@s9s_mb_2u_lib.s9s_mb_2u(sch_1):page137_i102@pure_quanta.q_res(chips)',
 P_PATH='@s9s_mb_2u_lib.s9s_mb_2u(sch_1):page134_i102@pure_quanta.q_res(chips)',
 PATH='I102',
 DRAWING='@S9S_MB_2U_LIB.S9S_MB_2U(SCH_1):PAGE137',
 PHYS_PAGE='134',
 XY='(-8175,-1775)',
 ROT='2',
 VER='2',
 PACK_TYPE='0402LF',
 CDS_LIB='pure_quanta',
 CDS_PART_NAME='Q_RES_0402LF-1K,1%,1/16W,EMPTYA',
 WATTAGE='1/16W',
 TOLERANCE='1%',
 MATERIAL='EMPTY',
 VALUE='1K',
 PRIM_FILE='./archive_libs/logical/q_res/chips/chips.prt';

PART_NAME
 R3026 'Q_RES_0402LF-1K,1%,1/16W,CHIP,A':;

SECTION_NUMBER 1
 '@S9S_MB_2U_LIB.S9S_MB_2U(SCH_1):PAGE137_I106@PURE_QUANTA.Q_RES(CHIPS)':
 C_PATH='@s9s_mb_2u_lib.s9s_mb_2u(sch_1):page137_i106@pure_quanta.q_res(chips)',
 P_PATH='@s9s_mb_2u_lib.s9s_mb_2u(sch_1):page134_i106@pure_quanta.q_res(chips)',
 PATH='I106',
 DRAWING='@S9S_MB_2U_LIB.S9S_MB_2U(SCH_1):PAGE137',
 PHYS_PAGE='134',
 XY='(-7850,-2950)',
 ROT='0',
 VER='2',
 PACK_TYPE='0402LF',
 CDS_LIB='pure_quanta',
 CDS_PART_NAME='Q_RES_0402LF-1K,1%,1/16W,CHIP,A',
 WATTAGE='1/16W',
 TOLERANCE='1%',
 MATERIAL='CHIP',
 VALUE='1K',
 PRIM_FILE='./archive_libs/logical/q_res/chips/chips.prt';

PART_NAME
 R3027 'Q_RES_0402LF-1K,1%,1/16W,CHIP,A':;

SECTION_NUMBER 1
 '@S9S_MB_2U_LIB.S9S_MB_2U(SCH_1):PAGE137_I105@PURE_QUANTA.Q_RES(CHIPS)':
 C_PATH='@s9s_mb_2u_lib.s9s_mb_2u(sch_1):page137_i105@pure_quanta.q_res(chips)',
 P_PATH='@s9s_mb_2u_lib.s9s_mb_2u(sch_1):page134_i105@pure_quanta.q_res(chips)',
 PATH='I105',
 DRAWING='@S9S_MB_2U_LIB.S9S_MB_2U(SCH_1):PAGE137',
 PHYS_PAGE='134',
 XY='(-7625,-2950)',
 ROT='0',
 VER='2',
 PACK_TYPE='0402LF',
 CDS_LIB='pure_quanta',
 CDS_PART_NAME='Q_RES_0402LF-1K,1%,1/16W,CHIP,A',
 WATTAGE='1/16W',
 TOLERANCE='1%',
 MATERIAL='CHIP',
 VALUE='1K',
 PRIM_FILE='./archive_libs/logical/q_res/chips/chips.prt';

PART_NAME
 R3028 'Q_RES_0402LF-100K,1%,1/16W,EMPA':;

SECTION_NUMBER 1
 '@S9S_MB_2U_LIB.S9S_MB_2U(SCH_1):PAGE145_I139@PURE_QUANTA.Q_RES(CHIPS)':
 C_PATH='@s9s_mb_2u_lib.s9s_mb_2u(sch_1):page145_i139@pure_quanta.q_res(chips)',
 P_PATH='@s9s_mb_2u_lib.s9s_mb_2u(sch_1):page148_i139@pure_quanta.q_res(chips)',
 PATH='I139',
 DRAWING='@S9S_MB_2U_LIB.S9S_MB_2U(SCH_1):PAGE145',
 PHYS_PAGE='148',
 XY='(-4650,2825)',
 ROT='0',
 VER='2',
 PACK_TYPE='0402LF',
 CDS_LIB='pure_quanta',
 CDS_PART_NAME='Q_RES_0402LF-100K,1%,1/16W,EMPA',
 WATTAGE='1/16W',
 TOLERANCE='1%',
 MATERIAL='EMPTY',
 VALUE='100K',
 PRIM_FILE='./archive_libs/logical/q_res/chips/chips.prt';

PART_NAME
 R3029 'Q_RES_0402LF-4.7K,5%,1/16W,CHIA':;

SECTION_NUMBER 1
 '@S9S_MB_2U_LIB.S9S_MB_2U(SCH_1):PAGE145_I144@PURE_QUANTA.Q_RES(CHIPS)':
 C_PATH='@s9s_mb_2u_lib.s9s_mb_2u(sch_1):page145_i144@pure_quanta.q_res(chips)',
 P_PATH='@s9s_mb_2u_lib.s9s_mb_2u(sch_1):page148_i144@pure_quanta.q_res(chips)',
 PATH='I144',
 DRAWING='@S9S_MB_2U_LIB.S9S_MB_2U(SCH_1):PAGE145',
 PHYS_PAGE='148',
 XY='(-3425,3550)',
 ROT='0',
 VER='2',
 PACK_TYPE='0402LF',
 CDS_LIB='pure_quanta',
 CDS_PART_NAME='Q_RES_0402LF-4.7K,5%,1/16W,CHIA',
 WATTAGE='1/16W',
 TOLERANCE='5%',
 MATERIAL='CHIP',
 VALUE='4.7K',
 PRIM_FILE='./archive_libs/logical/q_res/chips/chips.prt';

PART_NAME
 R3030 'Q_RES_0402LF-4.7K,5%,1/16W,CHIA':;

SECTION_NUMBER 1
 '@S9S_MB_2U_LIB.S9S_MB_2U(SCH_1):PAGE145_I146@PURE_QUANTA.Q_RES(CHIPS)':
 C_PATH='@s9s_mb_2u_lib.s9s_mb_2u(sch_1):page145_i146@pure_quanta.q_res(chips)',
 P_PATH='@s9s_mb_2u_lib.s9s_mb_2u(sch_1):page148_i146@pure_quanta.q_res(chips)',
 PATH='I146',
 DRAWING='@S9S_MB_2U_LIB.S9S_MB_2U(SCH_1):PAGE145',
 PHYS_PAGE='148',
 XY='(-2500,3800)',
 ROT='0',
 VER='2',
 PACK_TYPE='0402LF',
 CDS_LIB='pure_quanta',
 CDS_PART_NAME='Q_RES_0402LF-4.7K,5%,1/16W,CHIA',
 WATTAGE='1/16W',
 TOLERANCE='5%',
 MATERIAL='CHIP',
 VALUE='4.7K',
 PRIM_FILE='./archive_libs/logical/q_res/chips/chips.prt';

PART_NAME
 R3032 'Q_RES_0402LF-100K,1%,1/16W,EMPA':;

SECTION_NUMBER 1
 '@S9S_MB_2U_LIB.S9S_MB_2U(SCH_1):PAGE145_I134@PURE_QUANTA.Q_RES(CHIPS)':
 C_PATH='@s9s_mb_2u_lib.s9s_mb_2u(sch_1):page145_i134@pure_quanta.q_res(chips)',
 P_PATH='@s9s_mb_2u_lib.s9s_mb_2u(sch_1):page148_i134@pure_quanta.q_res(chips)',
 PATH='I134',
 DRAWING='@S9S_MB_2U_LIB.S9S_MB_2U(SCH_1):PAGE145',
 PHYS_PAGE='148',
 XY='(-100,4525)',
 ROT='0',
 VER='2',
 PACK_TYPE='0402LF',
 CDS_LIB='pure_quanta',
 CDS_PART_NAME='Q_RES_0402LF-100K,1%,1/16W,EMPA',
 WATTAGE='1/16W',
 TOLERANCE='1%',
 MATERIAL='EMPTY',
 VALUE='100K',
 PRIM_FILE='./archive_libs/logical/q_res/chips/chips.prt';

PART_NAME
 R3033 'Q_RES_0402LF-0,5%,1/16W,CHIP,CA':;

SECTION_NUMBER 1
 '@S9S_MB_2U_LIB.S9S_MB_2U(SCH_1):PAGE140_I170@PURE_QUANTA.Q_RES(CHIPS)':
 C_PATH='@s9s_mb_2u_lib.s9s_mb_2u(sch_1):page140_i170@pure_quanta.q_res(chips)',
 P_PATH='@s9s_mb_2u_lib.s9s_mb_2u(sch_1):page151_i170@pure_quanta.q_res(chips)',
 PATH='I170',
 DRAWING='@S9S_MB_2U_LIB.S9S_MB_2U(SCH_1):PAGE140',
 PHYS_PAGE='151',
 XY='(-1575,-1850)',
 ROT='0',
 VER='1',
 PACK_TYPE='0402LF',
 CDS_LIB='pure_quanta',
 CDS_PART_NAME='Q_RES_0402LF-0,5%,1/16W,CHIP,CA',
 WATTAGE='1/16W',
 TOLERANCE='5%',
 MATERIAL='CHIP',
 VALUE='0',
 PRIM_FILE='./archive_libs/logical/q_res/chips/chips.prt';

PART_NAME
 R3034 'Q_RES_0402LF-4.7K,5%,1/16W,CHIA':;

SECTION_NUMBER 1
 '@S9S_MB_2U_LIB.S9S_MB_2U(SCH_1):PAGE145_I129@PURE_QUANTA.Q_RES(CHIPS)':
 C_PATH='@s9s_mb_2u_lib.s9s_mb_2u(sch_1):page145_i129@pure_quanta.q_res(chips)',
 P_PATH='@s9s_mb_2u_lib.s9s_mb_2u(sch_1):page148_i129@pure_quanta.q_res(chips)',
 PATH='I129',
 DRAWING='@S9S_MB_2U_LIB.S9S_MB_2U(SCH_1):PAGE145',
 PHYS_PAGE='148',
 XY='(1125,5250)',
 ROT='0',
 VER='2',
 PACK_TYPE='0402LF',
 CDS_LIB='pure_quanta',
 CDS_PART_NAME='Q_RES_0402LF-4.7K,5%,1/16W,CHIA',
 WATTAGE='1/16W',
 TOLERANCE='5%',
 MATERIAL='CHIP',
 VALUE='4.7K',
 PRIM_FILE='./archive_libs/logical/q_res/chips/chips.prt';

PART_NAME
 R3035 'Q_RES_0402LF-4.7K,5%,1/16W,CHIA':;

SECTION_NUMBER 1
 '@S9S_MB_2U_LIB.S9S_MB_2U(SCH_1):PAGE145_I127@PURE_QUANTA.Q_RES(CHIPS)':
 C_PATH='@s9s_mb_2u_lib.s9s_mb_2u(sch_1):page145_i127@pure_quanta.q_res(chips)',
 P_PATH='@s9s_mb_2u_lib.s9s_mb_2u(sch_1):page148_i127@pure_quanta.q_res(chips)',
 PATH='I127',
 DRAWING='@S9S_MB_2U_LIB.S9S_MB_2U(SCH_1):PAGE145',
 PHYS_PAGE='148',
 XY='(2050,5500)',
 ROT='0',
 VER='2',
 PACK_TYPE='0402LF',
 CDS_LIB='pure_quanta',
 CDS_PART_NAME='Q_RES_0402LF-4.7K,5%,1/16W,CHIA',
 WATTAGE='1/16W',
 TOLERANCE='5%',
 MATERIAL='CHIP',
 VALUE='4.7K',
 PRIM_FILE='./archive_libs/logical/q_res/chips/chips.prt';

PART_NAME
 R3036 'Q_RES_0402LF-33.2,1%,1/16W,CHIA':;

SECTION_NUMBER 1
 '@S9S_MB_2U_LIB.S9S_MB_2U(SCH_1):PAGE140_I197@PURE_QUANTA.Q_RES(CHIPS)':
 C_PATH='@s9s_mb_2u_lib.s9s_mb_2u(sch_1):page140_i197@pure_quanta.q_res(chips)',
 P_PATH='@s9s_mb_2u_lib.s9s_mb_2u(sch_1):page151_i197@pure_quanta.q_res(chips)',
 PATH='I197',
 DRAWING='@S9S_MB_2U_LIB.S9S_MB_2U(SCH_1):PAGE140',
 PHYS_PAGE='151',
 XY='(650,-1900)',
 ROT='0',
 VER='1',
 PACK_TYPE='0402LF',
 LOCATION='R3036',
 CDS_LIB='pure_quanta',
 CDS_PART_NAME='Q_RES_0402LF-33.2,1%,1/16W,CHIA',
 WATTAGE='1/16W',
 TOLERANCE='1%',
 MATERIAL='CHIP',
 VALUE='33.2',
 PRIM_FILE='./archive_libs/logical/q_res/chips/chips.prt';

PART_NAME
 R3037 'Q_RES_0402LF-1K,1%,1/16W,EMPTYA':;

SECTION_NUMBER 1
 '@S9S_MB_2U_LIB.S9S_MB_2U(SCH_1):PAGE154_I134@PURE_QUANTA.Q_RES(CHIPS)':
 C_PATH='@s9s_mb_2u_lib.s9s_mb_2u(sch_1):page154_i134@pure_quanta.q_res(chips)',
 P_PATH='@s9s_mb_2u_lib.s9s_mb_2u(sch_1):page158_i134@pure_quanta.q_res(chips)',
 PATH='I134',
 DRAWING='@S9S_MB_2U_LIB.S9S_MB_2U(SCH_1):PAGE154',
 PHYS_PAGE='158',
 XY='(-4575,9600)',
 ROT='0',
 VER='2',
 PACK_TYPE='0402LF',
 CDS_LIB='pure_quanta',
 CDS_PART_NAME='Q_RES_0402LF-1K,1%,1/16W,EMPTYA',
 WATTAGE='1/16W',
 TOLERANCE='1%',
 MATERIAL='EMPTY',
 VALUE='1K',
 PRIM_FILE='./archive_libs/logical/q_res/chips/chips.prt';

PART_NAME
 R3038 'Q_RES_0402LF-5.11K,1%,1/16W,CHA':;

SECTION_NUMBER 1
 '@S9S_MB_2U_LIB.S9S_MB_2U(SCH_1):PAGE188_I57@PURE_QUANTA.Q_RES(CHIPS)':
 C_PATH='@s9s_mb_2u_lib.s9s_mb_2u(sch_1):page188_i57@pure_quanta.q_res(chips)',
 P_PATH='@s9s_mb_2u_lib.s9s_mb_2u(sch_1):page200_i57@pure_quanta.q_res(chips)',
 PATH='I57',
 DRAWING='@S9S_MB_2U_LIB.S9S_MB_2U(SCH_1):PAGE188',
 PHYS_PAGE='200',
 XY='(-2925,1625)',
 ROT='0',
 VER='2',
 PACK_TYPE='0402LF',
 CDS_LIB='pure_quanta',
 CDS_PART_NAME='Q_RES_0402LF-5.11K,1%,1/16W,CHA',
 WATTAGE='1/16W',
 TOLERANCE='1%',
 MATERIAL='CHIP',
 VALUE='5.11K',
 PRIM_FILE='./archive_libs/logical/q_res/chips/chips.prt';

PART_NAME
 R3039 'Q_RES_0402LF-1K,1%,1/16W,CHIP,A':;

SECTION_NUMBER 1
 '@S9S_MB_2U_LIB.S9S_MB_2U(SCH_1):PAGE189_I132@PURE_QUANTA.Q_RES(CHIPS)':
 C_PATH='@s9s_mb_2u_lib.s9s_mb_2u(sch_1):page189_i132@pure_quanta.q_res(chips)',
 P_PATH='@s9s_mb_2u_lib.s9s_mb_2u(sch_1):page201_i132@pure_quanta.q_res(chips)',
 PATH='I132',
 DRAWING='@S9S_MB_2U_LIB.S9S_MB_2U(SCH_1):PAGE189',
 PHYS_PAGE='201',
 XY='(-350,3450)',
 ROT='0',
 VER='1',
 PACK_TYPE='0402LF',
 CDS_LIB='pure_quanta',
 CDS_PART_NAME='Q_RES_0402LF-1K,1%,1/16W,CHIP,A',
 WATTAGE='1/16W',
 TOLERANCE='1%',
 MATERIAL='CHIP',
 VALUE='1K',
 PRIM_FILE='./archive_libs/logical/q_res/chips/chips.prt';

PART_NAME
 R3040 'Q_RES_0402LF-1K,1%,1/16W,CHIP,A':;

SECTION_NUMBER 1
 '@S9S_MB_2U_LIB.S9S_MB_2U(SCH_1):PAGE192_I1@PURE_QUANTA.Q_RES(CHIPS)':
 C_PATH='@s9s_mb_2u_lib.s9s_mb_2u(sch_1):page192_i1@pure_quanta.q_res(chips)',
 P_PATH='@s9s_mb_2u_lib.s9s_mb_2u(sch_1):page204_i1@pure_quanta.q_res(chips)',
 PATH='I1',
 DRAWING='@S9S_MB_2U_LIB.S9S_MB_2U(SCH_1):PAGE192',
 PHYS_PAGE='204',
 XY='(1150,3150)',
 ROT='0',
 VER='1',
 PACK_TYPE='0402LF',
 CDS_LIB='pure_quanta',
 CDS_PART_NAME='Q_RES_0402LF-1K,1%,1/16W,CHIP,A',
 WATTAGE='1/16W',
 TOLERANCE='1%',
 MATERIAL='CHIP',
 VALUE='1K',
 PRIM_FILE='./archive_libs/logical/q_res/chips/chips.prt';

PART_NAME
 R3041 'Q_RES_0402LF-10K,1%,1/16W,CHIPA':;

SECTION_NUMBER 1
 '@S9S_MB_2U_LIB.S9S_MB_2U(SCH_1):PAGE192_I6@PURE_QUANTA.Q_RES(CHIPS)':
 C_PATH='@s9s_mb_2u_lib.s9s_mb_2u(sch_1):page192_i6@pure_quanta.q_res(chips)',
 P_PATH='@s9s_mb_2u_lib.s9s_mb_2u(sch_1):page204_i6@pure_quanta.q_res(chips)',
 PATH='I6',
 DRAWING='@S9S_MB_2U_LIB.S9S_MB_2U(SCH_1):PAGE192',
 PHYS_PAGE='204',
 XY='(1150,2875)',
 ROT='0',
 VER='1',
 PACK_TYPE='0402LF',
 CDS_LIB='pure_quanta',
 CDS_PART_NAME='Q_RES_0402LF-10K,1%,1/16W,CHIPA',
 WATTAGE='1/16W',
 TOLERANCE='1%',
 MATERIAL='CHIP',
 VALUE='10K',
 PRIM_FILE='./archive_libs/logical/q_res/chips/chips.prt';

PART_NAME
 R3042 'Q_RES_0402LF-10K,1%,1/16W,EMPTA':;

SECTION_NUMBER 1
 '@S9S_MB_2U_LIB.S9S_MB_2U(SCH_1):PAGE192_I18@PURE_QUANTA.Q_RES(CHIPS)':
 C_PATH='@s9s_mb_2u_lib.s9s_mb_2u(sch_1):page192_i18@pure_quanta.q_res(chips)',
 P_PATH='@s9s_mb_2u_lib.s9s_mb_2u(sch_1):page204_i18@pure_quanta.q_res(chips)',
 PATH='I18',
 DRAWING='@S9S_MB_2U_LIB.S9S_MB_2U(SCH_1):PAGE192',
 PHYS_PAGE='204',
 XY='(1200,1175)',
 ROT='0',
 VER='1',
 PACK_TYPE='0402LF',
 CDS_LIB='pure_quanta',
 CDS_PART_NAME='Q_RES_0402LF-10K,1%,1/16W,EMPTA',
 WATTAGE='1/16W',
 TOLERANCE='1%',
 MATERIAL='EMPTY',
 VALUE='10K',
 PRIM_FILE='./archive_libs/logical/q_res/chips/chips.prt';

PART_NAME
 R3043 'Q_RES_0402LF-33.2,1%,1/16W,CHIA':;

SECTION_NUMBER 1
 '@S9S_MB_2U_LIB.S9S_MB_2U(SCH_1):PAGE314_I111@PURE_QUANTA.Q_RES(CHIPS)':
 C_PATH='@s9s_mb_2u_lib.s9s_mb_2u(sch_1):page314_i111@pure_quanta.q_res(chips)',
 P_PATH='@s9s_mb_2u_lib.s9s_mb_2u(sch_1):page213_i111@pure_quanta.q_res(chips)',
 PATH='I111',
 DRAWING='@S9S_MB_2U_LIB.S9S_MB_2U(SCH_1):PAGE314',
 PHYS_PAGE='213',
 XY='(2725,-650)',
 ROT='0',
 VER='1',
 PACK_TYPE='0402LF',
 LOCATION='R3043',
 CDS_LIB='pure_quanta',
 CDS_PART_NAME='Q_RES_0402LF-33.2,1%,1/16W,CHIA',
 WATTAGE='1/16W',
 TOLERANCE='1%',
 MATERIAL='CHIP',
 VALUE='33.2',
 PRIM_FILE='./archive_libs/logical/q_res/chips/chips.prt';

PART_NAME
 R3045 'Q_RES_0402LF-0,5%,1/16W,CHIP,CA':;

SECTION_NUMBER 1
 '@S9S_MB_2U_LIB.S9S_MB_2U(SCH_1):PAGE312_I164@PURE_QUANTA.Q_RES(CHIPS)':
 C_PATH='@s9s_mb_2u_lib.s9s_mb_2u(sch_1):page312_i164@pure_quanta.q_res(chips)',
 P_PATH='@s9s_mb_2u_lib.s9s_mb_2u(sch_1):page215_i164@pure_quanta.q_res(chips)',
 PATH='I164',
 DRAWING='@S9S_MB_2U_LIB.S9S_MB_2U(SCH_1):PAGE312',
 PHYS_PAGE='215',
 XY='(-575,-450)',
 ROT='0',
 VER='1',
 PACK_TYPE='0402LF',
 CDS_LIB='pure_quanta',
 CDS_PART_NAME='Q_RES_0402LF-0,5%,1/16W,CHIP,CA',
 WATTAGE='1/16W',
 TOLERANCE='5%',
 MATERIAL='CHIP',
 VALUE='0',
 PRIM_FILE='./archive_libs/logical/q_res/chips/chips.prt';

PART_NAME
 R3046 'Q_RES_0402LF-0,5%,1/16W,CHIP,CA':;

SECTION_NUMBER 1
 '@S9S_MB_2U_LIB.S9S_MB_2U(SCH_1):PAGE312_I165@PURE_QUANTA.Q_RES(CHIPS)':
 C_PATH='@s9s_mb_2u_lib.s9s_mb_2u(sch_1):page312_i165@pure_quanta.q_res(chips)',
 P_PATH='@s9s_mb_2u_lib.s9s_mb_2u(sch_1):page215_i165@pure_quanta.q_res(chips)',
 PATH='I165',
 DRAWING='@S9S_MB_2U_LIB.S9S_MB_2U(SCH_1):PAGE312',
 PHYS_PAGE='215',
 XY='(-575,-675)',
 ROT='0',
 VER='1',
 PACK_TYPE='0402LF',
 CDS_LIB='pure_quanta',
 CDS_PART_NAME='Q_RES_0402LF-0,5%,1/16W,CHIP,CA',
 WATTAGE='1/16W',
 TOLERANCE='5%',
 MATERIAL='CHIP',
 VALUE='0',
 PRIM_FILE='./archive_libs/logical/q_res/chips/chips.prt';

PART_NAME
 R3047 'Q_RES_0402LF-0,5%,1/16W,CHIP,CA':;

SECTION_NUMBER 1
 '@S9S_MB_2U_LIB.S9S_MB_2U(SCH_1):PAGE313_I85@PURE_QUANTA.Q_RES(CHIPS)':
 C_PATH='@s9s_mb_2u_lib.s9s_mb_2u(sch_1):page313_i85@pure_quanta.q_res(chips)',
 P_PATH='@s9s_mb_2u_lib.s9s_mb_2u(sch_1):page214_i85@pure_quanta.q_res(chips)',
 PATH='I85',
 DRAWING='@S9S_MB_2U_LIB.S9S_MB_2U(SCH_1):PAGE313',
 PHYS_PAGE='214',
 XY='(2650,-1800)',
 ROT='0',
 VER='1',
 PACK_TYPE='0402LF',
 CDS_LIB='pure_quanta',
 CDS_PART_NAME='Q_RES_0402LF-0,5%,1/16W,CHIP,CA',
 WATTAGE='1/16W',
 TOLERANCE='5%',
 MATERIAL='CHIP',
 VALUE='0',
 PRIM_FILE='./archive_libs/logical/q_res/chips/chips.prt';

PART_NAME
 R3048 'Q_RES_0402LF-0,5%,1/16W,CHIP,CA':;

SECTION_NUMBER 1
 '@S9S_MB_2U_LIB.S9S_MB_2U(SCH_1):PAGE313_I86@PURE_QUANTA.Q_RES(CHIPS)':
 C_PATH='@s9s_mb_2u_lib.s9s_mb_2u(sch_1):page313_i86@pure_quanta.q_res(chips)',
 P_PATH='@s9s_mb_2u_lib.s9s_mb_2u(sch_1):page214_i86@pure_quanta.q_res(chips)',
 PATH='I86',
 DRAWING='@S9S_MB_2U_LIB.S9S_MB_2U(SCH_1):PAGE313',
 PHYS_PAGE='214',
 XY='(2650,-1975)',
 ROT='0',
 VER='1',
 PACK_TYPE='0402LF',
 CDS_LIB='pure_quanta',
 CDS_PART_NAME='Q_RES_0402LF-0,5%,1/16W,CHIP,CA',
 WATTAGE='1/16W',
 TOLERANCE='5%',
 MATERIAL='CHIP',
 VALUE='0',
 PRIM_FILE='./archive_libs/logical/q_res/chips/chips.prt';

PART_NAME
 R3049 'Q_RES_0402LF-0,5%,1/16W,CHIP,CA':;

SECTION_NUMBER 1
 '@S9S_MB_2U_LIB.S9S_MB_2U(SCH_1):PAGE312_I176@PURE_QUANTA.Q_RES(CHIPS)':
 C_PATH='@s9s_mb_2u_lib.s9s_mb_2u(sch_1):page312_i176@pure_quanta.q_res(chips)',
 P_PATH='@s9s_mb_2u_lib.s9s_mb_2u(sch_1):page215_i176@pure_quanta.q_res(chips)',
 PATH='I176',
 DRAWING='@S9S_MB_2U_LIB.S9S_MB_2U(SCH_1):PAGE312',
 PHYS_PAGE='215',
 XY='(-575,-1225)',
 ROT='0',
 VER='1',
 PACK_TYPE='0402LF',
 CDS_LIB='pure_quanta',
 CDS_PART_NAME='Q_RES_0402LF-0,5%,1/16W,CHIP,CA',
 WATTAGE='1/16W',
 TOLERANCE='5%',
 MATERIAL='CHIP',
 VALUE='0',
 PRIM_FILE='./archive_libs/logical/q_res/chips/chips.prt';

PART_NAME
 R3050 'Q_RES_0402LF-33.2,1%,1/16W,CHIA':;

SECTION_NUMBER 1
 '@S9S_MB_2U_LIB.S9S_MB_2U(SCH_1):PAGE212_I129@PURE_QUANTA.Q_RES(CHIPS)':
 C_PATH='@s9s_mb_2u_lib.s9s_mb_2u(sch_1):page212_i129@pure_quanta.q_res(chips)',
 P_PATH='@s9s_mb_2u_lib.s9s_mb_2u(sch_1):page223_i129@pure_quanta.q_res(chips)',
 PATH='I129',
 DRAWING='@S9S_MB_2U_LIB.S9S_MB_2U(SCH_1):PAGE212',
 PHYS_PAGE='223',
 XY='(-2800,2075)',
 ROT='0',
 VER='1',
 PACK_TYPE='0402LF',
 CDS_LIB='pure_quanta',
 CDS_PART_NAME='Q_RES_0402LF-33.2,1%,1/16W,CHIA',
 WATTAGE='1/16W',
 TOLERANCE='1%',
 MATERIAL='CHIP',
 VALUE='33.2',
 PRIM_FILE='./archive_libs/logical/q_res/chips/chips.prt';

PART_NAME
 R3051 'Q_RES_0402LF-0,5%,1/16W,CHIP,CA':;

SECTION_NUMBER 1
 '@S9S_MB_2U_LIB.S9S_MB_2U(SCH_1):PAGE215_I2@PURE_QUANTA.Q_RES(CHIPS)':
 C_PATH='@s9s_mb_2u_lib.s9s_mb_2u(sch_1):page215_i2@pure_quanta.q_res(chips)',
 P_PATH='@s9s_mb_2u_lib.s9s_mb_2u(sch_1):page228_i2@pure_quanta.q_res(chips)',
 PATH='I2',
 DRAWING='@S9S_MB_2U_LIB.S9S_MB_2U(SCH_1):PAGE215',
 PHYS_PAGE='228',
 XY='(-1400,2150)',
 ROT='0',
 VER='1',
 PACK_TYPE='0402LF',
 CDS_LIB='pure_quanta',
 CDS_PART_NAME='Q_RES_0402LF-0,5%,1/16W,CHIP,CA',
 WATTAGE='1/16W',
 TOLERANCE='5%',
 MATERIAL='CHIP',
 VALUE='0',
 PRIM_FILE='./archive_libs/logical/q_res/chips/chips.prt';

PART_NAME
 R3052 'Q_RES_0402LF-33.2,1%,1/16W,CHIA':;

SECTION_NUMBER 1
 '@S9S_MB_2U_LIB.S9S_MB_2U(SCH_1):PAGE215_I13@PURE_QUANTA.Q_RES(CHIPS)':
 C_PATH='@s9s_mb_2u_lib.s9s_mb_2u(sch_1):page215_i13@pure_quanta.q_res(chips)',
 P_PATH='@s9s_mb_2u_lib.s9s_mb_2u(sch_1):page228_i13@pure_quanta.q_res(chips)',
 PATH='I13',
 DRAWING='@S9S_MB_2U_LIB.S9S_MB_2U(SCH_1):PAGE215',
 PHYS_PAGE='228',
 XY='(-1400,1925)',
 ROT='0',
 VER='1',
 PACK_TYPE='0402LF',
 CDS_LIB='pure_quanta',
 CDS_PART_NAME='Q_RES_0402LF-33.2,1%,1/16W,CHIA',
 WATTAGE='1/16W',
 TOLERANCE='1%',
 MATERIAL='CHIP',
 VALUE='33.2',
 PRIM_FILE='./archive_libs/logical/q_res/chips/chips.prt';

PART_NAME
 R3053 'Q_RES_0402LF-33.2,1%,1/16W,CHIA':;

SECTION_NUMBER 1
 '@S9S_MB_2U_LIB.S9S_MB_2U(SCH_1):PAGE215_I12@PURE_QUANTA.Q_RES(CHIPS)':
 C_PATH='@s9s_mb_2u_lib.s9s_mb_2u(sch_1):page215_i12@pure_quanta.q_res(chips)',
 P_PATH='@s9s_mb_2u_lib.s9s_mb_2u(sch_1):page228_i12@pure_quanta.q_res(chips)',
 PATH='I12',
 DRAWING='@S9S_MB_2U_LIB.S9S_MB_2U(SCH_1):PAGE215',
 PHYS_PAGE='228',
 XY='(-1400,1725)',
 ROT='0',
 VER='1',
 PACK_TYPE='0402LF',
 CDS_LIB='pure_quanta',
 CDS_PART_NAME='Q_RES_0402LF-33.2,1%,1/16W,CHIA',
 WATTAGE='1/16W',
 TOLERANCE='1%',
 MATERIAL='CHIP',
 VALUE='33.2',
 PRIM_FILE='./archive_libs/logical/q_res/chips/chips.prt';

PART_NAME
 R3054 'Q_RES_0402LF-33.2,1%,1/16W,CHIA':;

SECTION_NUMBER 1
 '@S9S_MB_2U_LIB.S9S_MB_2U(SCH_1):PAGE215_I23@PURE_QUANTA.Q_RES(CHIPS)':
 C_PATH='@s9s_mb_2u_lib.s9s_mb_2u(sch_1):page215_i23@pure_quanta.q_res(chips)',
 P_PATH='@s9s_mb_2u_lib.s9s_mb_2u(sch_1):page228_i23@pure_quanta.q_res(chips)',
 PATH='I23',
 DRAWING='@S9S_MB_2U_LIB.S9S_MB_2U(SCH_1):PAGE215',
 PHYS_PAGE='228',
 XY='(-125,3100)',
 ROT='0',
 VER='1',
 PACK_TYPE='0402LF',
 CDS_LIB='pure_quanta',
 CDS_PART_NAME='Q_RES_0402LF-33.2,1%,1/16W,CHIA',
 WATTAGE='1/16W',
 TOLERANCE='1%',
 MATERIAL='CHIP',
 VALUE='33.2',
 PRIM_FILE='./archive_libs/logical/q_res/chips/chips.prt';

PART_NAME
 R3055 'Q_RES_0402LF-1K,1%,1/16W,CHIP,A':;

SECTION_NUMBER 1
 '@S9S_MB_2U_LIB.S9S_MB_2U(SCH_1):PAGE226_I11@PURE_QUANTA.Q_RES(CHIPS)':
 C_PATH='@s9s_mb_2u_lib.s9s_mb_2u(sch_1):page226_i11@pure_quanta.q_res(chips)',
 P_PATH='@s9s_mb_2u_lib.s9s_mb_2u(sch_1):page239_i11@pure_quanta.q_res(chips)',
 PATH='I11',
 DRAWING='@S9S_MB_2U_LIB.S9S_MB_2U(SCH_1):PAGE226',
 PHYS_PAGE='239',
 XY='(-10100,3750)',
 ROT='0',
 VER='2',
 PACK_TYPE='0402LF',
 CDS_LIB='pure_quanta',
 CDS_PART_NAME='Q_RES_0402LF-1K,1%,1/16W,CHIP,A',
 WATTAGE='1/16W',
 TOLERANCE='1%',
 MATERIAL='CHIP',
 VALUE='1K',
 PRIM_FILE='./archive_libs/logical/q_res/chips/chips.prt';

PART_NAME
 R3056 'Q_RES_0402LF-33.2,1%,1/16W,CHIA':;

SECTION_NUMBER 1
 '@S9S_MB_2U_LIB.S9S_MB_2U(SCH_1):PAGE226_I36@PURE_QUANTA.Q_RES(CHIPS)':
 C_PATH='@s9s_mb_2u_lib.s9s_mb_2u(sch_1):page226_i36@pure_quanta.q_res(chips)',
 P_PATH='@s9s_mb_2u_lib.s9s_mb_2u(sch_1):page239_i36@pure_quanta.q_res(chips)',
 PATH='I36',
 DRAWING='@S9S_MB_2U_LIB.S9S_MB_2U(SCH_1):PAGE226',
 PHYS_PAGE='239',
 XY='(-9950,1525)',
 ROT='0',
 VER='1',
 PACK_TYPE='0402LF',
 CDS_LIB='pure_quanta',
 CDS_PART_NAME='Q_RES_0402LF-33.2,1%,1/16W,CHIA',
 WATTAGE='1/16W',
 TOLERANCE='1%',
 MATERIAL='CHIP',
 VALUE='33.2',
 PRIM_FILE='./archive_libs/logical/q_res/chips/chips.prt';

PART_NAME
 R3057 'Q_RES_0402LF-33.2,1%,1/16W,CHIA':;

SECTION_NUMBER 1
 '@S9S_MB_2U_LIB.S9S_MB_2U(SCH_1):PAGE226_I12@PURE_QUANTA.Q_RES(CHIPS)':
 C_PATH='@s9s_mb_2u_lib.s9s_mb_2u(sch_1):page226_i12@pure_quanta.q_res(chips)',
 P_PATH='@s9s_mb_2u_lib.s9s_mb_2u(sch_1):page239_i12@pure_quanta.q_res(chips)',
 PATH='I12',
 DRAWING='@S9S_MB_2U_LIB.S9S_MB_2U(SCH_1):PAGE226',
 PHYS_PAGE='239',
 XY='(-9850,3050)',
 ROT='0',
 VER='1',
 PACK_TYPE='0402LF',
 CDS_LIB='pure_quanta',
 CDS_PART_NAME='Q_RES_0402LF-33.2,1%,1/16W,CHIA',
 WATTAGE='1/16W',
 TOLERANCE='1%',
 MATERIAL='CHIP',
 VALUE='33.2',
 PRIM_FILE='./archive_libs/logical/q_res/chips/chips.prt';

PART_NAME
 R3058 'Q_RES_0402LF-33.2,1%,1/16W,CHIA':;

SECTION_NUMBER 1
 '@S9S_MB_2U_LIB.S9S_MB_2U(SCH_1):PAGE228_I242@PURE_QUANTA.Q_RES(CHIPS)':
 C_PATH='@s9s_mb_2u_lib.s9s_mb_2u(sch_1):page228_i242@pure_quanta.q_res(chips)',
 P_PATH='@s9s_mb_2u_lib.s9s_mb_2u(sch_1):page241_i242@pure_quanta.q_res(chips)',
 PATH='I242',
 DRAWING='@S9S_MB_2U_LIB.S9S_MB_2U(SCH_1):PAGE228',
 PHYS_PAGE='241',
 XY='(-300,4275)',
 ROT='0',
 VER='1',
 PACK_TYPE='0402LF',
 CDS_LIB='pure_quanta',
 CDS_PART_NAME='Q_RES_0402LF-33.2,1%,1/16W,CHIA',
 WATTAGE='1/16W',
 TOLERANCE='1%',
 MATERIAL='CHIP',
 VALUE='33.2',
 PRIM_FILE='./archive_libs/logical/q_res/chips/chips.prt';

PART_NAME
 R3059 'Q_RES_0402LF-33.2,1%,1/16W,CHIA':;

SECTION_NUMBER 1
 '@S9S_MB_2U_LIB.S9S_MB_2U(SCH_1):PAGE228_I243@PURE_QUANTA.Q_RES(CHIPS)':
 C_PATH='@s9s_mb_2u_lib.s9s_mb_2u(sch_1):page228_i243@pure_quanta.q_res(chips)',
 P_PATH='@s9s_mb_2u_lib.s9s_mb_2u(sch_1):page241_i243@pure_quanta.q_res(chips)',
 PATH='I243',
 DRAWING='@S9S_MB_2U_LIB.S9S_MB_2U(SCH_1):PAGE228',
 PHYS_PAGE='241',
 XY='(-300,4225)',
 ROT='0',
 VER='1',
 PACK_TYPE='0402LF',
 CDS_LIB='pure_quanta',
 CDS_PART_NAME='Q_RES_0402LF-33.2,1%,1/16W,CHIA',
 WATTAGE='1/16W',
 TOLERANCE='1%',
 MATERIAL='CHIP',
 VALUE='33.2',
 PRIM_FILE='./archive_libs/logical/q_res/chips/chips.prt';

PART_NAME
 R3060 'Q_RES_0402LF-33.2,1%,1/16W,CHIA':;

SECTION_NUMBER 1
 '@S9S_MB_2U_LIB.S9S_MB_2U(SCH_1):PAGE228_I237@PURE_QUANTA.Q_RES(CHIPS)':
 C_PATH='@s9s_mb_2u_lib.s9s_mb_2u(sch_1):page228_i237@pure_quanta.q_res(chips)',
 P_PATH='@s9s_mb_2u_lib.s9s_mb_2u(sch_1):page241_i237@pure_quanta.q_res(chips)',
 PATH='I237',
 DRAWING='@S9S_MB_2U_LIB.S9S_MB_2U(SCH_1):PAGE228',
 PHYS_PAGE='241',
 XY='(-325,3050)',
 ROT='0',
 VER='1',
 PACK_TYPE='0402LF',
 CDS_LIB='pure_quanta',
 CDS_PART_NAME='Q_RES_0402LF-33.2,1%,1/16W,CHIA',
 WATTAGE='1/16W',
 TOLERANCE='1%',
 MATERIAL='CHIP',
 VALUE='33.2',
 PRIM_FILE='./archive_libs/logical/q_res/chips/chips.prt';

PART_NAME
 R3061 'Q_RES_0402LF-33.2,1%,1/16W,CHIA':;

SECTION_NUMBER 1
 '@S9S_MB_2U_LIB.S9S_MB_2U(SCH_1):PAGE228_I234@PURE_QUANTA.Q_RES(CHIPS)':
 C_PATH='@s9s_mb_2u_lib.s9s_mb_2u(sch_1):page228_i234@pure_quanta.q_res(chips)',
 P_PATH='@s9s_mb_2u_lib.s9s_mb_2u(sch_1):page241_i234@pure_quanta.q_res(chips)',
 PATH='I234',
 DRAWING='@S9S_MB_2U_LIB.S9S_MB_2U(SCH_1):PAGE228',
 PHYS_PAGE='241',
 XY='(-325,3000)',
 ROT='0',
 VER='1',
 PACK_TYPE='0402LF',
 CDS_LIB='pure_quanta',
 CDS_PART_NAME='Q_RES_0402LF-33.2,1%,1/16W,CHIA',
 WATTAGE='1/16W',
 TOLERANCE='1%',
 MATERIAL='CHIP',
 VALUE='33.2',
 PRIM_FILE='./archive_libs/logical/q_res/chips/chips.prt';

PART_NAME
 R3062 'Q_RES_0402LF-2K,1%,1/16W,EMPTYA':;

SECTION_NUMBER 1
 '@S9S_MB_2U_LIB.S9S_MB_2U(SCH_1):PAGE228_I3@PURE_QUANTA.Q_RES(CHIPS)':
 C_PATH='@s9s_mb_2u_lib.s9s_mb_2u(sch_1):page228_i3@pure_quanta.q_res(chips)',
 P_PATH='@s9s_mb_2u_lib.s9s_mb_2u(sch_1):page241_i3@pure_quanta.q_res(chips)',
 PATH='I3',
 DRAWING='@S9S_MB_2U_LIB.S9S_MB_2U(SCH_1):PAGE228',
 PHYS_PAGE='241',
 XY='(5000,6025)',
 ROT='0',
 VER='1',
 PACK_TYPE='0402LF',
 CDS_LIB='pure_quanta',
 CDS_PART_NAME='Q_RES_0402LF-2K,1%,1/16W,EMPTYA',
 WATTAGE='1/16W',
 TOLERANCE='1%',
 MATERIAL='EMPTY',
 VALUE='2K',
 PRIM_FILE='./archive_libs/logical/q_res/chips/chips.prt';

PART_NAME
 R3063 'Q_RES_0402LF-33.2,1%,1/16W,CHIA':;

SECTION_NUMBER 1
 '@S9S_MB_2U_LIB.S9S_MB_2U(SCH_1):PAGE140_I208@PURE_QUANTA.Q_RES(CHIPS)':
 C_PATH='@s9s_mb_2u_lib.s9s_mb_2u(sch_1):page140_i208@pure_quanta.q_res(chips)',
 P_PATH='@s9s_mb_2u_lib.s9s_mb_2u(sch_1):page151_i208@pure_quanta.q_res(chips)',
 PATH='I208',
 DRAWING='@S9S_MB_2U_LIB.S9S_MB_2U(SCH_1):PAGE140',
 PHYS_PAGE='151',
 XY='(-1575,-1950)',
 ROT='0',
 VER='1',
 PACK_TYPE='0402LF',
 LOCATION='R3063',
 CDS_LIB='pure_quanta',
 CDS_PART_NAME='Q_RES_0402LF-33.2,1%,1/16W,CHIA',
 WATTAGE='1/16W',
 TOLERANCE='1%',
 MATERIAL='CHIP',
 VALUE='33.2',
 PRIM_FILE='./archive_libs/logical/q_res/chips/chips.prt';

PART_NAME
 R3064 'Q_RES_0402LF-0,5%,1/16W,EMPTY,A':;

SECTION_NUMBER 1
 '@S9S_MB_2U_LIB.S9S_MB_2U(SCH_1):PAGE185_I45@PURE_QUANTA.Q_RES(CHIPS)':
 C_PATH='@s9s_mb_2u_lib.s9s_mb_2u(sch_1):page185_i45@pure_quanta.q_res(chips)',
 P_PATH='@s9s_mb_2u_lib.s9s_mb_2u(sch_1):page197_i45@pure_quanta.q_res(chips)',
 PATH='I45',
 DRAWING='@S9S_MB_2U_LIB.S9S_MB_2U(SCH_1):PAGE185',
 PHYS_PAGE='197',
 XY='(-4275,2125)',
 ROT='0',
 VER='1',
 PACK_TYPE='0402LF',
 CDS_LIB='pure_quanta',
 CDS_PART_NAME='Q_RES_0402LF-0,5%,1/16W,EMPTY,A',
 WATTAGE='1/16W',
 TOLERANCE='5%',
 MATERIAL='EMPTY',
 VALUE='0',
 PRIM_FILE='./archive_libs/logical/q_res/chips/chips.prt';

PART_NAME
 R3065 'Q_RES_0402LF-33.2,1%,1/16W,CHIA':;

SECTION_NUMBER 1
 '@S9S_MB_2U_LIB.S9S_MB_2U(SCH_1):PAGE193_I40@PURE_QUANTA.Q_RES(CHIPS)':
 C_PATH='@s9s_mb_2u_lib.s9s_mb_2u(sch_1):page193_i40@pure_quanta.q_res(chips)',
 P_PATH='@s9s_mb_2u_lib.s9s_mb_2u(sch_1):page205_i40@pure_quanta.q_res(chips)',
 PATH='I40',
 DRAWING='@S9S_MB_2U_LIB.S9S_MB_2U(SCH_1):PAGE193',
 PHYS_PAGE='205',
 XY='(-5750,-1025)',
 ROT='0',
 VER='1',
 PACK_TYPE='0402LF',
 CDS_LIB='pure_quanta',
 CDS_PART_NAME='Q_RES_0402LF-33.2,1%,1/16W,CHIA',
 WATTAGE='1/16W',
 TOLERANCE='1%',
 MATERIAL='CHIP',
 VALUE='33.2',
 PRIM_FILE='./archive_libs/logical/q_res/chips/chips.prt';

PART_NAME
 R3066 'Q_RES_0402LF-0,5%,1/16W,CHIP,CA':;

SECTION_NUMBER 1
 '@S9S_MB_2U_LIB.S9S_MB_2U(SCH_1):PAGE313_I175@PURE_QUANTA.Q_RES(CHIPS)':
 C_PATH='@s9s_mb_2u_lib.s9s_mb_2u(sch_1):page313_i175@pure_quanta.q_res(chips)',
 P_PATH='@s9s_mb_2u_lib.s9s_mb_2u(sch_1):page214_i175@pure_quanta.q_res(chips)',
 PATH='I175',
 DRAWING='@S9S_MB_2U_LIB.S9S_MB_2U(SCH_1):PAGE313',
 PHYS_PAGE='214',
 XY='(-1025,-1000)',
 ROT='0',
 VER='1',
 PACK_TYPE='0402LF',
 CDS_LIB='pure_quanta',
 CDS_PART_NAME='Q_RES_0402LF-0,5%,1/16W,CHIP,CA',
 WATTAGE='1/16W',
 TOLERANCE='5%',
 MATERIAL='CHIP',
 VALUE='0',
 PRIM_FILE='./archive_libs/logical/q_res/chips/chips.prt';

PART_NAME
 R3067 'Q_RES_0402LF-0,5%,1/16W,CHIP,CA':;

SECTION_NUMBER 1
 '@S9S_MB_2U_LIB.S9S_MB_2U(SCH_1):PAGE313_I176@PURE_QUANTA.Q_RES(CHIPS)':
 C_PATH='@s9s_mb_2u_lib.s9s_mb_2u(sch_1):page313_i176@pure_quanta.q_res(chips)',
 P_PATH='@s9s_mb_2u_lib.s9s_mb_2u(sch_1):page214_i176@pure_quanta.q_res(chips)',
 PATH='I176',
 DRAWING='@S9S_MB_2U_LIB.S9S_MB_2U(SCH_1):PAGE313',
 PHYS_PAGE='214',
 XY='(-1025,-1200)',
 ROT='0',
 VER='1',
 PACK_TYPE='0402LF',
 CDS_LIB='pure_quanta',
 CDS_PART_NAME='Q_RES_0402LF-0,5%,1/16W,CHIP,CA',
 WATTAGE='1/16W',
 TOLERANCE='5%',
 MATERIAL='CHIP',
 VALUE='0',
 PRIM_FILE='./archive_libs/logical/q_res/chips/chips.prt';

PART_NAME
 R3068 'Q_RES_0402LF-130,1%,1/16W,CHIPA':;

SECTION_NUMBER 1
 '@S9S_MB_2U_LIB.S9S_MB_2U(SCH_1):PAGE241_I38@PURE_QUANTA.Q_RES(CHIPS)':
 C_PATH='@s9s_mb_2u_lib.s9s_mb_2u(sch_1):page241_i38@pure_quanta.q_res(chips)',
 P_PATH='@s9s_mb_2u_lib.s9s_mb_2u(sch_1):page255_i38@pure_quanta.q_res(chips)',
 PATH='I38',
 DRAWING='@S9S_MB_2U_LIB.S9S_MB_2U(SCH_1):PAGE241',
 PHYS_PAGE='255',
 XY='(-11125,3350)',
 ROT='0',
 VER='1',
 PACK_TYPE='0402LF',
 CDS_LIB='pure_quanta',
 CDS_PART_NAME='Q_RES_0402LF-130,1%,1/16W,CHIPA',
 WATTAGE='1/16W',
 TOLERANCE='1%',
 MATERIAL='CHIP',
 VALUE='130',
 PRIM_FILE='./archive_libs/logical/q_res/chips/chips.prt';

PART_NAME
 R3069 'Q_RES_0402LF-130,1%,1/16W,CHIPA':;

SECTION_NUMBER 1
 '@S9S_MB_2U_LIB.S9S_MB_2U(SCH_1):PAGE241_I39@PURE_QUANTA.Q_RES(CHIPS)':
 C_PATH='@s9s_mb_2u_lib.s9s_mb_2u(sch_1):page241_i39@pure_quanta.q_res(chips)',
 P_PATH='@s9s_mb_2u_lib.s9s_mb_2u(sch_1):page255_i39@pure_quanta.q_res(chips)',
 PATH='I39',
 DRAWING='@S9S_MB_2U_LIB.S9S_MB_2U(SCH_1):PAGE241',
 PHYS_PAGE='255',
 XY='(-11125,2075)',
 ROT='0',
 VER='1',
 PACK_TYPE='0402LF',
 CDS_LIB='pure_quanta',
 CDS_PART_NAME='Q_RES_0402LF-130,1%,1/16W,CHIPA',
 WATTAGE='1/16W',
 TOLERANCE='1%',
 MATERIAL='CHIP',
 VALUE='130',
 PRIM_FILE='./archive_libs/logical/q_res/chips/chips.prt';

PART_NAME
 R3070 'Q_RES_0402LF-130,1%,1/16W,CHIPA':;

SECTION_NUMBER 1
 '@S9S_MB_2U_LIB.S9S_MB_2U(SCH_1):PAGE241_I41@PURE_QUANTA.Q_RES(CHIPS)':
 C_PATH='@s9s_mb_2u_lib.s9s_mb_2u(sch_1):page241_i41@pure_quanta.q_res(chips)',
 P_PATH='@s9s_mb_2u_lib.s9s_mb_2u(sch_1):page255_i41@pure_quanta.q_res(chips)',
 PATH='I41',
 DRAWING='@S9S_MB_2U_LIB.S9S_MB_2U(SCH_1):PAGE241',
 PHYS_PAGE='255',
 XY='(-10950,-750)',
 ROT='0',
 VER='1',
 PACK_TYPE='0402LF',
 CDS_LIB='pure_quanta',
 CDS_PART_NAME='Q_RES_0402LF-130,1%,1/16W,CHIPA',
 WATTAGE='1/16W',
 TOLERANCE='1%',
 MATERIAL='CHIP',
 VALUE='130',
 PRIM_FILE='./archive_libs/logical/q_res/chips/chips.prt';

PART_NAME
 R3071 'Q_RES_0402LF-130,1%,1/16W,CHIPA':;

SECTION_NUMBER 1
 '@S9S_MB_2U_LIB.S9S_MB_2U(SCH_1):PAGE242_I19@PURE_QUANTA.Q_RES(CHIPS)':
 C_PATH='@s9s_mb_2u_lib.s9s_mb_2u(sch_1):page242_i19@pure_quanta.q_res(chips)',
 P_PATH='@s9s_mb_2u_lib.s9s_mb_2u(sch_1):page252_i19@pure_quanta.q_res(chips)',
 PATH='I19',
 DRAWING='@S9S_MB_2U_LIB.S9S_MB_2U(SCH_1):PAGE242',
 PHYS_PAGE='252',
 XY='(-3400,8450)',
 ROT='0',
 VER='1',
 PACK_TYPE='0402LF',
 CDS_LIB='pure_quanta',
 CDS_PART_NAME='Q_RES_0402LF-130,1%,1/16W,CHIPA',
 WATTAGE='1/16W',
 TOLERANCE='1%',
 MATERIAL='CHIP',
 VALUE='130',
 PRIM_FILE='./archive_libs/logical/q_res/chips/chips.prt';

PART_NAME
 R3072 'Q_RES_0402LF-130,1%,1/16W,CHIPA':;

SECTION_NUMBER 1
 '@S9S_MB_2U_LIB.S9S_MB_2U(SCH_1):PAGE242_I15@PURE_QUANTA.Q_RES(CHIPS)':
 C_PATH='@s9s_mb_2u_lib.s9s_mb_2u(sch_1):page242_i15@pure_quanta.q_res(chips)',
 P_PATH='@s9s_mb_2u_lib.s9s_mb_2u(sch_1):page252_i15@pure_quanta.q_res(chips)',
 PATH='I15',
 DRAWING='@S9S_MB_2U_LIB.S9S_MB_2U(SCH_1):PAGE242',
 PHYS_PAGE='252',
 XY='(-3375,7125)',
 ROT='0',
 VER='1',
 PACK_TYPE='0402LF',
 CDS_LIB='pure_quanta',
 CDS_PART_NAME='Q_RES_0402LF-130,1%,1/16W,CHIPA',
 WATTAGE='1/16W',
 TOLERANCE='1%',
 MATERIAL='CHIP',
 VALUE='130',
 PRIM_FILE='./archive_libs/logical/q_res/chips/chips.prt';

PART_NAME
 R3073 'Q_RES_0402LF-130,1%,1/16W,CHIPA':;

SECTION_NUMBER 1
 '@S9S_MB_2U_LIB.S9S_MB_2U(SCH_1):PAGE242_I12@PURE_QUANTA.Q_RES(CHIPS)':
 C_PATH='@s9s_mb_2u_lib.s9s_mb_2u(sch_1):page242_i12@pure_quanta.q_res(chips)',
 P_PATH='@s9s_mb_2u_lib.s9s_mb_2u(sch_1):page252_i12@pure_quanta.q_res(chips)',
 PATH='I12',
 DRAWING='@S9S_MB_2U_LIB.S9S_MB_2U(SCH_1):PAGE242',
 PHYS_PAGE='252',
 XY='(-3375,4575)',
 ROT='0',
 VER='1',
 PACK_TYPE='0402LF',
 CDS_LIB='pure_quanta',
 CDS_PART_NAME='Q_RES_0402LF-130,1%,1/16W,CHIPA',
 WATTAGE='1/16W',
 TOLERANCE='1%',
 MATERIAL='CHIP',
 VALUE='130',
 PRIM_FILE='./archive_libs/logical/q_res/chips/chips.prt';

PART_NAME
 R3074 'Q_RES_0402LF-130,1%,1/16W,CHIPA':;

SECTION_NUMBER 1
 '@S9S_MB_2U_LIB.S9S_MB_2U(SCH_1):PAGE242_I14@PURE_QUANTA.Q_RES(CHIPS)':
 C_PATH='@s9s_mb_2u_lib.s9s_mb_2u(sch_1):page242_i14@pure_quanta.q_res(chips)',
 P_PATH='@s9s_mb_2u_lib.s9s_mb_2u(sch_1):page252_i14@pure_quanta.q_res(chips)',
 PATH='I14',
 DRAWING='@S9S_MB_2U_LIB.S9S_MB_2U(SCH_1):PAGE242',
 PHYS_PAGE='252',
 XY='(-3325,5900)',
 ROT='0',
 VER='1',
 PACK_TYPE='0402LF',
 CDS_LIB='pure_quanta',
 CDS_PART_NAME='Q_RES_0402LF-130,1%,1/16W,CHIPA',
 WATTAGE='1/16W',
 TOLERANCE='1%',
 MATERIAL='CHIP',
 VALUE='130',
 PRIM_FILE='./archive_libs/logical/q_res/chips/chips.prt';

PART_NAME
 R3075 'Q_RES_0402LF-130,1%,1/16W,CHIPA':;

SECTION_NUMBER 1
 '@S9S_MB_2U_LIB.S9S_MB_2U(SCH_1):PAGE242_I37@PURE_QUANTA.Q_RES(CHIPS)':
 C_PATH='@s9s_mb_2u_lib.s9s_mb_2u(sch_1):page242_i37@pure_quanta.q_res(chips)',
 P_PATH='@s9s_mb_2u_lib.s9s_mb_2u(sch_1):page252_i37@pure_quanta.q_res(chips)',
 PATH='I37',
 DRAWING='@S9S_MB_2U_LIB.S9S_MB_2U(SCH_1):PAGE242',
 PHYS_PAGE='252',
 XY='(1325,7125)',
 ROT='0',
 VER='1',
 PACK_TYPE='0402LF',
 CDS_LIB='pure_quanta',
 CDS_PART_NAME='Q_RES_0402LF-130,1%,1/16W,CHIPA',
 WATTAGE='1/16W',
 TOLERANCE='1%',
 MATERIAL='CHIP',
 VALUE='130',
 PRIM_FILE='./archive_libs/logical/q_res/chips/chips.prt';

PART_NAME
 R3078 'Q_RES_0402LF-130,1%,1/16W,CHIPA':;

SECTION_NUMBER 1
 '@S9S_MB_2U_LIB.S9S_MB_2U(SCH_1):PAGE242_I41@PURE_QUANTA.Q_RES(CHIPS)':
 C_PATH='@s9s_mb_2u_lib.s9s_mb_2u(sch_1):page242_i41@pure_quanta.q_res(chips)',
 P_PATH='@s9s_mb_2u_lib.s9s_mb_2u(sch_1):page252_i41@pure_quanta.q_res(chips)',
 PATH='I41',
 DRAWING='@S9S_MB_2U_LIB.S9S_MB_2U(SCH_1):PAGE242',
 PHYS_PAGE='252',
 XY='(1350,8450)',
 ROT='0',
 VER='1',
 PACK_TYPE='0402LF',
 CDS_LIB='pure_quanta',
 CDS_PART_NAME='Q_RES_0402LF-130,1%,1/16W,CHIPA',
 WATTAGE='1/16W',
 TOLERANCE='1%',
 MATERIAL='CHIP',
 VALUE='130',
 PRIM_FILE='./archive_libs/logical/q_res/chips/chips.prt';

PART_NAME
 R3079 'Q_RES_0402LF-130,1%,1/16W,CHIPA':;

SECTION_NUMBER 1
 '@S9S_MB_2U_LIB.S9S_MB_2U(SCH_1):PAGE304_I51@PURE_QUANTA.Q_RES(CHIPS)':
 C_PATH='@s9s_mb_2u_lib.s9s_mb_2u(sch_1):page304_i51@pure_quanta.q_res(chips)',
 P_PATH='@s9s_mb_2u_lib.s9s_mb_2u(sch_1):page256_i51@pure_quanta.q_res(chips)',
 PATH='I51',
 DRAWING='@S9S_MB_2U_LIB.S9S_MB_2U(SCH_1):PAGE304',
 PHYS_PAGE='256',
 XY='(-500,1175)',
 ROT='0',
 VER='1',
 PACK_TYPE='0402LF',
 CDS_LIB='pure_quanta',
 CDS_PART_NAME='Q_RES_0402LF-130,1%,1/16W,CHIPA',
 WATTAGE='1/16W',
 TOLERANCE='1%',
 MATERIAL='CHIP',
 VALUE='130',
 PRIM_FILE='./archive_libs/logical/q_res/chips/chips.prt';

PART_NAME
 R3080 'Q_RES_0402LF-130,1%,1/16W,CHIPA':;

SECTION_NUMBER 1
 '@S9S_MB_2U_LIB.S9S_MB_2U(SCH_1):PAGE304_I50@PURE_QUANTA.Q_RES(CHIPS)':
 C_PATH='@s9s_mb_2u_lib.s9s_mb_2u(sch_1):page304_i50@pure_quanta.q_res(chips)',
 P_PATH='@s9s_mb_2u_lib.s9s_mb_2u(sch_1):page256_i50@pure_quanta.q_res(chips)',
 PATH='I50',
 DRAWING='@S9S_MB_2U_LIB.S9S_MB_2U(SCH_1):PAGE304',
 PHYS_PAGE='256',
 XY='(-475,2850)',
 ROT='0',
 VER='1',
 PACK_TYPE='0402LF',
 CDS_LIB='pure_quanta',
 CDS_PART_NAME='Q_RES_0402LF-130,1%,1/16W,CHIPA',
 WATTAGE='1/16W',
 TOLERANCE='1%',
 MATERIAL='CHIP',
 VALUE='130',
 PRIM_FILE='./archive_libs/logical/q_res/chips/chips.prt';

PART_NAME
 R3081 'Q_RES_0402LF-130,1%,1/16W,CHIPA':;

SECTION_NUMBER 1
 '@S9S_MB_2U_LIB.S9S_MB_2U(SCH_1):PAGE304_I52@PURE_QUANTA.Q_RES(CHIPS)':
 C_PATH='@s9s_mb_2u_lib.s9s_mb_2u(sch_1):page304_i52@pure_quanta.q_res(chips)',
 P_PATH='@s9s_mb_2u_lib.s9s_mb_2u(sch_1):page256_i52@pure_quanta.q_res(chips)',
 PATH='I52',
 DRAWING='@S9S_MB_2U_LIB.S9S_MB_2U(SCH_1):PAGE304',
 PHYS_PAGE='256',
 XY='(-350,-175)',
 ROT='0',
 VER='1',
 PACK_TYPE='0402LF',
 CDS_LIB='pure_quanta',
 CDS_PART_NAME='Q_RES_0402LF-130,1%,1/16W,CHIPA',
 WATTAGE='1/16W',
 TOLERANCE='1%',
 MATERIAL='CHIP',
 VALUE='130',
 PRIM_FILE='./archive_libs/logical/q_res/chips/chips.prt';

PART_NAME
 R3082 'Q_RES_0402LF-130,1%,1/16W,CHIPA':;

SECTION_NUMBER 1
 '@S9S_MB_2U_LIB.S9S_MB_2U(SCH_1):PAGE304_I54@PURE_QUANTA.Q_RES(CHIPS)':
 C_PATH='@s9s_mb_2u_lib.s9s_mb_2u(sch_1):page304_i54@pure_quanta.q_res(chips)',
 P_PATH='@s9s_mb_2u_lib.s9s_mb_2u(sch_1):page256_i54@pure_quanta.q_res(chips)',
 PATH='I54',
 DRAWING='@S9S_MB_2U_LIB.S9S_MB_2U(SCH_1):PAGE304',
 PHYS_PAGE='256',
 XY='(4000,4425)',
 ROT='0',
 VER='1',
 PACK_TYPE='0402LF',
 CDS_LIB='pure_quanta',
 CDS_PART_NAME='Q_RES_0402LF-130,1%,1/16W,CHIPA',
 WATTAGE='1/16W',
 TOLERANCE='1%',
 MATERIAL='CHIP',
 VALUE='130',
 PRIM_FILE='./archive_libs/logical/q_res/chips/chips.prt';

PART_NAME
 R3083 'Q_RES_0402LF-130,1%,1/16W,CHIPA':;

SECTION_NUMBER 1
 '@S9S_MB_2U_LIB.S9S_MB_2U(SCH_1):PAGE304_I57@PURE_QUANTA.Q_RES(CHIPS)':
 C_PATH='@s9s_mb_2u_lib.s9s_mb_2u(sch_1):page304_i57@pure_quanta.q_res(chips)',
 P_PATH='@s9s_mb_2u_lib.s9s_mb_2u(sch_1):page256_i57@pure_quanta.q_res(chips)',
 PATH='I57',
 DRAWING='@S9S_MB_2U_LIB.S9S_MB_2U(SCH_1):PAGE304',
 PHYS_PAGE='256',
 XY='(4025,1250)',
 ROT='0',
 VER='1',
 PACK_TYPE='0402LF',
 CDS_LIB='pure_quanta',
 CDS_PART_NAME='Q_RES_0402LF-130,1%,1/16W,CHIPA',
 WATTAGE='1/16W',
 TOLERANCE='1%',
 MATERIAL='CHIP',
 VALUE='130',
 PRIM_FILE='./archive_libs/logical/q_res/chips/chips.prt';

PART_NAME
 R3084 'Q_RES_0402LF-130,1%,1/16W,CHIPA':;

SECTION_NUMBER 1
 '@S9S_MB_2U_LIB.S9S_MB_2U(SCH_1):PAGE304_I53@PURE_QUANTA.Q_RES(CHIPS)':
 C_PATH='@s9s_mb_2u_lib.s9s_mb_2u(sch_1):page304_i53@pure_quanta.q_res(chips)',
 P_PATH='@s9s_mb_2u_lib.s9s_mb_2u(sch_1):page256_i53@pure_quanta.q_res(chips)',
 PATH='I53',
 DRAWING='@S9S_MB_2U_LIB.S9S_MB_2U(SCH_1):PAGE304',
 PHYS_PAGE='256',
 XY='(4100,3000)',
 ROT='0',
 VER='1',
 PACK_TYPE='0402LF',
 CDS_LIB='pure_quanta',
 CDS_PART_NAME='Q_RES_0402LF-130,1%,1/16W,CHIPA',
 WATTAGE='1/16W',
 TOLERANCE='1%',
 MATERIAL='CHIP',
 VALUE='130',
 PRIM_FILE='./archive_libs/logical/q_res/chips/chips.prt';

PART_NAME
 R3085 'Q_RES_0402LF-130,1%,1/16W,CHIPA':;

SECTION_NUMBER 1
 '@S9S_MB_2U_LIB.S9S_MB_2U(SCH_1):PAGE304_I62@PURE_QUANTA.Q_RES(CHIPS)':
 C_PATH='@s9s_mb_2u_lib.s9s_mb_2u(sch_1):page304_i62@pure_quanta.q_res(chips)',
 P_PATH='@s9s_mb_2u_lib.s9s_mb_2u(sch_1):page256_i62@pure_quanta.q_res(chips)',
 PATH='I62',
 DRAWING='@S9S_MB_2U_LIB.S9S_MB_2U(SCH_1):PAGE304',
 PHYS_PAGE='256',
 XY='(4175,-100)',
 ROT='0',
 VER='1',
 PACK_TYPE='0402LF',
 CDS_LIB='pure_quanta',
 CDS_PART_NAME='Q_RES_0402LF-130,1%,1/16W,CHIPA',
 WATTAGE='1/16W',
 TOLERANCE='1%',
 MATERIAL='CHIP',
 VALUE='130',
 PRIM_FILE='./archive_libs/logical/q_res/chips/chips.prt';

PART_NAME
 R3086 'Q_RES_0402LF-130,1%,1/16W,CHIPA':;

SECTION_NUMBER 1
 '@S9S_MB_2U_LIB.S9S_MB_2U(SCH_1):PAGE305_I49@PURE_QUANTA.Q_RES(CHIPS)':
 C_PATH='@s9s_mb_2u_lib.s9s_mb_2u(sch_1):page305_i49@pure_quanta.q_res(chips)',
 P_PATH='@s9s_mb_2u_lib.s9s_mb_2u(sch_1):page253_i49@pure_quanta.q_res(chips)',
 PATH='I49',
 DRAWING='@S9S_MB_2U_LIB.S9S_MB_2U(SCH_1):PAGE305',
 PHYS_PAGE='253',
 XY='(-225,4700)',
 ROT='0',
 VER='1',
 PACK_TYPE='0402LF',
 CDS_LIB='pure_quanta',
 CDS_PART_NAME='Q_RES_0402LF-130,1%,1/16W,CHIPA',
 WATTAGE='1/16W',
 TOLERANCE='1%',
 MATERIAL='CHIP',
 VALUE='130',
 PRIM_FILE='./archive_libs/logical/q_res/chips/chips.prt';

PART_NAME
 R3087 'Q_RES_0402LF-130,1%,1/16W,CHIPA':;

SECTION_NUMBER 1
 '@S9S_MB_2U_LIB.S9S_MB_2U(SCH_1):PAGE305_I50@PURE_QUANTA.Q_RES(CHIPS)':
 C_PATH='@s9s_mb_2u_lib.s9s_mb_2u(sch_1):page305_i50@pure_quanta.q_res(chips)',
 P_PATH='@s9s_mb_2u_lib.s9s_mb_2u(sch_1):page253_i50@pure_quanta.q_res(chips)',
 PATH='I50',
 DRAWING='@S9S_MB_2U_LIB.S9S_MB_2U(SCH_1):PAGE305',
 PHYS_PAGE='253',
 XY='(-200,3375)',
 ROT='0',
 VER='1',
 PACK_TYPE='0402LF',
 CDS_LIB='pure_quanta',
 CDS_PART_NAME='Q_RES_0402LF-130,1%,1/16W,CHIPA',
 WATTAGE='1/16W',
 TOLERANCE='1%',
 MATERIAL='CHIP',
 VALUE='130',
 PRIM_FILE='./archive_libs/logical/q_res/chips/chips.prt';

PART_NAME
 R3088 'Q_RES_0402LF-130,1%,1/16W,CHIPA':;

SECTION_NUMBER 1
 '@S9S_MB_2U_LIB.S9S_MB_2U(SCH_1):PAGE305_I52@PURE_QUANTA.Q_RES(CHIPS)':
 C_PATH='@s9s_mb_2u_lib.s9s_mb_2u(sch_1):page305_i52@pure_quanta.q_res(chips)',
 P_PATH='@s9s_mb_2u_lib.s9s_mb_2u(sch_1):page253_i52@pure_quanta.q_res(chips)',
 PATH='I52',
 DRAWING='@S9S_MB_2U_LIB.S9S_MB_2U(SCH_1):PAGE305',
 PHYS_PAGE='253',
 XY='(-200,825)',
 ROT='0',
 VER='1',
 PACK_TYPE='0402LF',
 CDS_LIB='pure_quanta',
 CDS_PART_NAME='Q_RES_0402LF-130,1%,1/16W,CHIPA',
 WATTAGE='1/16W',
 TOLERANCE='1%',
 MATERIAL='CHIP',
 VALUE='130',
 PRIM_FILE='./archive_libs/logical/q_res/chips/chips.prt';

PART_NAME
 R3089 'Q_RES_0402LF-130,1%,1/16W,CHIPA':;

SECTION_NUMBER 1
 '@S9S_MB_2U_LIB.S9S_MB_2U(SCH_1):PAGE305_I51@PURE_QUANTA.Q_RES(CHIPS)':
 C_PATH='@s9s_mb_2u_lib.s9s_mb_2u(sch_1):page305_i51@pure_quanta.q_res(chips)',
 P_PATH='@s9s_mb_2u_lib.s9s_mb_2u(sch_1):page253_i51@pure_quanta.q_res(chips)',
 PATH='I51',
 DRAWING='@S9S_MB_2U_LIB.S9S_MB_2U(SCH_1):PAGE305',
 PHYS_PAGE='253',
 XY='(-150,2150)',
 ROT='0',
 VER='1',
 PACK_TYPE='0402LF',
 CDS_LIB='pure_quanta',
 CDS_PART_NAME='Q_RES_0402LF-130,1%,1/16W,CHIPA',
 WATTAGE='1/16W',
 TOLERANCE='1%',
 MATERIAL='CHIP',
 VALUE='130',
 PRIM_FILE='./archive_libs/logical/q_res/chips/chips.prt';

PART_NAME
 R3090 'Q_RES_0402LF-130,1%,1/16W,CHIPA':;

SECTION_NUMBER 1
 '@S9S_MB_2U_LIB.S9S_MB_2U(SCH_1):PAGE305_I54@PURE_QUANTA.Q_RES(CHIPS)':
 C_PATH='@s9s_mb_2u_lib.s9s_mb_2u(sch_1):page305_i54@pure_quanta.q_res(chips)',
 P_PATH='@s9s_mb_2u_lib.s9s_mb_2u(sch_1):page253_i54@pure_quanta.q_res(chips)',
 PATH='I54',
 DRAWING='@S9S_MB_2U_LIB.S9S_MB_2U(SCH_1):PAGE305',
 PHYS_PAGE='253',
 XY='(4500,3375)',
 ROT='0',
 VER='1',
 PACK_TYPE='0402LF',
 CDS_LIB='pure_quanta',
 CDS_PART_NAME='Q_RES_0402LF-130,1%,1/16W,CHIPA',
 WATTAGE='1/16W',
 TOLERANCE='1%',
 MATERIAL='CHIP',
 VALUE='130',
 PRIM_FILE='./archive_libs/logical/q_res/chips/chips.prt';

PART_NAME
 R3091 'Q_RES_0402LF-130,1%,1/16W,CHIPA':;

SECTION_NUMBER 1
 '@S9S_MB_2U_LIB.S9S_MB_2U(SCH_1):PAGE305_I53@PURE_QUANTA.Q_RES(CHIPS)':
 C_PATH='@s9s_mb_2u_lib.s9s_mb_2u(sch_1):page305_i53@pure_quanta.q_res(chips)',
 P_PATH='@s9s_mb_2u_lib.s9s_mb_2u(sch_1):page253_i53@pure_quanta.q_res(chips)',
 PATH='I53',
 DRAWING='@S9S_MB_2U_LIB.S9S_MB_2U(SCH_1):PAGE305',
 PHYS_PAGE='253',
 XY='(4500,2125)',
 ROT='0',
 VER='1',
 PACK_TYPE='0402LF',
 CDS_LIB='pure_quanta',
 CDS_PART_NAME='Q_RES_0402LF-130,1%,1/16W,CHIPA',
 WATTAGE='1/16W',
 TOLERANCE='1%',
 MATERIAL='CHIP',
 VALUE='130',
 PRIM_FILE='./archive_libs/logical/q_res/chips/chips.prt';

PART_NAME
 R3092 'Q_RES_0402LF-130,1%,1/16W,CHIPA':;

SECTION_NUMBER 1
 '@S9S_MB_2U_LIB.S9S_MB_2U(SCH_1):PAGE305_I55@PURE_QUANTA.Q_RES(CHIPS)':
 C_PATH='@s9s_mb_2u_lib.s9s_mb_2u(sch_1):page305_i55@pure_quanta.q_res(chips)',
 P_PATH='@s9s_mb_2u_lib.s9s_mb_2u(sch_1):page253_i55@pure_quanta.q_res(chips)',
 PATH='I55',
 DRAWING='@S9S_MB_2U_LIB.S9S_MB_2U(SCH_1):PAGE305',
 PHYS_PAGE='253',
 XY='(4525,4700)',
 ROT='0',
 VER='1',
 PACK_TYPE='0402LF',
 CDS_LIB='pure_quanta',
 CDS_PART_NAME='Q_RES_0402LF-130,1%,1/16W,CHIPA',
 WATTAGE='1/16W',
 TOLERANCE='1%',
 MATERIAL='CHIP',
 VALUE='130',
 PRIM_FILE='./archive_libs/logical/q_res/chips/chips.prt';

PART_NAME
 R3093 'Q_RES_0402LF-130,1%,1/16W,CHIPA':;

SECTION_NUMBER 1
 '@S9S_MB_2U_LIB.S9S_MB_2U(SCH_1):PAGE306_I20@PURE_QUANTA.Q_RES(CHIPS)':
 C_PATH='@s9s_mb_2u_lib.s9s_mb_2u(sch_1):page306_i20@pure_quanta.q_res(chips)',
 P_PATH='@s9s_mb_2u_lib.s9s_mb_2u(sch_1):page254_i20@pure_quanta.q_res(chips)',
 PATH='I20',
 DRAWING='@S9S_MB_2U_LIB.S9S_MB_2U(SCH_1):PAGE306',
 PHYS_PAGE='254',
 XY='(-425,4350)',
 ROT='0',
 VER='1',
 PACK_TYPE='0402LF',
 CDS_LIB='pure_quanta',
 CDS_PART_NAME='Q_RES_0402LF-130,1%,1/16W,CHIPA',
 WATTAGE='1/16W',
 TOLERANCE='1%',
 MATERIAL='CHIP',
 VALUE='130',
 PRIM_FILE='./archive_libs/logical/q_res/chips/chips.prt';

PART_NAME
 R3094 'Q_RES_0402LF-130,1%,1/16W,CHIPA':;

SECTION_NUMBER 1
 '@S9S_MB_2U_LIB.S9S_MB_2U(SCH_1):PAGE306_I16@PURE_QUANTA.Q_RES(CHIPS)':
 C_PATH='@s9s_mb_2u_lib.s9s_mb_2u(sch_1):page306_i16@pure_quanta.q_res(chips)',
 P_PATH='@s9s_mb_2u_lib.s9s_mb_2u(sch_1):page254_i16@pure_quanta.q_res(chips)',
 PATH='I16',
 DRAWING='@S9S_MB_2U_LIB.S9S_MB_2U(SCH_1):PAGE306',
 PHYS_PAGE='254',
 XY='(-400,3025)',
 ROT='0',
 VER='1',
 PACK_TYPE='0402LF',
 CDS_LIB='pure_quanta',
 CDS_PART_NAME='Q_RES_0402LF-130,1%,1/16W,CHIPA',
 WATTAGE='1/16W',
 TOLERANCE='1%',
 MATERIAL='CHIP',
 VALUE='130',
 PRIM_FILE='./archive_libs/logical/q_res/chips/chips.prt';

PART_NAME
 R3095 'Q_RES_0402LF-130,1%,1/16W,CHIPA':;

SECTION_NUMBER 1
 '@S9S_MB_2U_LIB.S9S_MB_2U(SCH_1):PAGE306_I12@PURE_QUANTA.Q_RES(CHIPS)':
 C_PATH='@s9s_mb_2u_lib.s9s_mb_2u(sch_1):page306_i12@pure_quanta.q_res(chips)',
 P_PATH='@s9s_mb_2u_lib.s9s_mb_2u(sch_1):page254_i12@pure_quanta.q_res(chips)',
 PATH='I12',
 DRAWING='@S9S_MB_2U_LIB.S9S_MB_2U(SCH_1):PAGE306',
 PHYS_PAGE='254',
 XY='(-400,475)',
 ROT='0',
 VER='1',
 PACK_TYPE='0402LF',
 CDS_LIB='pure_quanta',
 CDS_PART_NAME='Q_RES_0402LF-130,1%,1/16W,CHIPA',
 WATTAGE='1/16W',
 TOLERANCE='1%',
 MATERIAL='CHIP',
 VALUE='130',
 PRIM_FILE='./archive_libs/logical/q_res/chips/chips.prt';

PART_NAME
 R3096 'Q_RES_0402LF-130,1%,1/16W,CHIPA':;

SECTION_NUMBER 1
 '@S9S_MB_2U_LIB.S9S_MB_2U(SCH_1):PAGE306_I15@PURE_QUANTA.Q_RES(CHIPS)':
 C_PATH='@s9s_mb_2u_lib.s9s_mb_2u(sch_1):page306_i15@pure_quanta.q_res(chips)',
 P_PATH='@s9s_mb_2u_lib.s9s_mb_2u(sch_1):page254_i15@pure_quanta.q_res(chips)',
 PATH='I15',
 DRAWING='@S9S_MB_2U_LIB.S9S_MB_2U(SCH_1):PAGE306',
 PHYS_PAGE='254',
 XY='(-350,1800)',
 ROT='0',
 VER='1',
 PACK_TYPE='0402LF',
 CDS_LIB='pure_quanta',
 CDS_PART_NAME='Q_RES_0402LF-130,1%,1/16W,CHIPA',
 WATTAGE='1/16W',
 TOLERANCE='1%',
 MATERIAL='CHIP',
 VALUE='130',
 PRIM_FILE='./archive_libs/logical/q_res/chips/chips.prt';

PART_NAME
 R3097 'Q_RES_0402LF-130,1%,1/16W,CHIPA':;

SECTION_NUMBER 1
 '@S9S_MB_2U_LIB.S9S_MB_2U(SCH_1):PAGE306_I38@PURE_QUANTA.Q_RES(CHIPS)':
 C_PATH='@s9s_mb_2u_lib.s9s_mb_2u(sch_1):page306_i38@pure_quanta.q_res(chips)',
 P_PATH='@s9s_mb_2u_lib.s9s_mb_2u(sch_1):page254_i38@pure_quanta.q_res(chips)',
 PATH='I38',
 DRAWING='@S9S_MB_2U_LIB.S9S_MB_2U(SCH_1):PAGE306',
 PHYS_PAGE='254',
 XY='(4300,3025)',
 ROT='0',
 VER='1',
 PACK_TYPE='0402LF',
 CDS_LIB='pure_quanta',
 CDS_PART_NAME='Q_RES_0402LF-130,1%,1/16W,CHIPA',
 WATTAGE='1/16W',
 TOLERANCE='1%',
 MATERIAL='CHIP',
 VALUE='130',
 PRIM_FILE='./archive_libs/logical/q_res/chips/chips.prt';

PART_NAME
 R3098 'Q_RES_0402LF-130,1%,1/16W,CHIPA':;

SECTION_NUMBER 1
 '@S9S_MB_2U_LIB.S9S_MB_2U(SCH_1):PAGE306_I37@PURE_QUANTA.Q_RES(CHIPS)':
 C_PATH='@s9s_mb_2u_lib.s9s_mb_2u(sch_1):page306_i37@pure_quanta.q_res(chips)',
 P_PATH='@s9s_mb_2u_lib.s9s_mb_2u(sch_1):page254_i37@pure_quanta.q_res(chips)',
 PATH='I37',
 DRAWING='@S9S_MB_2U_LIB.S9S_MB_2U(SCH_1):PAGE306',
 PHYS_PAGE='254',
 XY='(4300,1775)',
 ROT='0',
 VER='1',
 PACK_TYPE='0402LF',
 CDS_LIB='pure_quanta',
 CDS_PART_NAME='Q_RES_0402LF-130,1%,1/16W,CHIPA',
 WATTAGE='1/16W',
 TOLERANCE='1%',
 MATERIAL='CHIP',
 VALUE='130',
 PRIM_FILE='./archive_libs/logical/q_res/chips/chips.prt';

PART_NAME
 R3099 'Q_RES_0402LF-130,1%,1/16W,CHIPA':;

SECTION_NUMBER 1
 '@S9S_MB_2U_LIB.S9S_MB_2U(SCH_1):PAGE306_I41@PURE_QUANTA.Q_RES(CHIPS)':
 C_PATH='@s9s_mb_2u_lib.s9s_mb_2u(sch_1):page306_i41@pure_quanta.q_res(chips)',
 P_PATH='@s9s_mb_2u_lib.s9s_mb_2u(sch_1):page254_i41@pure_quanta.q_res(chips)',
 PATH='I41',
 DRAWING='@S9S_MB_2U_LIB.S9S_MB_2U(SCH_1):PAGE306',
 PHYS_PAGE='254',
 XY='(4325,4350)',
 ROT='0',
 VER='1',
 PACK_TYPE='0402LF',
 CDS_LIB='pure_quanta',
 CDS_PART_NAME='Q_RES_0402LF-130,1%,1/16W,CHIPA',
 WATTAGE='1/16W',
 TOLERANCE='1%',
 MATERIAL='CHIP',
 VALUE='130',
 PRIM_FILE='./archive_libs/logical/q_res/chips/chips.prt';

PART_NAME
 R3100 'Q_RES_0402LF-130,1%,1/16W,CHIPA':;

SECTION_NUMBER 1
 '@S9S_MB_2U_LIB.S9S_MB_2U(SCH_1):PAGE242_I64@PURE_QUANTA.Q_RES(CHIPS)':
 C_PATH='@s9s_mb_2u_lib.s9s_mb_2u(sch_1):page242_i64@pure_quanta.q_res(chips)',
 P_PATH='@s9s_mb_2u_lib.s9s_mb_2u(sch_1):page252_i64@pure_quanta.q_res(chips)',
 PATH='I64',
 DRAWING='@S9S_MB_2U_LIB.S9S_MB_2U(SCH_1):PAGE242',
 PHYS_PAGE='252',
 XY='(-75,3400)',
 ROT='0',
 VER='1',
 PACK_TYPE='0402LF',
 LOCATION='R3100',
 CDS_LIB='pure_quanta',
 CDS_PART_NAME='Q_RES_0402LF-130,1%,1/16W,CHIPA',
 WATTAGE='1/16W',
 TOLERANCE='1%',
 MATERIAL='CHIP',
 VALUE='130',
 PRIM_FILE='./archive_libs/logical/q_res/chips/chips.prt';

PART_NAME
 R3101 'Q_RES_0402LF-470,1%,1/16W,CHIPA':;

SECTION_NUMBER 1
 '@S9S_MB_2U_LIB.S9S_MB_2U(SCH_1):PAGE242_I62@PURE_QUANTA.Q_RES(CHIPS)':
 C_PATH='@s9s_mb_2u_lib.s9s_mb_2u(sch_1):page242_i62@pure_quanta.q_res(chips)',
 P_PATH='@s9s_mb_2u_lib.s9s_mb_2u(sch_1):page252_i62@pure_quanta.q_res(chips)',
 PATH='I62',
 DRAWING='@S9S_MB_2U_LIB.S9S_MB_2U(SCH_1):PAGE242',
 PHYS_PAGE='252',
 XY='(-25,5750)',
 ROT='0',
 VER='1',
 PACK_TYPE='0402LF',
 CDS_LIB='pure_quanta',
 CDS_PART_NAME='Q_RES_0402LF-470,1%,1/16W,CHIPA',
 WATTAGE='1/16W',
 TOLERANCE='1%',
 MATERIAL='CHIP',
 VALUE='470',
 PRIM_FILE='./archive_libs/logical/q_res/chips/chips.prt';

PART_NAME
 R3102 'Q_RES_0402LF-470,1%,1/16W,CHIPA':;

SECTION_NUMBER 1
 '@S9S_MB_2U_LIB.S9S_MB_2U(SCH_1):PAGE242_I61@PURE_QUANTA.Q_RES(CHIPS)':
 C_PATH='@s9s_mb_2u_lib.s9s_mb_2u(sch_1):page242_i61@pure_quanta.q_res(chips)',
 P_PATH='@s9s_mb_2u_lib.s9s_mb_2u(sch_1):page252_i61@pure_quanta.q_res(chips)',
 PATH='I61',
 DRAWING='@S9S_MB_2U_LIB.S9S_MB_2U(SCH_1):PAGE242',
 PHYS_PAGE='252',
 XY='(0,4625)',
 ROT='0',
 VER='1',
 PACK_TYPE='0402LF',
 CDS_LIB='pure_quanta',
 CDS_PART_NAME='Q_RES_0402LF-470,1%,1/16W,CHIPA',
 WATTAGE='1/16W',
 TOLERANCE='1%',
 MATERIAL='CHIP',
 VALUE='470',
 PRIM_FILE='./archive_libs/logical/q_res/chips/chips.prt';

PART_NAME
 R3103 'Q_RES_0402LF-0,5%,1/16W,CHIP,CA':;

SECTION_NUMBER 1
 '@S9S_MB_2U_LIB.S9S_MB_2U(SCH_1):PAGE215_I28@PURE_QUANTA.Q_RES(CHIPS)':
 C_PATH='@s9s_mb_2u_lib.s9s_mb_2u(sch_1):page215_i28@pure_quanta.q_res(chips)',
 P_PATH='@s9s_mb_2u_lib.s9s_mb_2u(sch_1):page228_i28@pure_quanta.q_res(chips)',
 PATH='I28',
 DRAWING='@S9S_MB_2U_LIB.S9S_MB_2U(SCH_1):PAGE215',
 PHYS_PAGE='228',
 XY='(-1400,2325)',
 ROT='0',
 VER='1',
 PACK_TYPE='0402LF',
 CDS_LIB='pure_quanta',
 CDS_PART_NAME='Q_RES_0402LF-0,5%,1/16W,CHIP,CA',
 WATTAGE='1/16W',
 TOLERANCE='5%',
 MATERIAL='CHIP',
 VALUE='0',
 PRIM_FILE='./archive_libs/logical/q_res/chips/chips.prt';

PART_NAME
 R3105 'Q_RES_0402LF-0,5%,1/16W,CHIP,CA':;

SECTION_NUMBER 1
 '@S9S_MB_2U_LIB.S9S_MB_2U(SCH_1):PAGE222_I43@PURE_QUANTA.Q_RES(CHIPS)':
 C_PATH='@s9s_mb_2u_lib.s9s_mb_2u(sch_1):page222_i43@pure_quanta.q_res(chips)',
 P_PATH='@s9s_mb_2u_lib.s9s_mb_2u(sch_1):page234_i43@pure_quanta.q_res(chips)',
 PATH='I43',
 DRAWING='@S9S_MB_2U_LIB.S9S_MB_2U(SCH_1):PAGE222',
 PHYS_PAGE='234',
 XY='(-6125,8800)',
 ROT='0',
 VER='1',
 PACK_TYPE='0402LF',
 CDS_LIB='pure_quanta',
 CDS_PART_NAME='Q_RES_0402LF-0,5%,1/16W,CHIP,CA',
 WATTAGE='1/16W',
 TOLERANCE='5%',
 MATERIAL='CHIP',
 VALUE='0',
 PRIM_FILE='./archive_libs/logical/q_res/chips/chips.prt';

PART_NAME
 R3106 'Q_RES_0402LF-0,5%,1/16W,CHIP,CA':;

SECTION_NUMBER 1
 '@S9S_MB_2U_LIB.S9S_MB_2U(SCH_1):PAGE222_I42@PURE_QUANTA.Q_RES(CHIPS)':
 C_PATH='@s9s_mb_2u_lib.s9s_mb_2u(sch_1):page222_i42@pure_quanta.q_res(chips)',
 P_PATH='@s9s_mb_2u_lib.s9s_mb_2u(sch_1):page234_i42@pure_quanta.q_res(chips)',
 PATH='I42',
 DRAWING='@S9S_MB_2U_LIB.S9S_MB_2U(SCH_1):PAGE222',
 PHYS_PAGE='234',
 XY='(-6125,8700)',
 ROT='0',
 VER='1',
 PACK_TYPE='0402LF',
 CDS_LIB='pure_quanta',
 CDS_PART_NAME='Q_RES_0402LF-0,5%,1/16W,CHIP,CA',
 WATTAGE='1/16W',
 TOLERANCE='5%',
 MATERIAL='CHIP',
 VALUE='0',
 PRIM_FILE='./archive_libs/logical/q_res/chips/chips.prt';

PART_NAME
 R3107 'Q_RES_0402LF-0,5%,1/16W,CHIP,CA':;

SECTION_NUMBER 1
 '@S9S_MB_2U_LIB.S9S_MB_2U(SCH_1):PAGE222_I8@PURE_QUANTA.Q_RES(CHIPS)':
 C_PATH='@s9s_mb_2u_lib.s9s_mb_2u(sch_1):page222_i8@pure_quanta.q_res(chips)',
 P_PATH='@s9s_mb_2u_lib.s9s_mb_2u(sch_1):page234_i8@pure_quanta.q_res(chips)',
 PATH='I8',
 DRAWING='@S9S_MB_2U_LIB.S9S_MB_2U(SCH_1):PAGE222',
 PHYS_PAGE='234',
 XY='(-6175,6075)',
 ROT='0',
 VER='1',
 PACK_TYPE='0402LF',
 CDS_LIB='pure_quanta',
 CDS_PART_NAME='Q_RES_0402LF-0,5%,1/16W,CHIP,CA',
 WATTAGE='1/16W',
 TOLERANCE='5%',
 MATERIAL='CHIP',
 VALUE='0',
 PRIM_FILE='./archive_libs/logical/q_res/chips/chips.prt';

PART_NAME
 R3108 'Q_RES_0402LF-0,5%,1/16W,CHIP,CA':;

SECTION_NUMBER 1
 '@S9S_MB_2U_LIB.S9S_MB_2U(SCH_1):PAGE222_I7@PURE_QUANTA.Q_RES(CHIPS)':
 C_PATH='@s9s_mb_2u_lib.s9s_mb_2u(sch_1):page222_i7@pure_quanta.q_res(chips)',
 P_PATH='@s9s_mb_2u_lib.s9s_mb_2u(sch_1):page234_i7@pure_quanta.q_res(chips)',
 PATH='I7',
 DRAWING='@S9S_MB_2U_LIB.S9S_MB_2U(SCH_1):PAGE222',
 PHYS_PAGE='234',
 XY='(-6175,5975)',
 ROT='0',
 VER='1',
 PACK_TYPE='0402LF',
 CDS_LIB='pure_quanta',
 CDS_PART_NAME='Q_RES_0402LF-0,5%,1/16W,CHIP,CA',
 WATTAGE='1/16W',
 TOLERANCE='5%',
 MATERIAL='CHIP',
 VALUE='0',
 PRIM_FILE='./archive_libs/logical/q_res/chips/chips.prt';

PART_NAME
 R3109 'Q_RES_0402LF-0,5%,1/16W,CHIP,CA':;

SECTION_NUMBER 1
 '@S9S_MB_2U_LIB.S9S_MB_2U(SCH_1):PAGE222_I51@PURE_QUANTA.Q_RES(CHIPS)':
 C_PATH='@s9s_mb_2u_lib.s9s_mb_2u(sch_1):page222_i51@pure_quanta.q_res(chips)',
 P_PATH='@s9s_mb_2u_lib.s9s_mb_2u(sch_1):page234_i51@pure_quanta.q_res(chips)',
 PATH='I51',
 DRAWING='@S9S_MB_2U_LIB.S9S_MB_2U(SCH_1):PAGE222',
 PHYS_PAGE='234',
 XY='(-4100,7425)',
 ROT='0',
 VER='1',
 PACK_TYPE='0402LF',
 CDS_LIB='pure_quanta',
 CDS_PART_NAME='Q_RES_0402LF-0,5%,1/16W,CHIP,CA',
 WATTAGE='1/16W',
 TOLERANCE='5%',
 MATERIAL='CHIP',
 VALUE='0',
 PRIM_FILE='./archive_libs/logical/q_res/chips/chips.prt';

PART_NAME
 R3110 'Q_RES_0402LF-0,5%,1/16W,CHIP,CA':;

SECTION_NUMBER 1
 '@S9S_MB_2U_LIB.S9S_MB_2U(SCH_1):PAGE222_I52@PURE_QUANTA.Q_RES(CHIPS)':
 C_PATH='@s9s_mb_2u_lib.s9s_mb_2u(sch_1):page222_i52@pure_quanta.q_res(chips)',
 P_PATH='@s9s_mb_2u_lib.s9s_mb_2u(sch_1):page234_i52@pure_quanta.q_res(chips)',
 PATH='I52',
 DRAWING='@S9S_MB_2U_LIB.S9S_MB_2U(SCH_1):PAGE222',
 PHYS_PAGE='234',
 XY='(-4100,7325)',
 ROT='0',
 VER='1',
 PACK_TYPE='0402LF',
 CDS_LIB='pure_quanta',
 CDS_PART_NAME='Q_RES_0402LF-0,5%,1/16W,CHIP,CA',
 WATTAGE='1/16W',
 TOLERANCE='5%',
 MATERIAL='CHIP',
 VALUE='0',
 PRIM_FILE='./archive_libs/logical/q_res/chips/chips.prt';

PART_NAME
 R3111 'Q_RES_0402LF-0,5%,1/16W,CHIP,CA':;

SECTION_NUMBER 1
 '@S9S_MB_2U_LIB.S9S_MB_2U(SCH_1):PAGE222_I17@PURE_QUANTA.Q_RES(CHIPS)':
 C_PATH='@s9s_mb_2u_lib.s9s_mb_2u(sch_1):page222_i17@pure_quanta.q_res(chips)',
 P_PATH='@s9s_mb_2u_lib.s9s_mb_2u(sch_1):page234_i17@pure_quanta.q_res(chips)',
 PATH='I17',
 DRAWING='@S9S_MB_2U_LIB.S9S_MB_2U(SCH_1):PAGE222',
 PHYS_PAGE='234',
 XY='(-4050,4550)',
 ROT='0',
 VER='1',
 PACK_TYPE='0402LF',
 LOCATION='R3111',
 CDS_LIB='pure_quanta',
 CDS_PART_NAME='Q_RES_0402LF-0,5%,1/16W,CHIP,CA',
 WATTAGE='1/16W',
 TOLERANCE='5%',
 MATERIAL='CHIP',
 VALUE='0',
 PRIM_FILE='./archive_libs/logical/q_res/chips/chips.prt';

PART_NAME
 R3112 'Q_RES_0402LF-33.2,1%,1/16W,CHIA':;

SECTION_NUMBER 1
 '@S9S_MB_2U_LIB.S9S_MB_2U(SCH_1):PAGE222_I18@PURE_QUANTA.Q_RES(CHIPS)':
 C_PATH='@s9s_mb_2u_lib.s9s_mb_2u(sch_1):page222_i18@pure_quanta.q_res(chips)',
 P_PATH='@s9s_mb_2u_lib.s9s_mb_2u(sch_1):page234_i18@pure_quanta.q_res(chips)',
 PATH='I18',
 DRAWING='@S9S_MB_2U_LIB.S9S_MB_2U(SCH_1):PAGE222',
 PHYS_PAGE='234',
 XY='(-4050,4650)',
 ROT='0',
 VER='1',
 PACK_TYPE='0402LF',
 LOCATION='R3112',
 CDS_LIB='pure_quanta',
 CDS_PART_NAME='Q_RES_0402LF-33.2,1%,1/16W,CHIA',
 WATTAGE='1/16W',
 TOLERANCE='1%',
 MATERIAL='CHIP',
 VALUE='33.2',
 PRIM_FILE='./archive_libs/logical/q_res/chips/chips.prt';

PART_NAME
 R3113 'Q_RES_0402LF-33.2,1%,1/16W,CHIA':;

SECTION_NUMBER 1
 '@S9S_MB_2U_LIB.S9S_MB_2U(SCH_1):PAGE233_I9@PURE_QUANTA.Q_RES(CHIPS)':
 C_PATH='@s9s_mb_2u_lib.s9s_mb_2u(sch_1):page233_i9@pure_quanta.q_res(chips)',
 P_PATH='@s9s_mb_2u_lib.s9s_mb_2u(sch_1):page245_i9@pure_quanta.q_res(chips)',
 PATH='I9',
 DRAWING='@S9S_MB_2U_LIB.S9S_MB_2U(SCH_1):PAGE233',
 PHYS_PAGE='245',
 XY='(-4100,-2125)',
 ROT='0',
 VER='1',
 PACK_TYPE='0402LF',
 LOCATION='R3113',
 CDS_LIB='pure_quanta',
 CDS_PART_NAME='Q_RES_0402LF-33.2,1%,1/16W,CHIA',
 WATTAGE='1/16W',
 TOLERANCE='1%',
 MATERIAL='CHIP',
 VALUE='33.2',
 PRIM_FILE='./archive_libs/logical/q_res/chips/chips.prt';

PART_NAME
 R3114 'Q_RES_0402LF-33.2,1%,1/16W,CHIA':;

SECTION_NUMBER 1
 '@S9S_MB_2U_LIB.S9S_MB_2U(SCH_1):PAGE233_I8@PURE_QUANTA.Q_RES(CHIPS)':
 C_PATH='@s9s_mb_2u_lib.s9s_mb_2u(sch_1):page233_i8@pure_quanta.q_res(chips)',
 P_PATH='@s9s_mb_2u_lib.s9s_mb_2u(sch_1):page245_i8@pure_quanta.q_res(chips)',
 PATH='I8',
 DRAWING='@S9S_MB_2U_LIB.S9S_MB_2U(SCH_1):PAGE233',
 PHYS_PAGE='245',
 XY='(-4100,-2225)',
 ROT='0',
 VER='1',
 PACK_TYPE='0402LF',
 LOCATION='R3114',
 CDS_LIB='pure_quanta',
 CDS_PART_NAME='Q_RES_0402LF-33.2,1%,1/16W,CHIA',
 WATTAGE='1/16W',
 TOLERANCE='1%',
 MATERIAL='CHIP',
 VALUE='33.2',
 PRIM_FILE='./archive_libs/logical/q_res/chips/chips.prt';

PART_NAME
 R3117 'Q_RES_0402LF-510K,5%,1/16W,EMPA':;

SECTION_NUMBER 1
 '@S9S_MB_2U_LIB.S9S_MB_2U(SCH_1):PAGE245_I78@PURE_QUANTA.Q_RES(CHIPS)':
 C_PATH='@s9s_mb_2u_lib.s9s_mb_2u(sch_1):page245_i78@pure_quanta.q_res(chips)',
 P_PATH='@s9s_mb_2u_lib.s9s_mb_2u(sch_1):page259_i78@pure_quanta.q_res(chips)',
 PATH='I78',
 DRAWING='@S9S_MB_2U_LIB.S9S_MB_2U(SCH_1):PAGE245',
 PHYS_PAGE='259',
 XY='(-3825,-950)',
 ROT='0',
 VER='2',
 PACK_TYPE='0402LF',
 CDS_LIB='pure_quanta',
 CDS_PART_NAME='Q_RES_0402LF-510K,5%,1/16W,EMPA',
 WATTAGE='1/16W',
 TOLERANCE='5%',
 MATERIAL='EMPTY',
 VALUE='510K',
 PRIM_FILE='./archive_libs/logical/q_res/chips/chips.prt';

PART_NAME
 R3118 'Q_RES_0402LF-86.6K,1%,1/16W,EMA':;

SECTION_NUMBER 1
 '@S9S_MB_2U_LIB.S9S_MB_2U(SCH_1):PAGE245_I76@PURE_QUANTA.Q_RES(CHIPS)':
 C_PATH='@s9s_mb_2u_lib.s9s_mb_2u(sch_1):page245_i76@pure_quanta.q_res(chips)',
 P_PATH='@s9s_mb_2u_lib.s9s_mb_2u(sch_1):page259_i76@pure_quanta.q_res(chips)',
 PATH='I76',
 DRAWING='@S9S_MB_2U_LIB.S9S_MB_2U(SCH_1):PAGE245',
 PHYS_PAGE='259',
 XY='(-3825,-1525)',
 ROT='0',
 VER='2',
 PACK_TYPE='0402LF',
 CDS_LIB='pure_quanta',
 CDS_PART_NAME='Q_RES_0402LF-86.6K,1%,1/16W,EMA',
 WATTAGE='1/16W',
 TOLERANCE='1%',
 MATERIAL='EMPTY',
 VALUE='86.6K',
 PRIM_FILE='./archive_libs/logical/q_res/chips/chips.prt';

PART_NAME
 R3123 'Q_RES_0402LF-0,5%,1/16W,CHIP,CA':;

SECTION_NUMBER 1
 '@S9S_MB_2U_LIB.S9S_MB_2U(SCH_1):PAGE224_I115@PURE_QUANTA.Q_RES(CHIPS)':
 C_PATH='@s9s_mb_2u_lib.s9s_mb_2u(sch_1):page224_i115@pure_quanta.q_res(chips)',
 P_PATH='@s9s_mb_2u_lib.s9s_mb_2u(sch_1):page236_i115@pure_quanta.q_res(chips)',
 PATH='I115',
 DRAWING='@S9S_MB_2U_LIB.S9S_MB_2U(SCH_1):PAGE224',
 PHYS_PAGE='236',
 XY='(1475,8300)',
 ROT='0',
 VER='1',
 PACK_TYPE='0402LF',
 CDS_LIB='pure_quanta',
 CDS_PART_NAME='Q_RES_0402LF-0,5%,1/16W,CHIP,CA',
 WATTAGE='1/16W',
 TOLERANCE='5%',
 MATERIAL='CHIP',
 VALUE='0',
 PRIM_FILE='./archive_libs/logical/q_res/chips/chips.prt';

PART_NAME
 R3124 'Q_RES_0402LF-0,5%,1/16W,CHIP,CA':;

SECTION_NUMBER 1
 '@S9S_MB_2U_LIB.S9S_MB_2U(SCH_1):PAGE224_I114@PURE_QUANTA.Q_RES(CHIPS)':
 C_PATH='@s9s_mb_2u_lib.s9s_mb_2u(sch_1):page224_i114@pure_quanta.q_res(chips)',
 P_PATH='@s9s_mb_2u_lib.s9s_mb_2u(sch_1):page236_i114@pure_quanta.q_res(chips)',
 PATH='I114',
 DRAWING='@S9S_MB_2U_LIB.S9S_MB_2U(SCH_1):PAGE224',
 PHYS_PAGE='236',
 XY='(1475,8250)',
 ROT='0',
 VER='1',
 PACK_TYPE='0402LF',
 CDS_LIB='pure_quanta',
 CDS_PART_NAME='Q_RES_0402LF-0,5%,1/16W,CHIP,CA',
 WATTAGE='1/16W',
 TOLERANCE='5%',
 MATERIAL='CHIP',
 VALUE='0',
 PRIM_FILE='./archive_libs/logical/q_res/chips/chips.prt';

PART_NAME
 R3125 'Q_RES_0402LF-0,5%,1/16W,CHIP,CA':;

SECTION_NUMBER 1
 '@S9S_MB_2U_LIB.S9S_MB_2U(SCH_1):PAGE224_I116@PURE_QUANTA.Q_RES(CHIPS)':
 C_PATH='@s9s_mb_2u_lib.s9s_mb_2u(sch_1):page224_i116@pure_quanta.q_res(chips)',
 P_PATH='@s9s_mb_2u_lib.s9s_mb_2u(sch_1):page236_i116@pure_quanta.q_res(chips)',
 PATH='I116',
 DRAWING='@S9S_MB_2U_LIB.S9S_MB_2U(SCH_1):PAGE224',
 PHYS_PAGE='236',
 XY='(1475,8000)',
 ROT='0',
 VER='1',
 PACK_TYPE='0402LF',
 CDS_LIB='pure_quanta',
 CDS_PART_NAME='Q_RES_0402LF-0,5%,1/16W,CHIP,CA',
 WATTAGE='1/16W',
 TOLERANCE='5%',
 MATERIAL='CHIP',
 VALUE='0',
 PRIM_FILE='./archive_libs/logical/q_res/chips/chips.prt';

PART_NAME
 R3126 'Q_RES_0402LF-0,5%,1/16W,CHIP,CA':;

SECTION_NUMBER 1
 '@S9S_MB_2U_LIB.S9S_MB_2U(SCH_1):PAGE224_I117@PURE_QUANTA.Q_RES(CHIPS)':
 C_PATH='@s9s_mb_2u_lib.s9s_mb_2u(sch_1):page224_i117@pure_quanta.q_res(chips)',
 P_PATH='@s9s_mb_2u_lib.s9s_mb_2u(sch_1):page236_i117@pure_quanta.q_res(chips)',
 PATH='I117',
 DRAWING='@S9S_MB_2U_LIB.S9S_MB_2U(SCH_1):PAGE224',
 PHYS_PAGE='236',
 XY='(1475,7950)',
 ROT='0',
 VER='1',
 PACK_TYPE='0402LF',
 CDS_LIB='pure_quanta',
 CDS_PART_NAME='Q_RES_0402LF-0,5%,1/16W,CHIP,CA',
 WATTAGE='1/16W',
 TOLERANCE='5%',
 MATERIAL='CHIP',
 VALUE='0',
 PRIM_FILE='./archive_libs/logical/q_res/chips/chips.prt';

PART_NAME
 R3127 'Q_RES_0402LF-10K,1%,1/16W,CHIPA':;

SECTION_NUMBER 1
 '@S9S_MB_2U_LIB.S9S_MB_2U(SCH_1):PAGE224_I109@PURE_QUANTA.Q_RES(CHIPS)':
 C_PATH='@s9s_mb_2u_lib.s9s_mb_2u(sch_1):page224_i109@pure_quanta.q_res(chips)',
 P_PATH='@s9s_mb_2u_lib.s9s_mb_2u(sch_1):page236_i109@pure_quanta.q_res(chips)',
 PATH='I109',
 DRAWING='@S9S_MB_2U_LIB.S9S_MB_2U(SCH_1):PAGE224',
 PHYS_PAGE='236',
 XY='(3600,9200)',
 ROT='0',
 VER='2',
 PACK_TYPE='0402LF',
 CDS_LIB='pure_quanta',
 CDS_PART_NAME='Q_RES_0402LF-10K,1%,1/16W,CHIPA',
 WATTAGE='1/16W',
 TOLERANCE='1%',
 MATERIAL='CHIP',
 VALUE='10K',
 PRIM_FILE='./archive_libs/logical/q_res/chips/chips.prt';

PART_NAME
 R3130 'Q_RES_0402LF-10K,1%,1/16W,CHIPA':;

SECTION_NUMBER 1
 '@S9S_MB_2U_LIB.S9S_MB_2U(SCH_1):PAGE224_I110@PURE_QUANTA.Q_RES(CHIPS)':
 C_PATH='@s9s_mb_2u_lib.s9s_mb_2u(sch_1):page224_i110@pure_quanta.q_res(chips)',
 P_PATH='@s9s_mb_2u_lib.s9s_mb_2u(sch_1):page236_i110@pure_quanta.q_res(chips)',
 PATH='I110',
 DRAWING='@S9S_MB_2U_LIB.S9S_MB_2U(SCH_1):PAGE224',
 PHYS_PAGE='236',
 XY='(3900,9200)',
 ROT='0',
 VER='2',
 PACK_TYPE='0402LF',
 CDS_LIB='pure_quanta',
 CDS_PART_NAME='Q_RES_0402LF-10K,1%,1/16W,CHIPA',
 WATTAGE='1/16W',
 TOLERANCE='1%',
 MATERIAL='CHIP',
 VALUE='10K',
 PRIM_FILE='./archive_libs/logical/q_res/chips/chips.prt';

PART_NAME
 R3131 'Q_RES_0402LF-10K,1%,1/16W,CHIPA':;

SECTION_NUMBER 1
 '@S9S_MB_2U_LIB.S9S_MB_2U(SCH_1):PAGE224_I111@PURE_QUANTA.Q_RES(CHIPS)':
 C_PATH='@s9s_mb_2u_lib.s9s_mb_2u(sch_1):page224_i111@pure_quanta.q_res(chips)',
 P_PATH='@s9s_mb_2u_lib.s9s_mb_2u(sch_1):page236_i111@pure_quanta.q_res(chips)',
 PATH='I111',
 DRAWING='@S9S_MB_2U_LIB.S9S_MB_2U(SCH_1):PAGE224',
 PHYS_PAGE='236',
 XY='(4200,9200)',
 ROT='0',
 VER='2',
 PACK_TYPE='0402LF',
 CDS_LIB='pure_quanta',
 CDS_PART_NAME='Q_RES_0402LF-10K,1%,1/16W,CHIPA',
 WATTAGE='1/16W',
 TOLERANCE='1%',
 MATERIAL='CHIP',
 VALUE='10K',
 PRIM_FILE='./archive_libs/logical/q_res/chips/chips.prt';

PART_NAME
 R3132 'Q_RES_0402LF-100K,1%,1/16W,CHIA':;

SECTION_NUMBER 1
 '@S9S_MB_2U_LIB.S9S_MB_2U(SCH_1):PAGE150_I35@PURE_QUANTA.Q_RES(CHIPS)':
 C_PATH='@s9s_mb_2u_lib.s9s_mb_2u(sch_1):page150_i35@pure_quanta.q_res(chips)',
 P_PATH='@s9s_mb_2u_lib.s9s_mb_2u(sch_1):page153_i35@pure_quanta.q_res(chips)',
 PATH='I35',
 DRAWING='@S9S_MB_2U_LIB.S9S_MB_2U(SCH_1):PAGE150',
 PHYS_PAGE='153',
 XY='(-4250,4425)',
 ROT='0',
 VER='1',
 PACK_TYPE='0402LF',
 CDS_LIB='pure_quanta',
 CDS_PART_NAME='Q_RES_0402LF-100K,1%,1/16W,CHIA',
 WATTAGE='1/16W',
 TOLERANCE='1%',
 MATERIAL='CHIP',
 VALUE='100K',
 PRIM_FILE='./archive_libs/logical/q_res/chips/chips.prt';

PART_NAME
 R3133 'Q_RES_0402LF-1K,1%,1/16W,CHIP,A':;

SECTION_NUMBER 1
 '@S9S_MB_2U_LIB.S9S_MB_2U(SCH_1):PAGE131_I11@PURE_QUANTA.Q_RES(CHIPS)':
 C_PATH='@s9s_mb_2u_lib.s9s_mb_2u(sch_1):page131_i11@pure_quanta.q_res(chips)',
 P_PATH='@s9s_mb_2u_lib.s9s_mb_2u(sch_1):page162_i11@pure_quanta.q_res(chips)',
 PATH='I11',
 DRAWING='@S9S_MB_2U_LIB.S9S_MB_2U(SCH_1):PAGE131',
 PHYS_PAGE='162',
 XY='(-2550,-1450)',
 ROT='0',
 VER='2',
 PACK_TYPE='0402LF',
 LOCATION='R3133',
 CDS_LIB='pure_quanta',
 CDS_PART_NAME='Q_RES_0402LF-1K,1%,1/16W,CHIP,A',
 WATTAGE='1/16W',
 TOLERANCE='1%',
 MATERIAL='CHIP',
 VALUE='1K',
 PRIM_FILE='./archive_libs/logical/q_res/chips/chips.prt';

PART_NAME
 R3134 'Q_RES_0402LF-1K,1%,1/16W,CHIP,A':;

SECTION_NUMBER 1
 '@S9S_MB_2U_LIB.S9S_MB_2U(SCH_1):PAGE131_I3@PURE_QUANTA.Q_RES(CHIPS)':
 C_PATH='@s9s_mb_2u_lib.s9s_mb_2u(sch_1):page131_i3@pure_quanta.q_res(chips)',
 P_PATH='@s9s_mb_2u_lib.s9s_mb_2u(sch_1):page162_i3@pure_quanta.q_res(chips)',
 PATH='I3',
 DRAWING='@S9S_MB_2U_LIB.S9S_MB_2U(SCH_1):PAGE131',
 PHYS_PAGE='162',
 XY='(-2550,-2350)',
 ROT='0',
 VER='2',
 PACK_TYPE='0402LF',
 LOCATION='R3134',
 CDS_LIB='pure_quanta',
 CDS_PART_NAME='Q_RES_0402LF-1K,1%,1/16W,CHIP,A',
 WATTAGE='1/16W',
 TOLERANCE='1%',
 MATERIAL='CHIP',
 VALUE='1K',
 PRIM_FILE='./archive_libs/logical/q_res/chips/chips.prt';

PART_NAME
 R3135 'Q_RES_0402LF-1K,1%,1/16W,CHIP,A':;

SECTION_NUMBER 1
 '@S9S_MB_2U_LIB.S9S_MB_2U(SCH_1):PAGE131_I13@PURE_QUANTA.Q_RES(CHIPS)':
 C_PATH='@s9s_mb_2u_lib.s9s_mb_2u(sch_1):page131_i13@pure_quanta.q_res(chips)',
 P_PATH='@s9s_mb_2u_lib.s9s_mb_2u(sch_1):page162_i13@pure_quanta.q_res(chips)',
 PATH='I13',
 DRAWING='@S9S_MB_2U_LIB.S9S_MB_2U(SCH_1):PAGE131',
 PHYS_PAGE='162',
 XY='(-2325,-1450)',
 ROT='0',
 VER='2',
 PACK_TYPE='0402LF',
 LOCATION='R3135',
 CDS_LIB='pure_quanta',
 CDS_PART_NAME='Q_RES_0402LF-1K,1%,1/16W,CHIP,A',
 WATTAGE='1/16W',
 TOLERANCE='1%',
 MATERIAL='CHIP',
 VALUE='1K',
 PRIM_FILE='./archive_libs/logical/q_res/chips/chips.prt';

PART_NAME
 R3136 'Q_RES_0402LF-1K,1%,1/16W,CHIP,A':;

SECTION_NUMBER 1
 '@S9S_MB_2U_LIB.S9S_MB_2U(SCH_1):PAGE131_I5@PURE_QUANTA.Q_RES(CHIPS)':
 C_PATH='@s9s_mb_2u_lib.s9s_mb_2u(sch_1):page131_i5@pure_quanta.q_res(chips)',
 P_PATH='@s9s_mb_2u_lib.s9s_mb_2u(sch_1):page162_i5@pure_quanta.q_res(chips)',
 PATH='I5',
 DRAWING='@S9S_MB_2U_LIB.S9S_MB_2U(SCH_1):PAGE131',
 PHYS_PAGE='162',
 XY='(-2325,-2350)',
 ROT='0',
 VER='2',
 PACK_TYPE='0402LF',
 LOCATION='R3136',
 CDS_LIB='pure_quanta',
 CDS_PART_NAME='Q_RES_0402LF-1K,1%,1/16W,CHIP,A',
 WATTAGE='1/16W',
 TOLERANCE='1%',
 MATERIAL='CHIP',
 VALUE='1K',
 PRIM_FILE='./archive_libs/logical/q_res/chips/chips.prt';

PART_NAME
 R3142 'Q_RES_0402LF-0,5%,1/16W,CHIP,CA':;

SECTION_NUMBER 1
 '@S9S_MB_2U_LIB.S9S_MB_2U(SCH_1):PAGE131_I57@PURE_QUANTA.Q_RES(CHIPS)':
 C_PATH='@s9s_mb_2u_lib.s9s_mb_2u(sch_1):page131_i57@pure_quanta.q_res(chips)',
 P_PATH='@s9s_mb_2u_lib.s9s_mb_2u(sch_1):page162_i57@pure_quanta.q_res(chips)',
 PATH='I57',
 DRAWING='@S9S_MB_2U_LIB.S9S_MB_2U(SCH_1):PAGE131',
 PHYS_PAGE='162',
 XY='(400,-2300)',
 ROT='0',
 VER='1',
 PACK_TYPE='0402LF',
 CDS_LIB='pure_quanta',
 CDS_PART_NAME='Q_RES_0402LF-0,5%,1/16W,CHIP,CA',
 WATTAGE='1/16W',
 TOLERANCE='5%',
 MATERIAL='CHIP',
 VALUE='0',
 PRIM_FILE='./archive_libs/logical/q_res/chips/chips.prt';

PART_NAME
 R3143 'Q_RES_0402LF-0,5%,1/16W,CHIP,CA':;

SECTION_NUMBER 1
 '@S9S_MB_2U_LIB.S9S_MB_2U(SCH_1):PAGE131_I56@PURE_QUANTA.Q_RES(CHIPS)':
 C_PATH='@s9s_mb_2u_lib.s9s_mb_2u(sch_1):page131_i56@pure_quanta.q_res(chips)',
 P_PATH='@s9s_mb_2u_lib.s9s_mb_2u(sch_1):page162_i56@pure_quanta.q_res(chips)',
 PATH='I56',
 DRAWING='@S9S_MB_2U_LIB.S9S_MB_2U(SCH_1):PAGE131',
 PHYS_PAGE='162',
 XY='(425,-2150)',
 ROT='0',
 VER='1',
 PACK_TYPE='0402LF',
 CDS_LIB='pure_quanta',
 CDS_PART_NAME='Q_RES_0402LF-0,5%,1/16W,CHIP,CA',
 WATTAGE='1/16W',
 TOLERANCE='5%',
 MATERIAL='CHIP',
 VALUE='0',
 PRIM_FILE='./archive_libs/logical/q_res/chips/chips.prt';

PART_NAME
 R3144 'Q_RES_0402LF-0,5%,1/16W,EMPTY,A':
 ROOM='NIC1_P12V_MAM_MAM_BOM1';

SECTION_NUMBER 1
 '@S9S_MB_2U_LIB.S9S_MB_2U(SCH_1):PAGE153_I82@PURE_QUANTA.Q_RES(CHIPS)':
 C_PATH='@s9s_mb_2u_lib.s9s_mb_2u(sch_1):page153_i82@pure_quanta.q_res(chips)',
 P_PATH='@s9s_mb_2u_lib.s9s_mb_2u(sch_1):page156_i82@pure_quanta.q_res(chips)',
 PATH='I82',
 DRAWING='@S9S_MB_2U_LIB.S9S_MB_2U(SCH_1):PAGE153',
 ROOM1='NIC1_P12V_MAM_TIC_BOM2',
 PHYS_PAGE='156',
 XY='(9025,10700)',
 ROT='0',
 VER='1',
 PACK_TYPE='0402LF',
 LOCATION='R3144',
 CDS_LIB='pure_quanta',
 CDS_PART_NAME='Q_RES_0402LF-0,5%,1/16W,EMPTY,A',
 WATTAGE='1/16W',
 TOLERANCE='5%',
 MATERIAL='EMPTY',
 ROOM='NIC1_P12V_MAM_MAM_BOM1',
 VALUE='0',
 PRIM_FILE='./archive_libs/logical/q_res/chips/chips.prt';

PART_NAME
 R3145 'Q_RES_0402LF-10K,1%,1/16W,CHIPA':;

SECTION_NUMBER 1
 '@S9S_MB_2U_LIB.S9S_MB_2U(SCH_1):PAGE131_I64@PURE_QUANTA.Q_RES(CHIPS)':
 C_PATH='@s9s_mb_2u_lib.s9s_mb_2u(sch_1):page131_i64@pure_quanta.q_res(chips)',
 P_PATH='@s9s_mb_2u_lib.s9s_mb_2u(sch_1):page162_i64@pure_quanta.q_res(chips)',
 PATH='I64',
 DRAWING='@S9S_MB_2U_LIB.S9S_MB_2U(SCH_1):PAGE131',
 PHYS_PAGE='162',
 XY='(1675,-1875)',
 ROT='0',
 VER='2',
 PACK_TYPE='0402LF',
 CDS_LIB='pure_quanta',
 CDS_PART_NAME='Q_RES_0402LF-10K,1%,1/16W,CHIPA',
 WATTAGE='1/16W',
 TOLERANCE='1%',
 MATERIAL='CHIP',
 VALUE='10K',
 PRIM_FILE='./archive_libs/logical/q_res/chips/chips.prt';

PART_NAME
 R3147 'Q_RES_0402LF-10K,1%,1/16W,CHIPA':;

SECTION_NUMBER 1
 '@S9S_MB_2U_LIB.S9S_MB_2U(SCH_1):PAGE131_I66@PURE_QUANTA.Q_RES(CHIPS)':
 C_PATH='@s9s_mb_2u_lib.s9s_mb_2u(sch_1):page131_i66@pure_quanta.q_res(chips)',
 P_PATH='@s9s_mb_2u_lib.s9s_mb_2u(sch_1):page162_i66@pure_quanta.q_res(chips)',
 PATH='I66',
 DRAWING='@S9S_MB_2U_LIB.S9S_MB_2U(SCH_1):PAGE131',
 PHYS_PAGE='162',
 XY='(1900,-1875)',
 ROT='0',
 VER='2',
 PACK_TYPE='0402LF',
 CDS_LIB='pure_quanta',
 CDS_PART_NAME='Q_RES_0402LF-10K,1%,1/16W,CHIPA',
 WATTAGE='1/16W',
 TOLERANCE='1%',
 MATERIAL='CHIP',
 VALUE='10K',
 PRIM_FILE='./archive_libs/logical/q_res/chips/chips.prt';

PART_NAME
 R3149 'Q_RES_0402LF-1K,1%,1/16W,EMPTYA':;

SECTION_NUMBER 1
 '@S9S_MB_2U_LIB.S9S_MB_2U(SCH_1):PAGE132_I29@PURE_QUANTA.Q_RES(CHIPS)':
 C_PATH='@s9s_mb_2u_lib.s9s_mb_2u(sch_1):page132_i29@pure_quanta.q_res(chips)',
 P_PATH='@s9s_mb_2u_lib.s9s_mb_2u(sch_1):page164_i29@pure_quanta.q_res(chips)',
 PATH='I29',
 DRAWING='@S9S_MB_2U_LIB.S9S_MB_2U(SCH_1):PAGE132',
 PHYS_PAGE='164',
 XY='(-5175,3475)',
 ROT='0',
 VER='2',
 PACK_TYPE='0402LF',
 CDS_LIB='pure_quanta',
 CDS_PART_NAME='Q_RES_0402LF-1K,1%,1/16W,EMPTYA',
 WATTAGE='1/16W',
 TOLERANCE='1%',
 MATERIAL='EMPTY',
 VALUE='1K',
 PRIM_FILE='./archive_libs/logical/q_res/chips/chips.prt';

PART_NAME
 R3150 'Q_RES_0402LF-1K,1%,1/16W,CHIP,A':;

SECTION_NUMBER 1
 '@S9S_MB_2U_LIB.S9S_MB_2U(SCH_1):PAGE132_I25@PURE_QUANTA.Q_RES(CHIPS)':
 C_PATH='@s9s_mb_2u_lib.s9s_mb_2u(sch_1):page132_i25@pure_quanta.q_res(chips)',
 P_PATH='@s9s_mb_2u_lib.s9s_mb_2u(sch_1):page164_i25@pure_quanta.q_res(chips)',
 PATH='I25',
 DRAWING='@S9S_MB_2U_LIB.S9S_MB_2U(SCH_1):PAGE132',
 PHYS_PAGE='164',
 XY='(-5175,2875)',
 ROT='0',
 VER='2',
 PACK_TYPE='0402LF',
 CDS_LIB='pure_quanta',
 CDS_PART_NAME='Q_RES_0402LF-1K,1%,1/16W,CHIP,A',
 WATTAGE='1/16W',
 TOLERANCE='1%',
 MATERIAL='CHIP',
 VALUE='1K',
 PRIM_FILE='./archive_libs/logical/q_res/chips/chips.prt';

PART_NAME
 R3151 'Q_RES_0402LF-1K,1%,1/16W,EMPTYA':;

SECTION_NUMBER 1
 '@S9S_MB_2U_LIB.S9S_MB_2U(SCH_1):PAGE132_I31@PURE_QUANTA.Q_RES(CHIPS)':
 C_PATH='@s9s_mb_2u_lib.s9s_mb_2u(sch_1):page132_i31@pure_quanta.q_res(chips)',
 P_PATH='@s9s_mb_2u_lib.s9s_mb_2u(sch_1):page164_i31@pure_quanta.q_res(chips)',
 PATH='I31',
 DRAWING='@S9S_MB_2U_LIB.S9S_MB_2U(SCH_1):PAGE132',
 PHYS_PAGE='164',
 XY='(-4925,3475)',
 ROT='0',
 VER='2',
 PACK_TYPE='0402LF',
 CDS_LIB='pure_quanta',
 CDS_PART_NAME='Q_RES_0402LF-1K,1%,1/16W,EMPTYA',
 WATTAGE='1/16W',
 TOLERANCE='1%',
 MATERIAL='EMPTY',
 VALUE='1K',
 PRIM_FILE='./archive_libs/logical/q_res/chips/chips.prt';

PART_NAME
 R3152 'Q_RES_0402LF-1K,1%,1/16W,CHIP,A':;

SECTION_NUMBER 1
 '@S9S_MB_2U_LIB.S9S_MB_2U(SCH_1):PAGE132_I27@PURE_QUANTA.Q_RES(CHIPS)':
 C_PATH='@s9s_mb_2u_lib.s9s_mb_2u(sch_1):page132_i27@pure_quanta.q_res(chips)',
 P_PATH='@s9s_mb_2u_lib.s9s_mb_2u(sch_1):page164_i27@pure_quanta.q_res(chips)',
 PATH='I27',
 DRAWING='@S9S_MB_2U_LIB.S9S_MB_2U(SCH_1):PAGE132',
 PHYS_PAGE='164',
 XY='(-4925,2875)',
 ROT='0',
 VER='2',
 PACK_TYPE='0402LF',
 CDS_LIB='pure_quanta',
 CDS_PART_NAME='Q_RES_0402LF-1K,1%,1/16W,CHIP,A',
 WATTAGE='1/16W',
 TOLERANCE='1%',
 MATERIAL='CHIP',
 VALUE='1K',
 PRIM_FILE='./archive_libs/logical/q_res/chips/chips.prt';

PART_NAME
 R3153 'Q_RES_0402LF-1K,1%,1/16W,EMPTYA':;

SECTION_NUMBER 1
 '@S9S_MB_2U_LIB.S9S_MB_2U(SCH_1):PAGE132_I32@PURE_QUANTA.Q_RES(CHIPS)':
 C_PATH='@s9s_mb_2u_lib.s9s_mb_2u(sch_1):page132_i32@pure_quanta.q_res(chips)',
 P_PATH='@s9s_mb_2u_lib.s9s_mb_2u(sch_1):page164_i32@pure_quanta.q_res(chips)',
 PATH='I32',
 DRAWING='@S9S_MB_2U_LIB.S9S_MB_2U(SCH_1):PAGE132',
 PHYS_PAGE='164',
 XY='(-4675,3475)',
 ROT='0',
 VER='2',
 PACK_TYPE='0402LF',
 CDS_LIB='pure_quanta',
 CDS_PART_NAME='Q_RES_0402LF-1K,1%,1/16W,EMPTYA',
 WATTAGE='1/16W',
 TOLERANCE='1%',
 MATERIAL='EMPTY',
 VALUE='1K',
 PRIM_FILE='./archive_libs/logical/q_res/chips/chips.prt';

PART_NAME
 R3154 'Q_RES_0402LF-1K,1%,1/16W,CHIP,A':;

SECTION_NUMBER 1
 '@S9S_MB_2U_LIB.S9S_MB_2U(SCH_1):PAGE132_I65@PURE_QUANTA.Q_RES(CHIPS)':
 C_PATH='@s9s_mb_2u_lib.s9s_mb_2u(sch_1):page132_i65@pure_quanta.q_res(chips)',
 P_PATH='@s9s_mb_2u_lib.s9s_mb_2u(sch_1):page164_i65@pure_quanta.q_res(chips)',
 PATH='I65',
 DRAWING='@S9S_MB_2U_LIB.S9S_MB_2U(SCH_1):PAGE132',
 PHYS_PAGE='164',
 XY='(-4675,2875)',
 ROT='0',
 VER='2',
 PACK_TYPE='0402LF',
 CDS_LIB='pure_quanta',
 CDS_PART_NAME='Q_RES_0402LF-1K,1%,1/16W,CHIP,A',
 WATTAGE='1/16W',
 TOLERANCE='1%',
 MATERIAL='CHIP',
 VALUE='1K',
 PRIM_FILE='./archive_libs/logical/q_res/chips/chips.prt';

PART_NAME
 R3155 'Q_RES_0402LF-1K,1%,1/16W,CHIP,A':;

SECTION_NUMBER 1
 '@S9S_MB_2U_LIB.S9S_MB_2U(SCH_1):PAGE132_I7@PURE_QUANTA.Q_RES(CHIPS)':
 C_PATH='@s9s_mb_2u_lib.s9s_mb_2u(sch_1):page132_i7@pure_quanta.q_res(chips)',
 P_PATH='@s9s_mb_2u_lib.s9s_mb_2u(sch_1):page164_i7@pure_quanta.q_res(chips)',
 PATH='I7',
 DRAWING='@S9S_MB_2U_LIB.S9S_MB_2U(SCH_1):PAGE132',
 PHYS_PAGE='164',
 XY='(-4250,-700)',
 ROT='0',
 VER='2',
 PACK_TYPE='0402LF',
 CDS_LIB='pure_quanta',
 CDS_PART_NAME='Q_RES_0402LF-1K,1%,1/16W,CHIP,A',
 WATTAGE='1/16W',
 TOLERANCE='1%',
 MATERIAL='CHIP',
 VALUE='1K',
 PRIM_FILE='./archive_libs/logical/q_res/chips/chips.prt';

PART_NAME
 R3156 'Q_RES_0402LF-33.2,1%,1/16W,CHIA':;

SECTION_NUMBER 1
 '@S9S_MB_2U_LIB.S9S_MB_2U(SCH_1):PAGE132_I34@PURE_QUANTA.Q_RES(CHIPS)':
 C_PATH='@s9s_mb_2u_lib.s9s_mb_2u(sch_1):page132_i34@pure_quanta.q_res(chips)',
 P_PATH='@s9s_mb_2u_lib.s9s_mb_2u(sch_1):page164_i34@pure_quanta.q_res(chips)',
 PATH='I34',
 DRAWING='@S9S_MB_2U_LIB.S9S_MB_2U(SCH_1):PAGE132',
 PHYS_PAGE='164',
 XY='(-3150,2175)',
 ROT='0',
 VER='1',
 PACK_TYPE='0402LF',
 CDS_LIB='pure_quanta',
 CDS_PART_NAME='Q_RES_0402LF-33.2,1%,1/16W,CHIA',
 WATTAGE='1/16W',
 TOLERANCE='1%',
 MATERIAL='CHIP',
 VALUE='33.2',
 PRIM_FILE='./archive_libs/logical/q_res/chips/chips.prt';

PART_NAME
 R3157 'Q_RES_0402LF-33.2,1%,1/16W,CHIA':;

SECTION_NUMBER 1
 '@S9S_MB_2U_LIB.S9S_MB_2U(SCH_1):PAGE132_I33@PURE_QUANTA.Q_RES(CHIPS)':
 C_PATH='@s9s_mb_2u_lib.s9s_mb_2u(sch_1):page132_i33@pure_quanta.q_res(chips)',
 P_PATH='@s9s_mb_2u_lib.s9s_mb_2u(sch_1):page164_i33@pure_quanta.q_res(chips)',
 PATH='I33',
 DRAWING='@S9S_MB_2U_LIB.S9S_MB_2U(SCH_1):PAGE132',
 PHYS_PAGE='164',
 XY='(-3150,2125)',
 ROT='0',
 VER='1',
 PACK_TYPE='0402LF',
 CDS_LIB='pure_quanta',
 CDS_PART_NAME='Q_RES_0402LF-33.2,1%,1/16W,CHIA',
 WATTAGE='1/16W',
 TOLERANCE='1%',
 MATERIAL='CHIP',
 VALUE='33.2',
 PRIM_FILE='./archive_libs/logical/q_res/chips/chips.prt';

PART_NAME
 R3158 'Q_RES_0402LF-33.2,1%,1/16W,CHIA':;

SECTION_NUMBER 1
 '@S9S_MB_2U_LIB.S9S_MB_2U(SCH_1):PAGE132_I23@PURE_QUANTA.Q_RES(CHIPS)':
 C_PATH='@s9s_mb_2u_lib.s9s_mb_2u(sch_1):page132_i23@pure_quanta.q_res(chips)',
 P_PATH='@s9s_mb_2u_lib.s9s_mb_2u(sch_1):page164_i23@pure_quanta.q_res(chips)',
 PATH='I23',
 DRAWING='@S9S_MB_2U_LIB.S9S_MB_2U(SCH_1):PAGE132',
 PHYS_PAGE='164',
 XY='(-3150,2075)',
 ROT='0',
 VER='1',
 PACK_TYPE='0402LF',
 CDS_LIB='pure_quanta',
 CDS_PART_NAME='Q_RES_0402LF-33.2,1%,1/16W,CHIA',
 WATTAGE='1/16W',
 TOLERANCE='1%',
 MATERIAL='CHIP',
 VALUE='33.2',
 PRIM_FILE='./archive_libs/logical/q_res/chips/chips.prt';

PART_NAME
 R3160 'Q_RES_0402LF-1K,1%,1/16W,EMPTYA':;

SECTION_NUMBER 1
 '@S9S_MB_2U_LIB.S9S_MB_2U(SCH_1):PAGE154_I235@PURE_QUANTA.Q_RES(CHIPS)':
 C_PATH='@s9s_mb_2u_lib.s9s_mb_2u(sch_1):page154_i235@pure_quanta.q_res(chips)',
 P_PATH='@s9s_mb_2u_lib.s9s_mb_2u(sch_1):page158_i235@pure_quanta.q_res(chips)',
 PATH='I235',
 DRAWING='@S9S_MB_2U_LIB.S9S_MB_2U(SCH_1):PAGE154',
 PHYS_PAGE='158',
 XY='(-1325,7800)',
 ROT='0',
 VER='2',
 PACK_TYPE='0402LF',
 CDS_LIB='pure_quanta',
 CDS_PART_NAME='Q_RES_0402LF-1K,1%,1/16W,EMPTYA',
 WATTAGE='1/16W',
 TOLERANCE='1%',
 MATERIAL='EMPTY',
 VALUE='1K',
 PRIM_FILE='./archive_libs/logical/q_res/chips/chips.prt';

PART_NAME
 R3162 'Q_RES_0402LF-4.7K,1%,1/16W,CHIA':;

SECTION_NUMBER 1
 '@S9S_MB_2U_LIB.S9S_MB_2U(SCH_1):PAGE146_I26@PURE_QUANTA.Q_RES(CHIPS)':
 C_PATH='@s9s_mb_2u_lib.s9s_mb_2u(sch_1):page146_i26@pure_quanta.q_res(chips)',
 P_PATH='@s9s_mb_2u_lib.s9s_mb_2u(sch_1):page159_i26@pure_quanta.q_res(chips)',
 PATH='I26',
 DRAWING='@S9S_MB_2U_LIB.S9S_MB_2U(SCH_1):PAGE146',
 PHYS_PAGE='159',
 XY='(300,350)',
 ROT='0',
 VER='2',
 PACK_TYPE='0402LF',
 CDS_LIB='pure_quanta',
 CDS_PART_NAME='Q_RES_0402LF-4.7K,1%,1/16W,CHIA',
 WATTAGE='1/16W',
 TOLERANCE='1%',
 MATERIAL='CHIP',
 VALUE='4.7K',
 PRIM_FILE='./archive_libs/logical/q_res/chips/chips.prt';

PART_NAME
 R3163 'Q_RES_0402LF-4.7K,1%,1/16W,EMPA':;

SECTION_NUMBER 1
 '@S9S_MB_2U_LIB.S9S_MB_2U(SCH_1):PAGE146_I25@PURE_QUANTA.Q_RES(CHIPS)':
 C_PATH='@s9s_mb_2u_lib.s9s_mb_2u(sch_1):page146_i25@pure_quanta.q_res(chips)',
 P_PATH='@s9s_mb_2u_lib.s9s_mb_2u(sch_1):page159_i25@pure_quanta.q_res(chips)',
 PATH='I25',
 DRAWING='@S9S_MB_2U_LIB.S9S_MB_2U(SCH_1):PAGE146',
 PHYS_PAGE='159',
 XY='(300,-175)',
 ROT='0',
 VER='2',
 PACK_TYPE='0402LF',
 CDS_LIB='pure_quanta',
 CDS_PART_NAME='Q_RES_0402LF-4.7K,1%,1/16W,EMPA',
 WATTAGE='1/16W',
 TOLERANCE='1%',
 MATERIAL='EMPTY',
 VALUE='4.7K',
 PRIM_FILE='./archive_libs/logical/q_res/chips/chips.prt';

PART_NAME
 R3164 'Q_RES_0402LF-10K,1%,1/16W,CHIPA':;

SECTION_NUMBER 1
 '@S9S_MB_2U_LIB.S9S_MB_2U(SCH_1):PAGE146_I38@PURE_QUANTA.Q_RES(CHIPS)':
 C_PATH='@s9s_mb_2u_lib.s9s_mb_2u(sch_1):page146_i38@pure_quanta.q_res(chips)',
 P_PATH='@s9s_mb_2u_lib.s9s_mb_2u(sch_1):page159_i38@pure_quanta.q_res(chips)',
 PATH='I38',
 DRAWING='@S9S_MB_2U_LIB.S9S_MB_2U(SCH_1):PAGE146',
 PHYS_PAGE='159',
 XY='(750,2900)',
 ROT='0',
 VER='1',
 PACK_TYPE='0402LF',
 CDS_LIB='pure_quanta',
 CDS_PART_NAME='Q_RES_0402LF-10K,1%,1/16W,CHIPA',
 WATTAGE='1/16W',
 TOLERANCE='1%',
 MATERIAL='CHIP',
 VALUE='10K',
 PRIM_FILE='./archive_libs/logical/q_res/chips/chips.prt';

PART_NAME
 R3165 'Q_RES_0402LF-10K,1%,1/16W,CHIPA':;

SECTION_NUMBER 1
 '@S9S_MB_2U_LIB.S9S_MB_2U(SCH_1):PAGE146_I37@PURE_QUANTA.Q_RES(CHIPS)':
 C_PATH='@s9s_mb_2u_lib.s9s_mb_2u(sch_1):page146_i37@pure_quanta.q_res(chips)',
 P_PATH='@s9s_mb_2u_lib.s9s_mb_2u(sch_1):page159_i37@pure_quanta.q_res(chips)',
 PATH='I37',
 DRAWING='@S9S_MB_2U_LIB.S9S_MB_2U(SCH_1):PAGE146',
 PHYS_PAGE='159',
 XY='(750,2800)',
 ROT='0',
 VER='1',
 PACK_TYPE='0402LF',
 CDS_LIB='pure_quanta',
 CDS_PART_NAME='Q_RES_0402LF-10K,1%,1/16W,CHIPA',
 WATTAGE='1/16W',
 TOLERANCE='1%',
 MATERIAL='CHIP',
 VALUE='10K',
 PRIM_FILE='./archive_libs/logical/q_res/chips/chips.prt';

PART_NAME
 R3166 'Q_RES_0402LF-4.7K,1%,1/16W,EMPA':;

SECTION_NUMBER 1
 '@S9S_MB_2U_LIB.S9S_MB_2U(SCH_1):PAGE146_I23@PURE_QUANTA.Q_RES(CHIPS)':
 C_PATH='@s9s_mb_2u_lib.s9s_mb_2u(sch_1):page146_i23@pure_quanta.q_res(chips)',
 P_PATH='@s9s_mb_2u_lib.s9s_mb_2u(sch_1):page159_i23@pure_quanta.q_res(chips)',
 PATH='I23',
 DRAWING='@S9S_MB_2U_LIB.S9S_MB_2U(SCH_1):PAGE146',
 PHYS_PAGE='159',
 XY='(775,350)',
 ROT='0',
 VER='2',
 PACK_TYPE='0402LF',
 CDS_LIB='pure_quanta',
 CDS_PART_NAME='Q_RES_0402LF-4.7K,1%,1/16W,EMPA',
 WATTAGE='1/16W',
 TOLERANCE='1%',
 MATERIAL='EMPTY',
 VALUE='4.7K',
 PRIM_FILE='./archive_libs/logical/q_res/chips/chips.prt';

PART_NAME
 R3167 'Q_RES_0402LF-4.7K,1%,1/16W,CHIA':;

SECTION_NUMBER 1
 '@S9S_MB_2U_LIB.S9S_MB_2U(SCH_1):PAGE146_I20@PURE_QUANTA.Q_RES(CHIPS)':
 C_PATH='@s9s_mb_2u_lib.s9s_mb_2u(sch_1):page146_i20@pure_quanta.q_res(chips)',
 P_PATH='@s9s_mb_2u_lib.s9s_mb_2u(sch_1):page159_i20@pure_quanta.q_res(chips)',
 PATH='I20',
 DRAWING='@S9S_MB_2U_LIB.S9S_MB_2U(SCH_1):PAGE146',
 PHYS_PAGE='159',
 XY='(775,-175)',
 ROT='0',
 VER='2',
 PACK_TYPE='0402LF',
 CDS_LIB='pure_quanta',
 CDS_PART_NAME='Q_RES_0402LF-4.7K,1%,1/16W,CHIA',
 WATTAGE='1/16W',
 TOLERANCE='1%',
 MATERIAL='CHIP',
 VALUE='4.7K',
 PRIM_FILE='./archive_libs/logical/q_res/chips/chips.prt';

PART_NAME
 R3168 'Q_RES_0402LF-0,5%,1/16W,CHIP,CA':;

SECTION_NUMBER 1
 '@S9S_MB_2U_LIB.S9S_MB_2U(SCH_1):PAGE146_I5@PURE_QUANTA.Q_RES(CHIPS)':
 C_PATH='@s9s_mb_2u_lib.s9s_mb_2u(sch_1):page146_i5@pure_quanta.q_res(chips)',
 P_PATH='@s9s_mb_2u_lib.s9s_mb_2u(sch_1):page159_i5@pure_quanta.q_res(chips)',
 PATH='I5',
 DRAWING='@S9S_MB_2U_LIB.S9S_MB_2U(SCH_1):PAGE146',
 PHYS_PAGE='159',
 XY='(1975,5125)',
 ROT='0',
 VER='1',
 PACK_TYPE='0402LF',
 CDS_LIB='pure_quanta',
 CDS_PART_NAME='Q_RES_0402LF-0,5%,1/16W,CHIP,CA',
 WATTAGE='1/16W',
 TOLERANCE='5%',
 MATERIAL='CHIP',
 VALUE='0',
 PRIM_FILE='./archive_libs/logical/q_res/chips/chips.prt';

PART_NAME
 R3169 'Q_RES_0402LF-0,5%,1/16W,CHIP,CA':;

SECTION_NUMBER 1
 '@S9S_MB_2U_LIB.S9S_MB_2U(SCH_1):PAGE146_I33@PURE_QUANTA.Q_RES(CHIPS)':
 C_PATH='@s9s_mb_2u_lib.s9s_mb_2u(sch_1):page146_i33@pure_quanta.q_res(chips)',
 P_PATH='@s9s_mb_2u_lib.s9s_mb_2u(sch_1):page159_i33@pure_quanta.q_res(chips)',
 PATH='I33',
 DRAWING='@S9S_MB_2U_LIB.S9S_MB_2U(SCH_1):PAGE146',
 PHYS_PAGE='159',
 XY='(1975,4075)',
 ROT='0',
 VER='1',
 PACK_TYPE='0402LF',
 CDS_LIB='pure_quanta',
 CDS_PART_NAME='Q_RES_0402LF-0,5%,1/16W,CHIP,CA',
 WATTAGE='1/16W',
 TOLERANCE='5%',
 MATERIAL='CHIP',
 VALUE='0',
 PRIM_FILE='./archive_libs/logical/q_res/chips/chips.prt';

PART_NAME
 R3170 'Q_RES_0402LF-0,5%,1/16W,CHIP,CA':;

SECTION_NUMBER 1
 '@S9S_MB_2U_LIB.S9S_MB_2U(SCH_1):PAGE146_I32@PURE_QUANTA.Q_RES(CHIPS)':
 C_PATH='@s9s_mb_2u_lib.s9s_mb_2u(sch_1):page146_i32@pure_quanta.q_res(chips)',
 P_PATH='@s9s_mb_2u_lib.s9s_mb_2u(sch_1):page159_i32@pure_quanta.q_res(chips)',
 PATH='I32',
 DRAWING='@S9S_MB_2U_LIB.S9S_MB_2U(SCH_1):PAGE146',
 PHYS_PAGE='159',
 XY='(1975,4025)',
 ROT='0',
 VER='1',
 PACK_TYPE='0402LF',
 CDS_LIB='pure_quanta',
 CDS_PART_NAME='Q_RES_0402LF-0,5%,1/16W,CHIP,CA',
 WATTAGE='1/16W',
 TOLERANCE='5%',
 MATERIAL='CHIP',
 VALUE='0',
 PRIM_FILE='./archive_libs/logical/q_res/chips/chips.prt';

PART_NAME
 R3171 'Q_RES_0402LF-0,5%,1/16W,CHIP,CA':;

SECTION_NUMBER 1
 '@S9S_MB_2U_LIB.S9S_MB_2U(SCH_1):PAGE146_I31@PURE_QUANTA.Q_RES(CHIPS)':
 C_PATH='@s9s_mb_2u_lib.s9s_mb_2u(sch_1):page146_i31@pure_quanta.q_res(chips)',
 P_PATH='@s9s_mb_2u_lib.s9s_mb_2u(sch_1):page159_i31@pure_quanta.q_res(chips)',
 PATH='I31',
 DRAWING='@S9S_MB_2U_LIB.S9S_MB_2U(SCH_1):PAGE146',
 PHYS_PAGE='159',
 XY='(1975,3975)',
 ROT='0',
 VER='1',
 PACK_TYPE='0402LF',
 CDS_LIB='pure_quanta',
 CDS_PART_NAME='Q_RES_0402LF-0,5%,1/16W,CHIP,CA',
 WATTAGE='1/16W',
 TOLERANCE='5%',
 MATERIAL='CHIP',
 VALUE='0',
 PRIM_FILE='./archive_libs/logical/q_res/chips/chips.prt';

PART_NAME
 R3172 'Q_RES_0402LF-0,5%,1/16W,CHIP,CA':;

SECTION_NUMBER 1
 '@S9S_MB_2U_LIB.S9S_MB_2U(SCH_1):PAGE146_I36@PURE_QUANTA.Q_RES(CHIPS)':
 C_PATH='@s9s_mb_2u_lib.s9s_mb_2u(sch_1):page146_i36@pure_quanta.q_res(chips)',
 P_PATH='@s9s_mb_2u_lib.s9s_mb_2u(sch_1):page159_i36@pure_quanta.q_res(chips)',
 PATH='I36',
 DRAWING='@S9S_MB_2U_LIB.S9S_MB_2U(SCH_1):PAGE146',
 PHYS_PAGE='159',
 XY='(1975,3825)',
 ROT='0',
 VER='1',
 PACK_TYPE='0402LF',
 CDS_LIB='pure_quanta',
 CDS_PART_NAME='Q_RES_0402LF-0,5%,1/16W,CHIP,CA',
 WATTAGE='1/16W',
 TOLERANCE='5%',
 MATERIAL='CHIP',
 VALUE='0',
 PRIM_FILE='./archive_libs/logical/q_res/chips/chips.prt';

PART_NAME
 R3173 'Q_RES_0402LF-1K,1%,1/16W,CHIP,A':;

SECTION_NUMBER 1
 '@S9S_MB_2U_LIB.S9S_MB_2U(SCH_1):PAGE146_I165@PURE_QUANTA.Q_RES(CHIPS)':
 C_PATH='@s9s_mb_2u_lib.s9s_mb_2u(sch_1):page146_i165@pure_quanta.q_res(chips)',
 P_PATH='@s9s_mb_2u_lib.s9s_mb_2u(sch_1):page159_i165@pure_quanta.q_res(chips)',
 PATH='I165',
 DRAWING='@S9S_MB_2U_LIB.S9S_MB_2U(SCH_1):PAGE146',
 PHYS_PAGE='159',
 XY='(3675,-50)',
 ROT='0',
 VER='1',
 PACK_TYPE='0402LF',
 CDS_LIB='pure_quanta',
 CDS_PART_NAME='Q_RES_0402LF-1K,1%,1/16W,CHIP,A',
 WATTAGE='1/16W',
 TOLERANCE='1%',
 MATERIAL='CHIP',
 VALUE='1K',
 PRIM_FILE='./archive_libs/logical/q_res/chips/chips.prt';

PART_NAME
 R3174 'Q_RES_0402LF-10K,1%,1/16W,CHIPA':;

SECTION_NUMBER 1
 '@S9S_MB_2U_LIB.S9S_MB_2U(SCH_1):PAGE146_I333@PURE_QUANTA.Q_RES(CHIPS)':
 C_PATH='@s9s_mb_2u_lib.s9s_mb_2u(sch_1):page146_i333@pure_quanta.q_res(chips)',
 P_PATH='@s9s_mb_2u_lib.s9s_mb_2u(sch_1):page159_i333@pure_quanta.q_res(chips)',
 PATH='I333',
 DRAWING='@S9S_MB_2U_LIB.S9S_MB_2U(SCH_1):PAGE146',
 PHYS_PAGE='159',
 XY='(3675,-225)',
 ROT='0',
 VER='1',
 PACK_TYPE='0402LF',
 LOCATION='R3174',
 CDS_LIB='pure_quanta',
 CDS_PART_NAME='Q_RES_0402LF-10K,1%,1/16W,CHIPA',
 WATTAGE='1/16W',
 TOLERANCE='1%',
 MATERIAL='CHIP',
 VALUE='10K',
 PRIM_FILE='./archive_libs/logical/q_res/chips/chips.prt';

PART_NAME
 R3175 'Q_RES_0402LF-10K,1%,1/16W,CHIPA':;

SECTION_NUMBER 1
 '@S9S_MB_2U_LIB.S9S_MB_2U(SCH_1):PAGE146_I334@PURE_QUANTA.Q_RES(CHIPS)':
 C_PATH='@s9s_mb_2u_lib.s9s_mb_2u(sch_1):page146_i334@pure_quanta.q_res(chips)',
 P_PATH='@s9s_mb_2u_lib.s9s_mb_2u(sch_1):page159_i334@pure_quanta.q_res(chips)',
 PATH='I334',
 DRAWING='@S9S_MB_2U_LIB.S9S_MB_2U(SCH_1):PAGE146',
 PHYS_PAGE='159',
 XY='(3700,-575)',
 ROT='0',
 VER='1',
 PACK_TYPE='0402LF',
 LOCATION='R3175',
 CDS_LIB='pure_quanta',
 CDS_PART_NAME='Q_RES_0402LF-10K,1%,1/16W,CHIPA',
 WATTAGE='1/16W',
 TOLERANCE='1%',
 MATERIAL='CHIP',
 VALUE='10K',
 PRIM_FILE='./archive_libs/logical/q_res/chips/chips.prt';

PART_NAME
 R3176 'Q_RES_0402LF-1K,1%,1/16W,CHIP,A':;

SECTION_NUMBER 1
 '@S9S_MB_2U_LIB.S9S_MB_2U(SCH_1):PAGE146_I336@PURE_QUANTA.Q_RES(CHIPS)':
 C_PATH='@s9s_mb_2u_lib.s9s_mb_2u(sch_1):page146_i336@pure_quanta.q_res(chips)',
 P_PATH='@s9s_mb_2u_lib.s9s_mb_2u(sch_1):page159_i336@pure_quanta.q_res(chips)',
 PATH='I336',
 DRAWING='@S9S_MB_2U_LIB.S9S_MB_2U(SCH_1):PAGE146',
 PHYS_PAGE='159',
 XY='(3700,-400)',
 ROT='0',
 VER='1',
 PACK_TYPE='0402LF',
 LOCATION='R3176',
 CDS_LIB='pure_quanta',
 CDS_PART_NAME='Q_RES_0402LF-1K,1%,1/16W,CHIP,A',
 WATTAGE='1/16W',
 TOLERANCE='1%',
 MATERIAL='CHIP',
 VALUE='1K',
 PRIM_FILE='./archive_libs/logical/q_res/chips/chips.prt';

PART_NAME
 R3177 'Q_RES_0402LF-0,5%,1/16W,CHIP,CA':;

SECTION_NUMBER 1
 '@S9S_MB_2U_LIB.S9S_MB_2U(SCH_1):PAGE146_I148@PURE_QUANTA.Q_RES(CHIPS)':
 C_PATH='@s9s_mb_2u_lib.s9s_mb_2u(sch_1):page146_i148@pure_quanta.q_res(chips)',
 P_PATH='@s9s_mb_2u_lib.s9s_mb_2u(sch_1):page159_i148@pure_quanta.q_res(chips)',
 PATH='I148',
 DRAWING='@S9S_MB_2U_LIB.S9S_MB_2U(SCH_1):PAGE146',
 PHYS_PAGE='159',
 XY='(6875,825)',
 ROT='0',
 VER='1',
 PACK_TYPE='0402LF',
 CDS_LIB='pure_quanta',
 CDS_PART_NAME='Q_RES_0402LF-0,5%,1/16W,CHIP,CA',
 WATTAGE='1/16W',
 TOLERANCE='5%',
 MATERIAL='CHIP',
 VALUE='0',
 PRIM_FILE='./archive_libs/logical/q_res/chips/chips.prt';

PART_NAME
 R3178 'Q_RES_0402LF-0,5%,1/16W,CHIP,CA':;

SECTION_NUMBER 1
 '@S9S_MB_2U_LIB.S9S_MB_2U(SCH_1):PAGE146_I147@PURE_QUANTA.Q_RES(CHIPS)':
 C_PATH='@s9s_mb_2u_lib.s9s_mb_2u(sch_1):page146_i147@pure_quanta.q_res(chips)',
 P_PATH='@s9s_mb_2u_lib.s9s_mb_2u(sch_1):page159_i147@pure_quanta.q_res(chips)',
 PATH='I147',
 DRAWING='@S9S_MB_2U_LIB.S9S_MB_2U(SCH_1):PAGE146',
 PHYS_PAGE='159',
 XY='(6875,775)',
 ROT='0',
 VER='1',
 PACK_TYPE='0402LF',
 CDS_LIB='pure_quanta',
 CDS_PART_NAME='Q_RES_0402LF-0,5%,1/16W,CHIP,CA',
 WATTAGE='1/16W',
 TOLERANCE='5%',
 MATERIAL='CHIP',
 VALUE='0',
 PRIM_FILE='./archive_libs/logical/q_res/chips/chips.prt';

PART_NAME
 R3180 'Q_RES_0402LF-100,1%,1/16W,CHIPA':;

SECTION_NUMBER 1
 '@S9S_MB_2U_LIB.S9S_MB_2U(SCH_1):PAGE146_I152@PURE_QUANTA.Q_RES(CHIPS)':
 C_PATH='@s9s_mb_2u_lib.s9s_mb_2u(sch_1):page146_i152@pure_quanta.q_res(chips)',
 P_PATH='@s9s_mb_2u_lib.s9s_mb_2u(sch_1):page159_i152@pure_quanta.q_res(chips)',
 PATH='I152',
 DRAWING='@S9S_MB_2U_LIB.S9S_MB_2U(SCH_1):PAGE146',
 PHYS_PAGE='159',
 XY='(7975,3675)',
 ROT='0',
 VER='2',
 PACK_TYPE='0402LF',
 CDS_LIB='pure_quanta',
 CDS_PART_NAME='Q_RES_0402LF-100,1%,1/16W,CHIPA',
 WATTAGE='1/16W',
 TOLERANCE='1%',
 MATERIAL='CHIP',
 VALUE='100',
 PRIM_FILE='./archive_libs/logical/q_res/chips/chips.prt';

PART_NAME
 R3181 'Q_RES_0402LF-27.4,1%,1/16W,CHIA':;

SECTION_NUMBER 1
 '@S9S_MB_2U_LIB.S9S_MB_2U(SCH_1):PAGE152_I78@PURE_QUANTA.Q_RES(CHIPS)':
 C_PATH='@s9s_mb_2u_lib.s9s_mb_2u(sch_1):page152_i78@pure_quanta.q_res(chips)',
 P_PATH='@s9s_mb_2u_lib.s9s_mb_2u(sch_1):page155_i78@pure_quanta.q_res(chips)',
 PATH='I78',
 DRAWING='@S9S_MB_2U_LIB.S9S_MB_2U(SCH_1):PAGE152',
 PHYS_PAGE='155',
 XY='(-5725,2275)',
 ROT='0',
 VER='1',
 PACK_TYPE='0402LF',
 CDS_LIB='pure_quanta',
 CDS_PART_NAME='Q_RES_0402LF-27.4,1%,1/16W,CHIA',
 WATTAGE='1/16W',
 TOLERANCE='1%',
 MATERIAL='CHIP',
 VALUE='27.4',
 PRIM_FILE='./archive_libs/logical/q_res/chips/chips.prt';

PART_NAME
 R3182 'Q_RES_0402LF-10K,1%,1/16W,CHIPA':;

SECTION_NUMBER 1
 '@S9S_MB_2U_LIB.S9S_MB_2U(SCH_1):PAGE156_I6@PURE_QUANTA.Q_RES(CHIPS)':
 C_PATH='@s9s_mb_2u_lib.s9s_mb_2u(sch_1):page156_i6@pure_quanta.q_res(chips)',
 P_PATH='@s9s_mb_2u_lib.s9s_mb_2u(sch_1):page161_i6@pure_quanta.q_res(chips)',
 PATH='I6',
 DRAWING='@S9S_MB_2U_LIB.S9S_MB_2U(SCH_1):PAGE156',
 PHYS_PAGE='161',
 XY='(3400,-1425)',
 ROT='2',
 VER='2',
 PACK_TYPE='0402LF',
 CDS_LIB='pure_quanta',
 CDS_PART_NAME='Q_RES_0402LF-10K,1%,1/16W,CHIPA',
 WATTAGE='1/16W',
 TOLERANCE='1%',
 MATERIAL='CHIP',
 VALUE='10K',
 PRIM_FILE='./archive_libs/logical/q_res/chips/chips.prt';

PART_NAME
 R3183 'Q_RES_0402LF-10K,1%,1/16W,CHIPA':;

SECTION_NUMBER 1
 '@S9S_MB_2U_LIB.S9S_MB_2U(SCH_1):PAGE156_I7@PURE_QUANTA.Q_RES(CHIPS)':
 C_PATH='@s9s_mb_2u_lib.s9s_mb_2u(sch_1):page156_i7@pure_quanta.q_res(chips)',
 P_PATH='@s9s_mb_2u_lib.s9s_mb_2u(sch_1):page161_i7@pure_quanta.q_res(chips)',
 PATH='I7',
 DRAWING='@S9S_MB_2U_LIB.S9S_MB_2U(SCH_1):PAGE156',
 PHYS_PAGE='161',
 XY='(3675,-1425)',
 ROT='0',
 VER='2',
 PACK_TYPE='0402LF',
 CDS_LIB='pure_quanta',
 CDS_PART_NAME='Q_RES_0402LF-10K,1%,1/16W,CHIPA',
 WATTAGE='1/16W',
 TOLERANCE='1%',
 MATERIAL='CHIP',
 VALUE='10K',
 PRIM_FILE='./archive_libs/logical/q_res/chips/chips.prt';

PART_NAME
 R3184 'Q_RES_0402LF-4.7K,1%,1/16W,CHIA':;

SECTION_NUMBER 1
 '@S9S_MB_2U_LIB.S9S_MB_2U(SCH_1):PAGE156_I28@PURE_QUANTA.Q_RES(CHIPS)':
 C_PATH='@s9s_mb_2u_lib.s9s_mb_2u(sch_1):page156_i28@pure_quanta.q_res(chips)',
 P_PATH='@s9s_mb_2u_lib.s9s_mb_2u(sch_1):page161_i28@pure_quanta.q_res(chips)',
 PATH='I28',
 DRAWING='@S9S_MB_2U_LIB.S9S_MB_2U(SCH_1):PAGE156',
 PHYS_PAGE='161',
 XY='(6025,-1325)',
 ROT='0',
 VER='2',
 PACK_TYPE='0402LF',
 CDS_LIB='pure_quanta',
 CDS_PART_NAME='Q_RES_0402LF-4.7K,1%,1/16W,CHIA',
 WATTAGE='1/16W',
 TOLERANCE='1%',
 MATERIAL='CHIP',
 VALUE='4.7K',
 PRIM_FILE='./archive_libs/logical/q_res/chips/chips.prt';

PART_NAME
 R3185 'Q_RES_0402LF-33.2,1%,1/16W,CHIA':;

SECTION_NUMBER 1
 '@S9S_MB_2U_LIB.S9S_MB_2U(SCH_1):PAGE156_I24@PURE_QUANTA.Q_RES(CHIPS)':
 C_PATH='@s9s_mb_2u_lib.s9s_mb_2u(sch_1):page156_i24@pure_quanta.q_res(chips)',
 P_PATH='@s9s_mb_2u_lib.s9s_mb_2u(sch_1):page161_i24@pure_quanta.q_res(chips)',
 PATH='I24',
 DRAWING='@S9S_MB_2U_LIB.S9S_MB_2U(SCH_1):PAGE156',
 PHYS_PAGE='161',
 XY='(6350,-1775)',
 ROT='0',
 VER='1',
 PACK_TYPE='0402LF',
 CDS_LIB='pure_quanta',
 CDS_PART_NAME='Q_RES_0402LF-33.2,1%,1/16W,CHIA',
 WATTAGE='1/16W',
 TOLERANCE='1%',
 MATERIAL='CHIP',
 VALUE='33.2',
 PRIM_FILE='./archive_libs/logical/q_res/chips/chips.prt';

PART_NAME
 R3186 'Q_RES_0402LF-33.2,1%,1/16W,CHIA':;

SECTION_NUMBER 1
 '@S9S_MB_2U_LIB.S9S_MB_2U(SCH_1):PAGE156_I41@PURE_QUANTA.Q_RES(CHIPS)':
 C_PATH='@s9s_mb_2u_lib.s9s_mb_2u(sch_1):page156_i41@pure_quanta.q_res(chips)',
 P_PATH='@s9s_mb_2u_lib.s9s_mb_2u(sch_1):page161_i41@pure_quanta.q_res(chips)',
 PATH='I41',
 DRAWING='@S9S_MB_2U_LIB.S9S_MB_2U(SCH_1):PAGE156',
 PHYS_PAGE='161',
 XY='(7000,1100)',
 ROT='0',
 VER='1',
 PACK_TYPE='0402LF',
 CDS_LIB='pure_quanta',
 CDS_PART_NAME='Q_RES_0402LF-33.2,1%,1/16W,CHIA',
 WATTAGE='1/16W',
 TOLERANCE='1%',
 MATERIAL='CHIP',
 VALUE='33.2',
 PRIM_FILE='./archive_libs/logical/q_res/chips/chips.prt';

PART_NAME
 R3187 'Q_RES_0402LF-33.2,1%,1/16W,CHIA':;

SECTION_NUMBER 1
 '@S9S_MB_2U_LIB.S9S_MB_2U(SCH_1):PAGE156_I40@PURE_QUANTA.Q_RES(CHIPS)':
 C_PATH='@s9s_mb_2u_lib.s9s_mb_2u(sch_1):page156_i40@pure_quanta.q_res(chips)',
 P_PATH='@s9s_mb_2u_lib.s9s_mb_2u(sch_1):page161_i40@pure_quanta.q_res(chips)',
 PATH='I40',
 DRAWING='@S9S_MB_2U_LIB.S9S_MB_2U(SCH_1):PAGE156',
 PHYS_PAGE='161',
 XY='(7000,875)',
 ROT='0',
 VER='1',
 PACK_TYPE='0402LF',
 CDS_LIB='pure_quanta',
 CDS_PART_NAME='Q_RES_0402LF-33.2,1%,1/16W,CHIA',
 WATTAGE='1/16W',
 TOLERANCE='1%',
 MATERIAL='CHIP',
 VALUE='33.2',
 PRIM_FILE='./archive_libs/logical/q_res/chips/chips.prt';

PART_NAME
 R3188 'Q_RES_0402LF-33.2,1%,1/16W,CHIA':;

SECTION_NUMBER 1
 '@S9S_MB_2U_LIB.S9S_MB_2U(SCH_1):PAGE156_I39@PURE_QUANTA.Q_RES(CHIPS)':
 C_PATH='@s9s_mb_2u_lib.s9s_mb_2u(sch_1):page156_i39@pure_quanta.q_res(chips)',
 P_PATH='@s9s_mb_2u_lib.s9s_mb_2u(sch_1):page161_i39@pure_quanta.q_res(chips)',
 PATH='I39',
 DRAWING='@S9S_MB_2U_LIB.S9S_MB_2U(SCH_1):PAGE156',
 PHYS_PAGE='161',
 XY='(7000,650)',
 ROT='0',
 VER='1',
 PACK_TYPE='0402LF',
 CDS_LIB='pure_quanta',
 CDS_PART_NAME='Q_RES_0402LF-33.2,1%,1/16W,CHIA',
 WATTAGE='1/16W',
 TOLERANCE='1%',
 MATERIAL='CHIP',
 VALUE='33.2',
 PRIM_FILE='./archive_libs/logical/q_res/chips/chips.prt';

PART_NAME
 R3189 'Q_RES_0402LF-33.2,1%,1/16W,CHIA':;

SECTION_NUMBER 1
 '@S9S_MB_2U_LIB.S9S_MB_2U(SCH_1):PAGE156_I38@PURE_QUANTA.Q_RES(CHIPS)':
 C_PATH='@s9s_mb_2u_lib.s9s_mb_2u(sch_1):page156_i38@pure_quanta.q_res(chips)',
 P_PATH='@s9s_mb_2u_lib.s9s_mb_2u(sch_1):page161_i38@pure_quanta.q_res(chips)',
 PATH='I38',
 DRAWING='@S9S_MB_2U_LIB.S9S_MB_2U(SCH_1):PAGE156',
 PHYS_PAGE='161',
 XY='(7000,425)',
 ROT='0',
 VER='1',
 PACK_TYPE='0402LF',
 CDS_LIB='pure_quanta',
 CDS_PART_NAME='Q_RES_0402LF-33.2,1%,1/16W,CHIA',
 WATTAGE='1/16W',
 TOLERANCE='1%',
 MATERIAL='CHIP',
 VALUE='33.2',
 PRIM_FILE='./archive_libs/logical/q_res/chips/chips.prt';

PART_NAME
 R3190 'Q_RES_0402LF-4.7K,1%,1/16W,CHIA':;

SECTION_NUMBER 1
 '@S9S_MB_2U_LIB.S9S_MB_2U(SCH_1):PAGE156_I42@PURE_QUANTA.Q_RES(CHIPS)':
 C_PATH='@s9s_mb_2u_lib.s9s_mb_2u(sch_1):page156_i42@pure_quanta.q_res(chips)',
 P_PATH='@s9s_mb_2u_lib.s9s_mb_2u(sch_1):page161_i42@pure_quanta.q_res(chips)',
 PATH='I42',
 DRAWING='@S9S_MB_2U_LIB.S9S_MB_2U(SCH_1):PAGE156',
 PHYS_PAGE='161',
 XY='(7200,-175)',
 ROT='0',
 VER='2',
 PACK_TYPE='0402LF',
 CDS_LIB='pure_quanta',
 CDS_PART_NAME='Q_RES_0402LF-4.7K,1%,1/16W,CHIA',
 WATTAGE='1/16W',
 TOLERANCE='1%',
 MATERIAL='CHIP',
 VALUE='4.7K',
 PRIM_FILE='./archive_libs/logical/q_res/chips/chips.prt';

PART_NAME
 R3191 'Q_RES_0402LF-33.2,1%,1/16W,CHIA':;

SECTION_NUMBER 1
 '@S9S_MB_2U_LIB.S9S_MB_2U(SCH_1):PAGE156_I44@PURE_QUANTA.Q_RES(CHIPS)':
 C_PATH='@s9s_mb_2u_lib.s9s_mb_2u(sch_1):page156_i44@pure_quanta.q_res(chips)',
 P_PATH='@s9s_mb_2u_lib.s9s_mb_2u(sch_1):page161_i44@pure_quanta.q_res(chips)',
 PATH='I44',
 DRAWING='@S9S_MB_2U_LIB.S9S_MB_2U(SCH_1):PAGE156',
 PHYS_PAGE='161',
 XY='(7750,-550)',
 ROT='0',
 VER='1',
 PACK_TYPE='0402LF',
 CDS_LIB='pure_quanta',
 CDS_PART_NAME='Q_RES_0402LF-33.2,1%,1/16W,CHIA',
 WATTAGE='1/16W',
 TOLERANCE='1%',
 MATERIAL='CHIP',
 VALUE='33.2',
 PRIM_FILE='./archive_libs/logical/q_res/chips/chips.prt';

PART_NAME
 R3192 'Q_RES_0402LF-4.7K,1%,1/16W,EMPA':;

SECTION_NUMBER 1
 '@S9S_MB_2U_LIB.S9S_MB_2U(SCH_1):PAGE156_I59@PURE_QUANTA.Q_RES(CHIPS)':
 C_PATH='@s9s_mb_2u_lib.s9s_mb_2u(sch_1):page156_i59@pure_quanta.q_res(chips)',
 P_PATH='@s9s_mb_2u_lib.s9s_mb_2u(sch_1):page161_i59@pure_quanta.q_res(chips)',
 PATH='I59',
 DRAWING='@S9S_MB_2U_LIB.S9S_MB_2U(SCH_1):PAGE156',
 PHYS_PAGE='161',
 XY='(9300,-1425)',
 ROT='0',
 VER='2',
 PACK_TYPE='0402LF',
 CDS_LIB='pure_quanta',
 CDS_PART_NAME='Q_RES_0402LF-4.7K,1%,1/16W,EMPA',
 WATTAGE='1/16W',
 TOLERANCE='1%',
 MATERIAL='EMPTY',
 VALUE='4.7K',
 PRIM_FILE='./archive_libs/logical/q_res/chips/chips.prt';

PART_NAME
 R3193 'Q_RES_0402LF-33.2,1%,1/16W,CHIA':;

SECTION_NUMBER 1
 '@S9S_MB_2U_LIB.S9S_MB_2U(SCH_1):PAGE156_I55@PURE_QUANTA.Q_RES(CHIPS)':
 C_PATH='@s9s_mb_2u_lib.s9s_mb_2u(sch_1):page156_i55@pure_quanta.q_res(chips)',
 P_PATH='@s9s_mb_2u_lib.s9s_mb_2u(sch_1):page161_i55@pure_quanta.q_res(chips)',
 PATH='I55',
 DRAWING='@S9S_MB_2U_LIB.S9S_MB_2U(SCH_1):PAGE156',
 PHYS_PAGE='161',
 XY='(9600,-1875)',
 ROT='0',
 VER='1',
 PACK_TYPE='0402LF',
 CDS_LIB='pure_quanta',
 CDS_PART_NAME='Q_RES_0402LF-33.2,1%,1/16W,CHIA',
 WATTAGE='1/16W',
 TOLERANCE='1%',
 MATERIAL='CHIP',
 VALUE='33.2',
 PRIM_FILE='./archive_libs/logical/q_res/chips/chips.prt';

PART_NAME
 R3194 'Q_RES_0402LF-22,1%,1/16W,CHIP,A':;

SECTION_NUMBER 1
 '@S9S_MB_2U_LIB.S9S_MB_2U(SCH_1):PAGE196_I17@PURE_QUANTA.Q_RES(CHIPS)':
 C_PATH='@s9s_mb_2u_lib.s9s_mb_2u(sch_1):page196_i17@pure_quanta.q_res(chips)',
 P_PATH='@s9s_mb_2u_lib.s9s_mb_2u(sch_1):page207_i17@pure_quanta.q_res(chips)',
 PATH='I17',
 DRAWING='@S9S_MB_2U_LIB.S9S_MB_2U(SCH_1):PAGE196',
 PHYS_PAGE='207',
 XY='(-100,-6425)',
 ROT='0',
 VER='1',
 PACK_TYPE='0402LF',
 CDS_LIB='pure_quanta',
 CDS_PART_NAME='Q_RES_0402LF-22,1%,1/16W,CHIP,A',
 WATTAGE='1/16W',
 TOLERANCE='1%',
 MATERIAL='CHIP',
 VALUE='22',
 PRIM_FILE='./archive_libs/logical/q_res/chips/chips.prt';

PART_NAME
 R3195 'Q_RES_0402LF-22,1%,1/16W,CHIP,A':;

SECTION_NUMBER 1
 '@S9S_MB_2U_LIB.S9S_MB_2U(SCH_1):PAGE196_I16@PURE_QUANTA.Q_RES(CHIPS)':
 C_PATH='@s9s_mb_2u_lib.s9s_mb_2u(sch_1):page196_i16@pure_quanta.q_res(chips)',
 P_PATH='@s9s_mb_2u_lib.s9s_mb_2u(sch_1):page207_i16@pure_quanta.q_res(chips)',
 PATH='I16',
 DRAWING='@S9S_MB_2U_LIB.S9S_MB_2U(SCH_1):PAGE196',
 PHYS_PAGE='207',
 XY='(-100,-6575)',
 ROT='0',
 VER='1',
 PACK_TYPE='0402LF',
 CDS_LIB='pure_quanta',
 CDS_PART_NAME='Q_RES_0402LF-22,1%,1/16W,CHIP,A',
 WATTAGE='1/16W',
 TOLERANCE='1%',
 MATERIAL='CHIP',
 VALUE='22',
 PRIM_FILE='./archive_libs/logical/q_res/chips/chips.prt';

PART_NAME
 R3196 'Q_RES_0402LF-22,1%,1/16W,CHIP,A':;

SECTION_NUMBER 1
 '@S9S_MB_2U_LIB.S9S_MB_2U(SCH_1):PAGE196_I15@PURE_QUANTA.Q_RES(CHIPS)':
 C_PATH='@s9s_mb_2u_lib.s9s_mb_2u(sch_1):page196_i15@pure_quanta.q_res(chips)',
 P_PATH='@s9s_mb_2u_lib.s9s_mb_2u(sch_1):page207_i15@pure_quanta.q_res(chips)',
 PATH='I15',
 DRAWING='@S9S_MB_2U_LIB.S9S_MB_2U(SCH_1):PAGE196',
 PHYS_PAGE='207',
 XY='(-100,-6825)',
 ROT='0',
 VER='1',
 PACK_TYPE='0402LF',
 CDS_LIB='pure_quanta',
 CDS_PART_NAME='Q_RES_0402LF-22,1%,1/16W,CHIP,A',
 WATTAGE='1/16W',
 TOLERANCE='1%',
 MATERIAL='CHIP',
 VALUE='22',
 PRIM_FILE='./archive_libs/logical/q_res/chips/chips.prt';

PART_NAME
 R3197 'Q_RES_0402LF-22,1%,1/16W,CHIP,A':;

SECTION_NUMBER 1
 '@S9S_MB_2U_LIB.S9S_MB_2U(SCH_1):PAGE196_I14@PURE_QUANTA.Q_RES(CHIPS)':
 C_PATH='@s9s_mb_2u_lib.s9s_mb_2u(sch_1):page196_i14@pure_quanta.q_res(chips)',
 P_PATH='@s9s_mb_2u_lib.s9s_mb_2u(sch_1):page207_i14@pure_quanta.q_res(chips)',
 PATH='I14',
 DRAWING='@S9S_MB_2U_LIB.S9S_MB_2U(SCH_1):PAGE196',
 PHYS_PAGE='207',
 XY='(-100,-6975)',
 ROT='0',
 VER='1',
 PACK_TYPE='0402LF',
 CDS_LIB='pure_quanta',
 CDS_PART_NAME='Q_RES_0402LF-22,1%,1/16W,CHIP,A',
 WATTAGE='1/16W',
 TOLERANCE='1%',
 MATERIAL='CHIP',
 VALUE='22',
 PRIM_FILE='./archive_libs/logical/q_res/chips/chips.prt';

PART_NAME
 R3198 'Q_RES_0402LF-22,1%,1/16W,CHIP,A':;

SECTION_NUMBER 1
 '@S9S_MB_2U_LIB.S9S_MB_2U(SCH_1):PAGE196_I13@PURE_QUANTA.Q_RES(CHIPS)':
 C_PATH='@s9s_mb_2u_lib.s9s_mb_2u(sch_1):page196_i13@pure_quanta.q_res(chips)',
 P_PATH='@s9s_mb_2u_lib.s9s_mb_2u(sch_1):page207_i13@pure_quanta.q_res(chips)',
 PATH='I13',
 DRAWING='@S9S_MB_2U_LIB.S9S_MB_2U(SCH_1):PAGE196',
 PHYS_PAGE='207',
 XY='(-100,-7225)',
 ROT='0',
 VER='1',
 PACK_TYPE='0402LF',
 CDS_LIB='pure_quanta',
 CDS_PART_NAME='Q_RES_0402LF-22,1%,1/16W,CHIP,A',
 WATTAGE='1/16W',
 TOLERANCE='1%',
 MATERIAL='CHIP',
 VALUE='22',
 PRIM_FILE='./archive_libs/logical/q_res/chips/chips.prt';

PART_NAME
 R3199 'Q_RES_0402LF-22,1%,1/16W,CHIP,A':;

SECTION_NUMBER 1
 '@S9S_MB_2U_LIB.S9S_MB_2U(SCH_1):PAGE196_I12@PURE_QUANTA.Q_RES(CHIPS)':
 C_PATH='@s9s_mb_2u_lib.s9s_mb_2u(sch_1):page196_i12@pure_quanta.q_res(chips)',
 P_PATH='@s9s_mb_2u_lib.s9s_mb_2u(sch_1):page207_i12@pure_quanta.q_res(chips)',
 PATH='I12',
 DRAWING='@S9S_MB_2U_LIB.S9S_MB_2U(SCH_1):PAGE196',
 PHYS_PAGE='207',
 XY='(-100,-7375)',
 ROT='0',
 VER='1',
 PACK_TYPE='0402LF',
 CDS_LIB='pure_quanta',
 CDS_PART_NAME='Q_RES_0402LF-22,1%,1/16W,CHIP,A',
 WATTAGE='1/16W',
 TOLERANCE='1%',
 MATERIAL='CHIP',
 VALUE='22',
 PRIM_FILE='./archive_libs/logical/q_res/chips/chips.prt';

PART_NAME
 R3200 'Q_RES_0402LF-22,1%,1/16W,CHIP,A':;

SECTION_NUMBER 1
 '@S9S_MB_2U_LIB.S9S_MB_2U(SCH_1):PAGE196_I11@PURE_QUANTA.Q_RES(CHIPS)':
 C_PATH='@s9s_mb_2u_lib.s9s_mb_2u(sch_1):page196_i11@pure_quanta.q_res(chips)',
 P_PATH='@s9s_mb_2u_lib.s9s_mb_2u(sch_1):page207_i11@pure_quanta.q_res(chips)',
 PATH='I11',
 DRAWING='@S9S_MB_2U_LIB.S9S_MB_2U(SCH_1):PAGE196',
 PHYS_PAGE='207',
 XY='(-100,-7625)',
 ROT='0',
 VER='1',
 PACK_TYPE='0402LF',
 CDS_LIB='pure_quanta',
 CDS_PART_NAME='Q_RES_0402LF-22,1%,1/16W,CHIP,A',
 WATTAGE='1/16W',
 TOLERANCE='1%',
 MATERIAL='CHIP',
 VALUE='22',
 PRIM_FILE='./archive_libs/logical/q_res/chips/chips.prt';

PART_NAME
 R3201 'Q_RES_0402LF-22,1%,1/16W,CHIP,A':;

SECTION_NUMBER 1
 '@S9S_MB_2U_LIB.S9S_MB_2U(SCH_1):PAGE196_I10@PURE_QUANTA.Q_RES(CHIPS)':
 C_PATH='@s9s_mb_2u_lib.s9s_mb_2u(sch_1):page196_i10@pure_quanta.q_res(chips)',
 P_PATH='@s9s_mb_2u_lib.s9s_mb_2u(sch_1):page207_i10@pure_quanta.q_res(chips)',
 PATH='I10',
 DRAWING='@S9S_MB_2U_LIB.S9S_MB_2U(SCH_1):PAGE196',
 PHYS_PAGE='207',
 XY='(-100,-7775)',
 ROT='0',
 VER='1',
 PACK_TYPE='0402LF',
 CDS_LIB='pure_quanta',
 CDS_PART_NAME='Q_RES_0402LF-22,1%,1/16W,CHIP,A',
 WATTAGE='1/16W',
 TOLERANCE='1%',
 MATERIAL='CHIP',
 VALUE='22',
 PRIM_FILE='./archive_libs/logical/q_res/chips/chips.prt';

PART_NAME
 R3203 'Q_RES_0402LF-33.2,1%,1/16W,CHIA':;

SECTION_NUMBER 1
 '@S9S_MB_2U_LIB.S9S_MB_2U(SCH_1):PAGE307_I81@PURE_QUANTA.Q_RES(CHIPS)':
 C_PATH='@s9s_mb_2u_lib.s9s_mb_2u(sch_1):page307_i81@pure_quanta.q_res(chips)',
 P_PATH='@s9s_mb_2u_lib.s9s_mb_2u(sch_1):page160_i81@pure_quanta.q_res(chips)',
 PATH='I81',
 DRAWING='@S9S_MB_2U_LIB.S9S_MB_2U(SCH_1):PAGE307',
 PHYS_PAGE='160',
 XY='(-2875,-475)',
 ROT='0',
 VER='1',
 PACK_TYPE='0402LF',
 CDS_LIB='pure_quanta',
 CDS_PART_NAME='Q_RES_0402LF-33.2,1%,1/16W,CHIA',
 WATTAGE='1/16W',
 TOLERANCE='1%',
 MATERIAL='CHIP',
 VALUE='33.2',
 PRIM_FILE='./archive_libs/logical/q_res/chips/chips.prt';

PART_NAME
 R3205 'Q_RES_0402LF-49.9,1%,1/16W,CHIA':;

SECTION_NUMBER 1
 '@S9S_MB_2U_LIB.S9S_MB_2U(SCH_1):PAGE307_I85@PURE_QUANTA.Q_RES(CHIPS)':
 C_PATH='@s9s_mb_2u_lib.s9s_mb_2u(sch_1):page307_i85@pure_quanta.q_res(chips)',
 P_PATH='@s9s_mb_2u_lib.s9s_mb_2u(sch_1):page160_i85@pure_quanta.q_res(chips)',
 PATH='I85',
 DRAWING='@S9S_MB_2U_LIB.S9S_MB_2U(SCH_1):PAGE307',
 PHYS_PAGE='160',
 XY='(-75,-425)',
 ROT='0',
 VER='1',
 PACK_TYPE='0402LF',
 LOCATION='R3205',
 CDS_LIB='pure_quanta',
 CDS_PART_NAME='Q_RES_0402LF-49.9,1%,1/16W,CHIA',
 WATTAGE='1/16W',
 TOLERANCE='1%',
 MATERIAL='CHIP',
 VALUE='49.9',
 PRIM_FILE='./archive_libs/logical/q_res/chips/chips.prt';

PART_NAME
 R3206 'Q_RES_0402LF-0,5%,1/16W,EMPTY,A':;

SECTION_NUMBER 1
 '@S9S_MB_2U_LIB.S9S_MB_2U(SCH_1):PAGE307_I12@PURE_QUANTA.Q_RES(CHIPS)':
 C_PATH='@s9s_mb_2u_lib.s9s_mb_2u(sch_1):page307_i12@pure_quanta.q_res(chips)',
 P_PATH='@s9s_mb_2u_lib.s9s_mb_2u(sch_1):page160_i12@pure_quanta.q_res(chips)',
 PATH='I12',
 DRAWING='@S9S_MB_2U_LIB.S9S_MB_2U(SCH_1):PAGE307',
 PHYS_PAGE='160',
 XY='(-75,-950)',
 ROT='0',
 VER='1',
 PACK_TYPE='0402LF',
 CDS_LIB='pure_quanta',
 CDS_PART_NAME='Q_RES_0402LF-0,5%,1/16W,EMPTY,A',
 WATTAGE='1/16W',
 TOLERANCE='5%',
 MATERIAL='EMPTY',
 VALUE='0',
 PRIM_FILE='./archive_libs/logical/q_res/chips/chips.prt';

PART_NAME
 R3207 'Q_RES_0402LF-100K,1%,1/16W,CHIA':;

SECTION_NUMBER 1
 '@S9S_MB_2U_LIB.S9S_MB_2U(SCH_1):PAGE307_I15@PURE_QUANTA.Q_RES(CHIPS)':
 C_PATH='@s9s_mb_2u_lib.s9s_mb_2u(sch_1):page307_i15@pure_quanta.q_res(chips)',
 P_PATH='@s9s_mb_2u_lib.s9s_mb_2u(sch_1):page160_i15@pure_quanta.q_res(chips)',
 PATH='I15',
 DRAWING='@S9S_MB_2U_LIB.S9S_MB_2U(SCH_1):PAGE307',
 PHYS_PAGE='160',
 XY='(350,-625)',
 ROT='0',
 VER='2',
 PACK_TYPE='0402LF',
 CDS_LIB='pure_quanta',
 CDS_PART_NAME='Q_RES_0402LF-100K,1%,1/16W,CHIA',
 WATTAGE='1/16W',
 TOLERANCE='1%',
 MATERIAL='CHIP',
 VALUE='100K',
 PRIM_FILE='./archive_libs/logical/q_res/chips/chips.prt';

PART_NAME
 R3208 'Q_RES_0402LF-100,1%,1/16W,CHIPA':;

SECTION_NUMBER 1
 '@S9S_MB_2U_LIB.S9S_MB_2U(SCH_1):PAGE307_I37@PURE_QUANTA.Q_RES(CHIPS)':
 C_PATH='@s9s_mb_2u_lib.s9s_mb_2u(sch_1):page307_i37@pure_quanta.q_res(chips)',
 P_PATH='@s9s_mb_2u_lib.s9s_mb_2u(sch_1):page160_i37@pure_quanta.q_res(chips)',
 PATH='I37',
 DRAWING='@S9S_MB_2U_LIB.S9S_MB_2U(SCH_1):PAGE307',
 PHYS_PAGE='160',
 XY='(1800,-2525)',
 ROT='0',
 VER='2',
 PACK_TYPE='0402LF',
 CDS_LIB='pure_quanta',
 CDS_PART_NAME='Q_RES_0402LF-100,1%,1/16W,CHIPA',
 WATTAGE='1/16W',
 TOLERANCE='1%',
 MATERIAL='CHIP',
 VALUE='100',
 PRIM_FILE='./archive_libs/logical/q_res/chips/chips.prt';

PART_NAME
 R3209 'Q_RES_0402LF-22,1%,1/16W,EMPTYA':;

SECTION_NUMBER 1
 '@S9S_MB_2U_LIB.S9S_MB_2U(SCH_1):PAGE307_I64@PURE_QUANTA.Q_RES(CHIPS)':
 C_PATH='@s9s_mb_2u_lib.s9s_mb_2u(sch_1):page307_i64@pure_quanta.q_res(chips)',
 P_PATH='@s9s_mb_2u_lib.s9s_mb_2u(sch_1):page160_i64@pure_quanta.q_res(chips)',
 PATH='I64',
 DRAWING='@S9S_MB_2U_LIB.S9S_MB_2U(SCH_1):PAGE307',
 PHYS_PAGE='160',
 XY='(3450,2475)',
 ROT='0',
 VER='1',
 PACK_TYPE='0402LF',
 CDS_LIB='pure_quanta',
 CDS_PART_NAME='Q_RES_0402LF-22,1%,1/16W,EMPTYA',
 WATTAGE='1/16W',
 TOLERANCE='1%',
 MATERIAL='EMPTY',
 VALUE='22',
 PRIM_FILE='./archive_libs/logical/q_res/chips/chips.prt';

PART_NAME
 R3210 'Q_RES_0402LF-22,1%,1/16W,EMPTYA':;

SECTION_NUMBER 1
 '@S9S_MB_2U_LIB.S9S_MB_2U(SCH_1):PAGE307_I65@PURE_QUANTA.Q_RES(CHIPS)':
 C_PATH='@s9s_mb_2u_lib.s9s_mb_2u(sch_1):page307_i65@pure_quanta.q_res(chips)',
 P_PATH='@s9s_mb_2u_lib.s9s_mb_2u(sch_1):page160_i65@pure_quanta.q_res(chips)',
 PATH='I65',
 DRAWING='@S9S_MB_2U_LIB.S9S_MB_2U(SCH_1):PAGE307',
 PHYS_PAGE='160',
 XY='(1900,2325)',
 ROT='0',
 VER='1',
 PACK_TYPE='0402LF',
 CDS_LIB='pure_quanta',
 CDS_PART_NAME='Q_RES_0402LF-22,1%,1/16W,EMPTYA',
 WATTAGE='1/16W',
 TOLERANCE='1%',
 MATERIAL='EMPTY',
 VALUE='22',
 PRIM_FILE='./archive_libs/logical/q_res/chips/chips.prt';

PART_NAME
 R3211 'Q_RES_0402LF-22,1%,1/16W,EMPTYA':;

SECTION_NUMBER 1
 '@S9S_MB_2U_LIB.S9S_MB_2U(SCH_1):PAGE307_I63@PURE_QUANTA.Q_RES(CHIPS)':
 C_PATH='@s9s_mb_2u_lib.s9s_mb_2u(sch_1):page307_i63@pure_quanta.q_res(chips)',
 P_PATH='@s9s_mb_2u_lib.s9s_mb_2u(sch_1):page160_i63@pure_quanta.q_res(chips)',
 PATH='I63',
 DRAWING='@S9S_MB_2U_LIB.S9S_MB_2U(SCH_1):PAGE307',
 PHYS_PAGE='160',
 XY='(1900,2175)',
 ROT='0',
 VER='1',
 PACK_TYPE='0402LF',
 CDS_LIB='pure_quanta',
 CDS_PART_NAME='Q_RES_0402LF-22,1%,1/16W,EMPTYA',
 WATTAGE='1/16W',
 TOLERANCE='1%',
 MATERIAL='EMPTY',
 VALUE='22',
 PRIM_FILE='./archive_libs/logical/q_res/chips/chips.prt';

PART_NAME
 R3212 'Q_RES_0402LF-22,1%,1/16W,EMPTYA':;

SECTION_NUMBER 1
 '@S9S_MB_2U_LIB.S9S_MB_2U(SCH_1):PAGE307_I62@PURE_QUANTA.Q_RES(CHIPS)':
 C_PATH='@s9s_mb_2u_lib.s9s_mb_2u(sch_1):page307_i62@pure_quanta.q_res(chips)',
 P_PATH='@s9s_mb_2u_lib.s9s_mb_2u(sch_1):page160_i62@pure_quanta.q_res(chips)',
 PATH='I62',
 DRAWING='@S9S_MB_2U_LIB.S9S_MB_2U(SCH_1):PAGE307',
 PHYS_PAGE='160',
 XY='(1900,2025)',
 ROT='0',
 VER='1',
 PACK_TYPE='0402LF',
 CDS_LIB='pure_quanta',
 CDS_PART_NAME='Q_RES_0402LF-22,1%,1/16W,EMPTYA',
 WATTAGE='1/16W',
 TOLERANCE='1%',
 MATERIAL='EMPTY',
 VALUE='22',
 PRIM_FILE='./archive_libs/logical/q_res/chips/chips.prt';

PART_NAME
 R3213 'Q_RES_0402LF-0,5%,1/16W,EMPTY,A':;

SECTION_NUMBER 1
 '@S9S_MB_2U_LIB.S9S_MB_2U(SCH_1):PAGE307_I61@PURE_QUANTA.Q_RES(CHIPS)':
 C_PATH='@s9s_mb_2u_lib.s9s_mb_2u(sch_1):page307_i61@pure_quanta.q_res(chips)',
 P_PATH='@s9s_mb_2u_lib.s9s_mb_2u(sch_1):page160_i61@pure_quanta.q_res(chips)',
 PATH='I61',
 DRAWING='@S9S_MB_2U_LIB.S9S_MB_2U(SCH_1):PAGE307',
 PHYS_PAGE='160',
 XY='(1900,900)',
 ROT='0',
 VER='1',
 PACK_TYPE='0402LF',
 CDS_LIB='pure_quanta',
 CDS_PART_NAME='Q_RES_0402LF-0,5%,1/16W,EMPTY,A',
 WATTAGE='1/16W',
 TOLERANCE='5%',
 MATERIAL='EMPTY',
 VALUE='0',
 PRIM_FILE='./archive_libs/logical/q_res/chips/chips.prt';

PART_NAME
 R3214 'Q_RES_0402LF-0,5%,1/16W,EMPTY,A':;

SECTION_NUMBER 1
 '@S9S_MB_2U_LIB.S9S_MB_2U(SCH_1):PAGE307_I60@PURE_QUANTA.Q_RES(CHIPS)':
 C_PATH='@s9s_mb_2u_lib.s9s_mb_2u(sch_1):page307_i60@pure_quanta.q_res(chips)',
 P_PATH='@s9s_mb_2u_lib.s9s_mb_2u(sch_1):page160_i60@pure_quanta.q_res(chips)',
 PATH='I60',
 DRAWING='@S9S_MB_2U_LIB.S9S_MB_2U(SCH_1):PAGE307',
 PHYS_PAGE='160',
 XY='(1900,750)',
 ROT='0',
 VER='1',
 PACK_TYPE='0402LF',
 CDS_LIB='pure_quanta',
 CDS_PART_NAME='Q_RES_0402LF-0,5%,1/16W,EMPTY,A',
 WATTAGE='1/16W',
 TOLERANCE='5%',
 MATERIAL='EMPTY',
 VALUE='0',
 PRIM_FILE='./archive_libs/logical/q_res/chips/chips.prt';

PART_NAME
 R3215 'Q_RES_0402LF-0,5%,1/16W,EMPTY,A':;

SECTION_NUMBER 1
 '@S9S_MB_2U_LIB.S9S_MB_2U(SCH_1):PAGE307_I56@PURE_QUANTA.Q_RES(CHIPS)':
 C_PATH='@s9s_mb_2u_lib.s9s_mb_2u(sch_1):page307_i56@pure_quanta.q_res(chips)',
 P_PATH='@s9s_mb_2u_lib.s9s_mb_2u(sch_1):page160_i56@pure_quanta.q_res(chips)',
 PATH='I56',
 DRAWING='@S9S_MB_2U_LIB.S9S_MB_2U(SCH_1):PAGE307',
 PHYS_PAGE='160',
 XY='(1900,600)',
 ROT='0',
 VER='1',
 PACK_TYPE='0402LF',
 CDS_LIB='pure_quanta',
 CDS_PART_NAME='Q_RES_0402LF-0,5%,1/16W,EMPTY,A',
 WATTAGE='1/16W',
 TOLERANCE='5%',
 MATERIAL='EMPTY',
 VALUE='0',
 PRIM_FILE='./archive_libs/logical/q_res/chips/chips.prt';

PART_NAME
 R3216 'Q_RES_0402LF-100,1%,1/16W,CHIPA':;

SECTION_NUMBER 1
 '@S9S_MB_2U_LIB.S9S_MB_2U(SCH_1):PAGE307_I38@PURE_QUANTA.Q_RES(CHIPS)':
 C_PATH='@s9s_mb_2u_lib.s9s_mb_2u(sch_1):page307_i38@pure_quanta.q_res(chips)',
 P_PATH='@s9s_mb_2u_lib.s9s_mb_2u(sch_1):page160_i38@pure_quanta.q_res(chips)',
 PATH='I38',
 DRAWING='@S9S_MB_2U_LIB.S9S_MB_2U(SCH_1):PAGE307',
 PHYS_PAGE='160',
 XY='(2050,-2525)',
 ROT='0',
 VER='2',
 PACK_TYPE='0402LF',
 CDS_LIB='pure_quanta',
 CDS_PART_NAME='Q_RES_0402LF-100,1%,1/16W,CHIPA',
 WATTAGE='1/16W',
 TOLERANCE='1%',
 MATERIAL='CHIP',
 VALUE='100',
 PRIM_FILE='./archive_libs/logical/q_res/chips/chips.prt';

PART_NAME
 R3217 'Q_RES_0402LF-100,1%,1/16W,CHIPA':;

SECTION_NUMBER 1
 '@S9S_MB_2U_LIB.S9S_MB_2U(SCH_1):PAGE307_I40@PURE_QUANTA.Q_RES(CHIPS)':
 C_PATH='@s9s_mb_2u_lib.s9s_mb_2u(sch_1):page307_i40@pure_quanta.q_res(chips)',
 P_PATH='@s9s_mb_2u_lib.s9s_mb_2u(sch_1):page160_i40@pure_quanta.q_res(chips)',
 PATH='I40',
 DRAWING='@S9S_MB_2U_LIB.S9S_MB_2U(SCH_1):PAGE307',
 PHYS_PAGE='160',
 XY='(2300,-2525)',
 ROT='0',
 VER='2',
 PACK_TYPE='0402LF',
 CDS_LIB='pure_quanta',
 CDS_PART_NAME='Q_RES_0402LF-100,1%,1/16W,CHIPA',
 WATTAGE='1/16W',
 TOLERANCE='1%',
 MATERIAL='CHIP',
 VALUE='100',
 PRIM_FILE='./archive_libs/logical/q_res/chips/chips.prt';

PART_NAME
 R3222 'Q_RES_0402LF-2K,1%,1/16W,CHIP,A':;

SECTION_NUMBER 1
 '@S9S_MB_2U_LIB.S9S_MB_2U(SCH_1):PAGE224_I132@PURE_QUANTA.Q_RES(CHIPS)':
 C_PATH='@s9s_mb_2u_lib.s9s_mb_2u(sch_1):page224_i132@pure_quanta.q_res(chips)',
 P_PATH='@s9s_mb_2u_lib.s9s_mb_2u(sch_1):page236_i132@pure_quanta.q_res(chips)',
 PATH='I132',
 DRAWING='@S9S_MB_2U_LIB.S9S_MB_2U(SCH_1):PAGE224',
 PHYS_PAGE='236',
 XY='(3650,6800)',
 ROT='0',
 VER='1',
 PACK_TYPE='0402LF',
 CDS_LIB='pure_quanta',
 CDS_PART_NAME='Q_RES_0402LF-2K,1%,1/16W,CHIP,A',
 WATTAGE='1/16W',
 TOLERANCE='1%',
 MATERIAL='CHIP',
 VALUE='2K',
 PRIM_FILE='./archive_libs/logical/q_res/chips/chips.prt';

PART_NAME
 R3223 'Q_RES_0402LF-2K,1%,1/16W,CHIP,A':;

SECTION_NUMBER 1
 '@S9S_MB_2U_LIB.S9S_MB_2U(SCH_1):PAGE224_I133@PURE_QUANTA.Q_RES(CHIPS)':
 C_PATH='@s9s_mb_2u_lib.s9s_mb_2u(sch_1):page224_i133@pure_quanta.q_res(chips)',
 P_PATH='@s9s_mb_2u_lib.s9s_mb_2u(sch_1):page236_i133@pure_quanta.q_res(chips)',
 PATH='I133',
 DRAWING='@S9S_MB_2U_LIB.S9S_MB_2U(SCH_1):PAGE224',
 PHYS_PAGE='236',
 XY='(3650,6750)',
 ROT='0',
 VER='1',
 PACK_TYPE='0402LF',
 CDS_LIB='pure_quanta',
 CDS_PART_NAME='Q_RES_0402LF-2K,1%,1/16W,CHIP,A',
 WATTAGE='1/16W',
 TOLERANCE='1%',
 MATERIAL='CHIP',
 VALUE='2K',
 PRIM_FILE='./archive_libs/logical/q_res/chips/chips.prt';

PART_NAME
 R3224 'Q_RES_0402LF-2K,1%,1/16W,CHIP,A':;

SECTION_NUMBER 1
 '@S9S_MB_2U_LIB.S9S_MB_2U(SCH_1):PAGE224_I131@PURE_QUANTA.Q_RES(CHIPS)':
 C_PATH='@s9s_mb_2u_lib.s9s_mb_2u(sch_1):page224_i131@pure_quanta.q_res(chips)',
 P_PATH='@s9s_mb_2u_lib.s9s_mb_2u(sch_1):page236_i131@pure_quanta.q_res(chips)',
 PATH='I131',
 DRAWING='@S9S_MB_2U_LIB.S9S_MB_2U(SCH_1):PAGE224',
 PHYS_PAGE='236',
 XY='(3650,6500)',
 ROT='0',
 VER='1',
 PACK_TYPE='0402LF',
 CDS_LIB='pure_quanta',
 CDS_PART_NAME='Q_RES_0402LF-2K,1%,1/16W,CHIP,A',
 WATTAGE='1/16W',
 TOLERANCE='1%',
 MATERIAL='CHIP',
 VALUE='2K',
 PRIM_FILE='./archive_libs/logical/q_res/chips/chips.prt';

PART_NAME
 R3225 'Q_RES_0402LF-2K,1%,1/16W,CHIP,A':;

SECTION_NUMBER 1
 '@S9S_MB_2U_LIB.S9S_MB_2U(SCH_1):PAGE224_I130@PURE_QUANTA.Q_RES(CHIPS)':
 C_PATH='@s9s_mb_2u_lib.s9s_mb_2u(sch_1):page224_i130@pure_quanta.q_res(chips)',
 P_PATH='@s9s_mb_2u_lib.s9s_mb_2u(sch_1):page236_i130@pure_quanta.q_res(chips)',
 PATH='I130',
 DRAWING='@S9S_MB_2U_LIB.S9S_MB_2U(SCH_1):PAGE224',
 PHYS_PAGE='236',
 XY='(3650,6450)',
 ROT='0',
 VER='1',
 PACK_TYPE='0402LF',
 CDS_LIB='pure_quanta',
 CDS_PART_NAME='Q_RES_0402LF-2K,1%,1/16W,CHIP,A',
 WATTAGE='1/16W',
 TOLERANCE='1%',
 MATERIAL='CHIP',
 VALUE='2K',
 PRIM_FILE='./archive_libs/logical/q_res/chips/chips.prt';

PART_NAME
 R3226 'Q_RES_0402LF-2.2K,5%,1/16W,EMPA':;

SECTION_NUMBER 1
 '@S9S_MB_2U_LIB.S9S_MB_2U(SCH_1):PAGE228_I251@PURE_QUANTA.Q_RES(CHIPS)':
 C_PATH='@s9s_mb_2u_lib.s9s_mb_2u(sch_1):page228_i251@pure_quanta.q_res(chips)',
 P_PATH='@s9s_mb_2u_lib.s9s_mb_2u(sch_1):page241_i251@pure_quanta.q_res(chips)',
 PATH='I251',
 DRAWING='@S9S_MB_2U_LIB.S9S_MB_2U(SCH_1):PAGE228',
 PHYS_PAGE='241',
 XY='(5000,3300)',
 ROT='0',
 VER='1',
 PACK_TYPE='0402LF',
 CDS_LIB='pure_quanta',
 CDS_PART_NAME='Q_RES_0402LF-2.2K,5%,1/16W,EMPA',
 WATTAGE='1/16W',
 TOLERANCE='5%',
 MATERIAL='EMPTY',
 VALUE='2.2K',
 PRIM_FILE='./archive_libs/logical/q_res/chips/chips.prt';

PART_NAME
 R3227 'Q_RES_0402LF-2.2K,5%,1/16W,EMPA':;

SECTION_NUMBER 1
 '@S9S_MB_2U_LIB.S9S_MB_2U(SCH_1):PAGE228_I250@PURE_QUANTA.Q_RES(CHIPS)':
 C_PATH='@s9s_mb_2u_lib.s9s_mb_2u(sch_1):page228_i250@pure_quanta.q_res(chips)',
 P_PATH='@s9s_mb_2u_lib.s9s_mb_2u(sch_1):page241_i250@pure_quanta.q_res(chips)',
 PATH='I250',
 DRAWING='@S9S_MB_2U_LIB.S9S_MB_2U(SCH_1):PAGE228',
 PHYS_PAGE='241',
 XY='(5000,3250)',
 ROT='0',
 VER='1',
 PACK_TYPE='0402LF',
 CDS_LIB='pure_quanta',
 CDS_PART_NAME='Q_RES_0402LF-2.2K,5%,1/16W,EMPA',
 WATTAGE='1/16W',
 TOLERANCE='5%',
 MATERIAL='EMPTY',
 VALUE='2.2K',
 PRIM_FILE='./archive_libs/logical/q_res/chips/chips.prt';

PART_NAME
 R3228 'Q_RES_0402LF-200,1%,1/16W,CHIPA':;

SECTION_NUMBER 1
 '@S9S_MB_2U_LIB.S9S_MB_2U(SCH_1):PAGE146_I339@PURE_QUANTA.Q_RES(CHIPS)':
 C_PATH='@s9s_mb_2u_lib.s9s_mb_2u(sch_1):page146_i339@pure_quanta.q_res(chips)',
 P_PATH='@s9s_mb_2u_lib.s9s_mb_2u(sch_1):page159_i339@pure_quanta.q_res(chips)',
 PATH='I339',
 DRAWING='@S9S_MB_2U_LIB.S9S_MB_2U(SCH_1):PAGE146',
 PHYS_PAGE='159',
 XY='(6400,4075)',
 ROT='0',
 VER='1',
 PACK_TYPE='0402LF',
 LOCATION='R3228',
 CDS_LIB='pure_quanta',
 CDS_PART_NAME='Q_RES_0402LF-200,1%,1/16W,CHIPA',
 WATTAGE='1/16W',
 TOLERANCE='1%',
 MATERIAL='CHIP',
 VALUE='200',
 PRIM_FILE='./archive_libs/logical/q_res/chips/chips.prt';

PART_NAME
 R3229 'Q_RES_0402LF-200,1%,1/16W,CHIPA':;

SECTION_NUMBER 1
 '@S9S_MB_2U_LIB.S9S_MB_2U(SCH_1):PAGE146_I338@PURE_QUANTA.Q_RES(CHIPS)':
 C_PATH='@s9s_mb_2u_lib.s9s_mb_2u(sch_1):page146_i338@pure_quanta.q_res(chips)',
 P_PATH='@s9s_mb_2u_lib.s9s_mb_2u(sch_1):page159_i338@pure_quanta.q_res(chips)',
 PATH='I338',
 DRAWING='@S9S_MB_2U_LIB.S9S_MB_2U(SCH_1):PAGE146',
 PHYS_PAGE='159',
 XY='(6400,4025)',
 ROT='0',
 VER='1',
 PACK_TYPE='0402LF',
 LOCATION='R3229',
 CDS_LIB='pure_quanta',
 CDS_PART_NAME='Q_RES_0402LF-200,1%,1/16W,CHIPA',
 WATTAGE='1/16W',
 TOLERANCE='1%',
 MATERIAL='CHIP',
 VALUE='200',
 PRIM_FILE='./archive_libs/logical/q_res/chips/chips.prt';

PART_NAME
 R3230 'Q_RES_0402LF-33.2,1%,1/16W,CHIA':;

SECTION_NUMBER 1
 '@S9S_MB_2U_LIB.S9S_MB_2U(SCH_1):PAGE314_I110@PURE_QUANTA.Q_RES(CHIPS)':
 C_PATH='@s9s_mb_2u_lib.s9s_mb_2u(sch_1):page314_i110@pure_quanta.q_res(chips)',
 P_PATH='@s9s_mb_2u_lib.s9s_mb_2u(sch_1):page213_i110@pure_quanta.q_res(chips)',
 PATH='I110',
 DRAWING='@S9S_MB_2U_LIB.S9S_MB_2U(SCH_1):PAGE314',
 PHYS_PAGE='213',
 XY='(2725,-775)',
 ROT='0',
 VER='1',
 PACK_TYPE='0402LF',
 LOCATION='R3230',
 CDS_LIB='pure_quanta',
 CDS_PART_NAME='Q_RES_0402LF-33.2,1%,1/16W,CHIA',
 WATTAGE='1/16W',
 TOLERANCE='1%',
 MATERIAL='CHIP',
 VALUE='33.2',
 PRIM_FILE='./archive_libs/logical/q_res/chips/chips.prt';

PART_NAME
 R3231 'Q_RES_0402LF-33.2,1%,1/16W,CHIA':;

SECTION_NUMBER 1
 '@S9S_MB_2U_LIB.S9S_MB_2U(SCH_1):PAGE151_I3@PURE_QUANTA.Q_RES(CHIPS)':
 C_PATH='@s9s_mb_2u_lib.s9s_mb_2u(sch_1):page151_i3@pure_quanta.q_res(chips)',
 P_PATH='@s9s_mb_2u_lib.s9s_mb_2u(sch_1):page154_i3@pure_quanta.q_res(chips)',
 PATH='I3',
 DRAWING='@S9S_MB_2U_LIB.S9S_MB_2U(SCH_1):PAGE151',
 PHYS_PAGE='154',
 XY='(-4750,1950)',
 ROT='0',
 VER='1',
 PACK_TYPE='0402LF',
 CDS_LIB='pure_quanta',
 CDS_PART_NAME='Q_RES_0402LF-33.2,1%,1/16W,CHIA',
 WATTAGE='1/16W',
 TOLERANCE='1%',
 MATERIAL='CHIP',
 VALUE='33.2',
 PRIM_FILE='./archive_libs/logical/q_res/chips/chips.prt';

PART_NAME
 R3232 'Q_RES_0402LF-100K,1%,1/16W,CHIA':;

SECTION_NUMBER 1
 '@S9S_MB_2U_LIB.S9S_MB_2U(SCH_1):PAGE151_I13@PURE_QUANTA.Q_RES(CHIPS)':
 C_PATH='@s9s_mb_2u_lib.s9s_mb_2u(sch_1):page151_i13@pure_quanta.q_res(chips)',
 P_PATH='@s9s_mb_2u_lib.s9s_mb_2u(sch_1):page154_i13@pure_quanta.q_res(chips)',
 PATH='I13',
 DRAWING='@S9S_MB_2U_LIB.S9S_MB_2U(SCH_1):PAGE151',
 PHYS_PAGE='154',
 XY='(-2525,1775)',
 ROT='0',
 VER='2',
 PACK_TYPE='0402LF',
 CDS_LIB='pure_quanta',
 CDS_PART_NAME='Q_RES_0402LF-100K,1%,1/16W,CHIA',
 WATTAGE='1/16W',
 TOLERANCE='1%',
 MATERIAL='CHIP',
 VALUE='100K',
 PRIM_FILE='./archive_libs/logical/q_res/chips/chips.prt';

PART_NAME
 R3233 'Q_RES_0402LF-0,5%,1/16W,CHIP,CA':;

SECTION_NUMBER 1
 '@S9S_MB_2U_LIB.S9S_MB_2U(SCH_1):PAGE151_I17@PURE_QUANTA.Q_RES(CHIPS)':
 C_PATH='@s9s_mb_2u_lib.s9s_mb_2u(sch_1):page151_i17@pure_quanta.q_res(chips)',
 P_PATH='@s9s_mb_2u_lib.s9s_mb_2u(sch_1):page154_i17@pure_quanta.q_res(chips)',
 PATH='I17',
 DRAWING='@S9S_MB_2U_LIB.S9S_MB_2U(SCH_1):PAGE151',
 PHYS_PAGE='154',
 XY='(-2200,2000)',
 ROT='0',
 VER='1',
 PACK_TYPE='0402LF',
 CDS_LIB='pure_quanta',
 CDS_PART_NAME='Q_RES_0402LF-0,5%,1/16W,CHIP,CA',
 WATTAGE='1/16W',
 TOLERANCE='5%',
 MATERIAL='CHIP',
 VALUE='0',
 PRIM_FILE='./archive_libs/logical/q_res/chips/chips.prt';

PART_NAME
 R3234 'Q_RES_0402LF-33.2,1%,1/16W,CHIA':;

SECTION_NUMBER 1
 '@S9S_MB_2U_LIB.S9S_MB_2U(SCH_1):PAGE156_I75@PURE_QUANTA.Q_RES(CHIPS)':
 C_PATH='@s9s_mb_2u_lib.s9s_mb_2u(sch_1):page156_i75@pure_quanta.q_res(chips)',
 P_PATH='@s9s_mb_2u_lib.s9s_mb_2u(sch_1):page161_i75@pure_quanta.q_res(chips)',
 PATH='I75',
 DRAWING='@S9S_MB_2U_LIB.S9S_MB_2U(SCH_1):PAGE156',
 PHYS_PAGE='161',
 XY='(4350,-3225)',
 ROT='0',
 VER='1',
 PACK_TYPE='0402LF',
 CDS_LIB='pure_quanta',
 CDS_PART_NAME='Q_RES_0402LF-33.2,1%,1/16W,CHIA',
 WATTAGE='1/16W',
 TOLERANCE='1%',
 MATERIAL='CHIP',
 VALUE='33.2',
 PRIM_FILE='./archive_libs/logical/q_res/chips/chips.prt';

PART_NAME
 R3235 'Q_RES_0402LF-100K,1%,1/16W,CHIA':;

SECTION_NUMBER 1
 '@S9S_MB_2U_LIB.S9S_MB_2U(SCH_1):PAGE156_I72@PURE_QUANTA.Q_RES(CHIPS)':
 C_PATH='@s9s_mb_2u_lib.s9s_mb_2u(sch_1):page156_i72@pure_quanta.q_res(chips)',
 P_PATH='@s9s_mb_2u_lib.s9s_mb_2u(sch_1):page161_i72@pure_quanta.q_res(chips)',
 PATH='I72',
 DRAWING='@S9S_MB_2U_LIB.S9S_MB_2U(SCH_1):PAGE156',
 PHYS_PAGE='161',
 XY='(6875,-3375)',
 ROT='0',
 VER='2',
 PACK_TYPE='0402LF',
 CDS_LIB='pure_quanta',
 CDS_PART_NAME='Q_RES_0402LF-100K,1%,1/16W,CHIA',
 WATTAGE='1/16W',
 TOLERANCE='1%',
 MATERIAL='CHIP',
 VALUE='100K',
 PRIM_FILE='./archive_libs/logical/q_res/chips/chips.prt';

PART_NAME
 R3236 'Q_RES_0402LF-0,5%,1/16W,CHIP,CA':;

SECTION_NUMBER 1
 '@S9S_MB_2U_LIB.S9S_MB_2U(SCH_1):PAGE156_I70@PURE_QUANTA.Q_RES(CHIPS)':
 C_PATH='@s9s_mb_2u_lib.s9s_mb_2u(sch_1):page156_i70@pure_quanta.q_res(chips)',
 P_PATH='@s9s_mb_2u_lib.s9s_mb_2u(sch_1):page161_i70@pure_quanta.q_res(chips)',
 PATH='I70',
 DRAWING='@S9S_MB_2U_LIB.S9S_MB_2U(SCH_1):PAGE156',
 PHYS_PAGE='161',
 XY='(7150,-3175)',
 ROT='0',
 VER='1',
 PACK_TYPE='0402LF',
 CDS_LIB='pure_quanta',
 CDS_PART_NAME='Q_RES_0402LF-0,5%,1/16W,CHIP,CA',
 WATTAGE='1/16W',
 TOLERANCE='5%',
 MATERIAL='CHIP',
 VALUE='0',
 PRIM_FILE='./archive_libs/logical/q_res/chips/chips.prt';

PART_NAME
 R3237 'Q_RES_0402LF-0,5%,1/16W,CHIP,CA':;

SECTION_NUMBER 1
 '@S9S_MB_2U_LIB.S9S_MB_2U(SCH_1):PAGE151_I80@PURE_QUANTA.Q_RES(CHIPS)':
 C_PATH='@s9s_mb_2u_lib.s9s_mb_2u(sch_1):page151_i80@pure_quanta.q_res(chips)',
 P_PATH='@s9s_mb_2u_lib.s9s_mb_2u(sch_1):page154_i80@pure_quanta.q_res(chips)',
 PATH='I80',
 DRAWING='@S9S_MB_2U_LIB.S9S_MB_2U(SCH_1):PAGE151',
 PHYS_PAGE='154',
 XY='(1500,6450)',
 ROT='1',
 VER='1',
 PACK_TYPE='0402LF',
 CDS_LIB='pure_quanta',
 CDS_PART_NAME='Q_RES_0402LF-0,5%,1/16W,CHIP,CA',
 WATTAGE='1/16W',
 TOLERANCE='5%',
 MATERIAL='CHIP',
 VALUE='0',
 PRIM_FILE='./archive_libs/logical/q_res/chips/chips.prt';

PART_NAME
 R3238 'Q_RES_0402LF-33.2,1%,1/16W,CHIA':;

SECTION_NUMBER 1
 '@S9S_MB_2U_LIB.S9S_MB_2U(SCH_1):PAGE227_I101@PURE_QUANTA.Q_RES(CHIPS)':
 C_PATH='@s9s_mb_2u_lib.s9s_mb_2u(sch_1):page227_i101@pure_quanta.q_res(chips)',
 P_PATH='@s9s_mb_2u_lib.s9s_mb_2u(sch_1):page240_i101@pure_quanta.q_res(chips)',
 PATH='I101',
 DRAWING='@S9S_MB_2U_LIB.S9S_MB_2U(SCH_1):PAGE227',
 PHYS_PAGE='240',
 XY='(-13275,1375)',
 ROT='0',
 VER='1',
 PACK_TYPE='0402LF',
 CDS_LIB='pure_quanta',
 CDS_PART_NAME='Q_RES_0402LF-33.2,1%,1/16W,CHIA',
 WATTAGE='1/16W',
 TOLERANCE='1%',
 MATERIAL='CHIP',
 VALUE='33.2',
 PRIM_FILE='./archive_libs/logical/q_res/chips/chips.prt';

PART_NAME
 R3239 'Q_RES_0402LF-33.2,1%,1/16W,CHIA':;

SECTION_NUMBER 1
 '@S9S_MB_2U_LIB.S9S_MB_2U(SCH_1):PAGE227_I102@PURE_QUANTA.Q_RES(CHIPS)':
 C_PATH='@s9s_mb_2u_lib.s9s_mb_2u(sch_1):page227_i102@pure_quanta.q_res(chips)',
 P_PATH='@s9s_mb_2u_lib.s9s_mb_2u(sch_1):page240_i102@pure_quanta.q_res(chips)',
 PATH='I102',
 DRAWING='@S9S_MB_2U_LIB.S9S_MB_2U(SCH_1):PAGE227',
 PHYS_PAGE='240',
 XY='(-13275,1325)',
 ROT='0',
 VER='1',
 PACK_TYPE='0402LF',
 CDS_LIB='pure_quanta',
 CDS_PART_NAME='Q_RES_0402LF-33.2,1%,1/16W,CHIA',
 WATTAGE='1/16W',
 TOLERANCE='1%',
 MATERIAL='CHIP',
 VALUE='33.2',
 PRIM_FILE='./archive_libs/logical/q_res/chips/chips.prt';

PART_NAME
 R3240 'Q_RES_0402LF-2.2K,5%,1/16W,EMPA':;

SECTION_NUMBER 1
 '@S9S_MB_2U_LIB.S9S_MB_2U(SCH_1):PAGE228_I259@PURE_QUANTA.Q_RES(CHIPS)':
 C_PATH='@s9s_mb_2u_lib.s9s_mb_2u(sch_1):page228_i259@pure_quanta.q_res(chips)',
 P_PATH='@s9s_mb_2u_lib.s9s_mb_2u(sch_1):page241_i259@pure_quanta.q_res(chips)',
 PATH='I259',
 DRAWING='@S9S_MB_2U_LIB.S9S_MB_2U(SCH_1):PAGE228',
 PHYS_PAGE='241',
 XY='(5000,3025)',
 ROT='0',
 VER='1',
 PACK_TYPE='0402LF',
 CDS_LIB='pure_quanta',
 CDS_PART_NAME='Q_RES_0402LF-2.2K,5%,1/16W,EMPA',
 WATTAGE='1/16W',
 TOLERANCE='5%',
 MATERIAL='EMPTY',
 VALUE='2.2K',
 PRIM_FILE='./archive_libs/logical/q_res/chips/chips.prt';

PART_NAME
 R3241 'Q_RES_0402LF-2.2K,5%,1/16W,EMPA':;

SECTION_NUMBER 1
 '@S9S_MB_2U_LIB.S9S_MB_2U(SCH_1):PAGE228_I258@PURE_QUANTA.Q_RES(CHIPS)':
 C_PATH='@s9s_mb_2u_lib.s9s_mb_2u(sch_1):page228_i258@pure_quanta.q_res(chips)',
 P_PATH='@s9s_mb_2u_lib.s9s_mb_2u(sch_1):page241_i258@pure_quanta.q_res(chips)',
 PATH='I258',
 DRAWING='@S9S_MB_2U_LIB.S9S_MB_2U(SCH_1):PAGE228',
 PHYS_PAGE='241',
 XY='(5000,2975)',
 ROT='0',
 VER='1',
 PACK_TYPE='0402LF',
 CDS_LIB='pure_quanta',
 CDS_PART_NAME='Q_RES_0402LF-2.2K,5%,1/16W,EMPA',
 WATTAGE='1/16W',
 TOLERANCE='5%',
 MATERIAL='EMPTY',
 VALUE='2.2K',
 PRIM_FILE='./archive_libs/logical/q_res/chips/chips.prt';

PART_NAME
 R3242 'Q_RES_0402LF-2.2K,5%,1/16W,EMPA':;

SECTION_NUMBER 1
 '@S9S_MB_2U_LIB.S9S_MB_2U(SCH_1):PAGE228_I260@PURE_QUANTA.Q_RES(CHIPS)':
 C_PATH='@s9s_mb_2u_lib.s9s_mb_2u(sch_1):page228_i260@pure_quanta.q_res(chips)',
 P_PATH='@s9s_mb_2u_lib.s9s_mb_2u(sch_1):page241_i260@pure_quanta.q_res(chips)',
 PATH='I260',
 DRAWING='@S9S_MB_2U_LIB.S9S_MB_2U(SCH_1):PAGE228',
 PHYS_PAGE='241',
 XY='(5000,2725)',
 ROT='0',
 VER='1',
 PACK_TYPE='0402LF',
 CDS_LIB='pure_quanta',
 CDS_PART_NAME='Q_RES_0402LF-2.2K,5%,1/16W,EMPA',
 WATTAGE='1/16W',
 TOLERANCE='5%',
 MATERIAL='EMPTY',
 VALUE='2.2K',
 PRIM_FILE='./archive_libs/logical/q_res/chips/chips.prt';

PART_NAME
 R3243 'Q_RES_0402LF-2.2K,5%,1/16W,EMPA':;

SECTION_NUMBER 1
 '@S9S_MB_2U_LIB.S9S_MB_2U(SCH_1):PAGE228_I261@PURE_QUANTA.Q_RES(CHIPS)':
 C_PATH='@s9s_mb_2u_lib.s9s_mb_2u(sch_1):page228_i261@pure_quanta.q_res(chips)',
 P_PATH='@s9s_mb_2u_lib.s9s_mb_2u(sch_1):page241_i261@pure_quanta.q_res(chips)',
 PATH='I261',
 DRAWING='@S9S_MB_2U_LIB.S9S_MB_2U(SCH_1):PAGE228',
 PHYS_PAGE='241',
 XY='(5000,2675)',
 ROT='0',
 VER='1',
 PACK_TYPE='0402LF',
 CDS_LIB='pure_quanta',
 CDS_PART_NAME='Q_RES_0402LF-2.2K,5%,1/16W,EMPA',
 WATTAGE='1/16W',
 TOLERANCE='5%',
 MATERIAL='EMPTY',
 VALUE='2.2K',
 PRIM_FILE='./archive_libs/logical/q_res/chips/chips.prt';

PART_NAME
 R3244 'Q_RES_0402LF-0,5%,1/16W,CHIP,CA':;

SECTION_NUMBER 1
 '@S9S_MB_2U_LIB.S9S_MB_2U(SCH_1):PAGE307_I79@PURE_QUANTA.Q_RES(CHIPS)':
 C_PATH='@s9s_mb_2u_lib.s9s_mb_2u(sch_1):page307_i79@pure_quanta.q_res(chips)',
 P_PATH='@s9s_mb_2u_lib.s9s_mb_2u(sch_1):page160_i79@pure_quanta.q_res(chips)',
 PATH='I79',
 DRAWING='@S9S_MB_2U_LIB.S9S_MB_2U(SCH_1):PAGE307',
 PHYS_PAGE='160',
 XY='(3275,2275)',
 ROT='1',
 VER='1',
 PACK_TYPE='0402LF',
 CDS_LIB='pure_quanta',
 CDS_PART_NAME='Q_RES_0402LF-0,5%,1/16W,CHIP,CA',
 WATTAGE='1/16W',
 TOLERANCE='5%',
 MATERIAL='CHIP',
 VALUE='0',
 PRIM_FILE='./archive_libs/logical/q_res/chips/chips.prt';

PART_NAME
 R3249 'Q_RES_0402LF-10K,1%,1/16W,CHIPA':;

SECTION_NUMBER 1
 '@S9S_MB_2U_LIB.S9S_MB_2U(SCH_1):PAGE311_I29@PURE_QUANTA.Q_RES(CHIPS)':
 C_PATH='@s9s_mb_2u_lib.s9s_mb_2u(sch_1):page311_i29@pure_quanta.q_res(chips)',
 P_PATH='@s9s_mb_2u_lib.s9s_mb_2u(sch_1):page216_i29@pure_quanta.q_res(chips)',
 PATH='I29',
 DRAWING='@S9S_MB_2U_LIB.S9S_MB_2U(SCH_1):PAGE311',
 PHYS_PAGE='216',
 XY='(1300,50)',
 ROT='0',
 VER='2',
 PACK_TYPE='0402LF',
 CDS_LIB='pure_quanta',
 CDS_PART_NAME='Q_RES_0402LF-10K,1%,1/16W,CHIPA',
 WATTAGE='1/16W',
 TOLERANCE='1%',
 MATERIAL='CHIP',
 VALUE='10K',
 PRIM_FILE='./archive_libs/logical/q_res/chips/chips.prt';

PART_NAME
 R3254 'Q_RES_0402LF-0,5%,1/16W,EMPTY,A':;

SECTION_NUMBER 1
 '@S9S_MB_2U_LIB.S9S_MB_2U(SCH_1):PAGE227_I49@PURE_QUANTA.Q_RES(CHIPS)':
 C_PATH='@s9s_mb_2u_lib.s9s_mb_2u(sch_1):page227_i49@pure_quanta.q_res(chips)',
 P_PATH='@s9s_mb_2u_lib.s9s_mb_2u(sch_1):page240_i49@pure_quanta.q_res(chips)',
 PATH='I49',
 DRAWING='@S9S_MB_2U_LIB.S9S_MB_2U(SCH_1):PAGE227',
 PHYS_PAGE='240',
 XY='(-7875,-2175)',
 ROT='0',
 VER='1',
 PACK_TYPE='0402LF',
 CDS_LIB='pure_quanta',
 CDS_PART_NAME='Q_RES_0402LF-0,5%,1/16W,EMPTY,A',
 WATTAGE='1/16W',
 TOLERANCE='5%',
 MATERIAL='EMPTY',
 VALUE='0',
 PRIM_FILE='./archive_libs/logical/q_res/chips/chips.prt';

PART_NAME
 R3263 'Q_RES_0402LF-0,5%,1/16W,CHIP,CA':;

SECTION_NUMBER 1
 '@S9S_MB_2U_LIB.S9S_MB_2U(SCH_1):PAGE216_I21@PURE_QUANTA.Q_RES(CHIPS)':
 C_PATH='@s9s_mb_2u_lib.s9s_mb_2u(sch_1):page216_i21@pure_quanta.q_res(chips)',
 P_PATH='@s9s_mb_2u_lib.s9s_mb_2u(sch_1):page238_i21@pure_quanta.q_res(chips)',
 PATH='I21',
 DRAWING='@S9S_MB_2U_LIB.S9S_MB_2U(SCH_1):PAGE216',
 PHYS_PAGE='238',
 XY='(-5825,5075)',
 ROT='0',
 VER='1',
 PACK_TYPE='0402LF',
 CDS_LIB='pure_quanta',
 CDS_PART_NAME='Q_RES_0402LF-0,5%,1/16W,CHIP,CA',
 WATTAGE='1/16W',
 TOLERANCE='5%',
 MATERIAL='CHIP',
 VALUE='0',
 PRIM_FILE='./archive_libs/logical/q_res/chips/chips.prt';

PART_NAME
 R3264 'Q_RES_0402LF-0,5%,1/16W,CHIP,CA':;

SECTION_NUMBER 1
 '@S9S_MB_2U_LIB.S9S_MB_2U(SCH_1):PAGE216_I7@PURE_QUANTA.Q_RES(CHIPS)':
 C_PATH='@s9s_mb_2u_lib.s9s_mb_2u(sch_1):page216_i7@pure_quanta.q_res(chips)',
 P_PATH='@s9s_mb_2u_lib.s9s_mb_2u(sch_1):page238_i7@pure_quanta.q_res(chips)',
 PATH='I7',
 DRAWING='@S9S_MB_2U_LIB.S9S_MB_2U(SCH_1):PAGE216',
 PHYS_PAGE='238',
 XY='(-5750,3250)',
 ROT='0',
 VER='1',
 PACK_TYPE='0402LF',
 CDS_LIB='pure_quanta',
 CDS_PART_NAME='Q_RES_0402LF-0,5%,1/16W,CHIP,CA',
 WATTAGE='1/16W',
 TOLERANCE='5%',
 MATERIAL='CHIP',
 VALUE='0',
 PRIM_FILE='./archive_libs/logical/q_res/chips/chips.prt';

PART_NAME
 R3265 'Q_RES_0402LF-4.7K,1%,1/16W,EMPA':;

SECTION_NUMBER 1
 '@S9S_MB_2U_LIB.S9S_MB_2U(SCH_1):PAGE136_I84@PURE_QUANTA.Q_RES(CHIPS)':
 C_PATH='@s9s_mb_2u_lib.s9s_mb_2u(sch_1):page136_i84@pure_quanta.q_res(chips)',
 P_PATH='@s9s_mb_2u_lib.s9s_mb_2u(sch_1):page166_i84@pure_quanta.q_res(chips)',
 PATH='I84',
 DRAWING='@S9S_MB_2U_LIB.S9S_MB_2U(SCH_1):PAGE136',
 PHYS_PAGE='166',
 XY='(3100,375)',
 ROT='0',
 VER='2',
 PACK_TYPE='0402LF',
 CDS_LIB='pure_quanta',
 CDS_PART_NAME='Q_RES_0402LF-4.7K,1%,1/16W,EMPA',
 WATTAGE='1/16W',
 TOLERANCE='1%',
 MATERIAL='EMPTY',
 VALUE='4.7K',
 PRIM_FILE='./archive_libs/logical/q_res/chips/chips.prt';

PART_NAME
 R3266 'Q_RES_0402LF-4.7K,1%,1/16W,CHIA':
 ROOM='PCIE REDRIVER1_BOM1';

SECTION_NUMBER 1
 '@S9S_MB_2U_LIB.S9S_MB_2U(SCH_1):PAGE136_I89@PURE_QUANTA.Q_RES(CHIPS)':
 C_PATH='@s9s_mb_2u_lib.s9s_mb_2u(sch_1):page136_i89@pure_quanta.q_res(chips)',
 P_PATH='@s9s_mb_2u_lib.s9s_mb_2u(sch_1):page166_i89@pure_quanta.q_res(chips)',
 PATH='I89',
 DRAWING='@S9S_MB_2U_LIB.S9S_MB_2U(SCH_1):PAGE136',
 PHYS_PAGE='166',
 XY='(3100,2375)',
 ROT='0',
 VER='2',
 PACK_TYPE='0402LF',
 CDS_LIB='pure_quanta',
 CDS_PART_NAME='Q_RES_0402LF-4.7K,1%,1/16W,CHIA',
 WATTAGE='1/16W',
 TOLERANCE='1%',
 MATERIAL='CHIP',
 ROOM='PCIE REDRIVER1_BOM1',
 VALUE='4.7K',
 PRIM_FILE='./archive_libs/logical/q_res/chips/chips.prt';

PART_NAME
 R3267 'Q_RES_0402LF-68K,1%,1/16W,EMPTA':;

SECTION_NUMBER 1
 '@S9S_MB_2U_LIB.S9S_MB_2U(SCH_1):PAGE136_I12@PURE_QUANTA.Q_RES(CHIPS)':
 C_PATH='@s9s_mb_2u_lib.s9s_mb_2u(sch_1):page136_i12@pure_quanta.q_res(chips)',
 P_PATH='@s9s_mb_2u_lib.s9s_mb_2u(sch_1):page166_i12@pure_quanta.q_res(chips)',
 PATH='I12',
 DRAWING='@S9S_MB_2U_LIB.S9S_MB_2U(SCH_1):PAGE136',
 PHYS_PAGE='166',
 XY='(-4500,-800)',
 ROT='0',
 VER='2',
 PACK_TYPE='0402LF',
 CDS_LIB='pure_quanta',
 CDS_PART_NAME='Q_RES_0402LF-68K,1%,1/16W,EMPTA',
 WATTAGE='1/16W',
 TOLERANCE='1%',
 MATERIAL='EMPTY',
 VALUE='68K',
 PRIM_FILE='./archive_libs/logical/q_res/chips/chips.prt';

PART_NAME
 R3268 'Q_RES_0402LF-68K,1%,1/16W,EMPTA':;

SECTION_NUMBER 1
 '@S9S_MB_2U_LIB.S9S_MB_2U(SCH_1):PAGE136_I2@PURE_QUANTA.Q_RES(CHIPS)':
 C_PATH='@s9s_mb_2u_lib.s9s_mb_2u(sch_1):page136_i2@pure_quanta.q_res(chips)',
 P_PATH='@s9s_mb_2u_lib.s9s_mb_2u(sch_1):page166_i2@pure_quanta.q_res(chips)',
 PATH='I2',
 DRAWING='@S9S_MB_2U_LIB.S9S_MB_2U(SCH_1):PAGE136',
 PHYS_PAGE='166',
 XY='(-4325,-2525)',
 ROT='0',
 VER='2',
 PACK_TYPE='0402LF',
 CDS_LIB='pure_quanta',
 CDS_PART_NAME='Q_RES_0402LF-68K,1%,1/16W,EMPTA',
 WATTAGE='1/16W',
 TOLERANCE='1%',
 MATERIAL='EMPTY',
 VALUE='68K',
 PRIM_FILE='./archive_libs/logical/q_res/chips/chips.prt';

PART_NAME
 R3269 'Q_RES_0402LF-1K,1%,1/16W,EMPTYA':;

SECTION_NUMBER 1
 '@S9S_MB_2U_LIB.S9S_MB_2U(SCH_1):PAGE136_I15@PURE_QUANTA.Q_RES(CHIPS)':
 C_PATH='@s9s_mb_2u_lib.s9s_mb_2u(sch_1):page136_i15@pure_quanta.q_res(chips)',
 P_PATH='@s9s_mb_2u_lib.s9s_mb_2u(sch_1):page166_i15@pure_quanta.q_res(chips)',
 PATH='I15',
 DRAWING='@S9S_MB_2U_LIB.S9S_MB_2U(SCH_1):PAGE136',
 PHYS_PAGE='166',
 XY='(-4125,-275)',
 ROT='0',
 VER='2',
 PACK_TYPE='0402LF',
 CDS_LIB='pure_quanta',
 CDS_PART_NAME='Q_RES_0402LF-1K,1%,1/16W,EMPTYA',
 WATTAGE='1/16W',
 TOLERANCE='1%',
 MATERIAL='EMPTY',
 VALUE='1K',
 PRIM_FILE='./archive_libs/logical/q_res/chips/chips.prt';

PART_NAME
 R3270 'Q_RES_0402LF-1K,1%,1/16W,EMPTYA':;

SECTION_NUMBER 1
 '@S9S_MB_2U_LIB.S9S_MB_2U(SCH_1):PAGE136_I14@PURE_QUANTA.Q_RES(CHIPS)':
 C_PATH='@s9s_mb_2u_lib.s9s_mb_2u(sch_1):page136_i14@pure_quanta.q_res(chips)',
 P_PATH='@s9s_mb_2u_lib.s9s_mb_2u(sch_1):page166_i14@pure_quanta.q_res(chips)',
 PATH='I14',
 DRAWING='@S9S_MB_2U_LIB.S9S_MB_2U(SCH_1):PAGE136',
 PHYS_PAGE='166',
 XY='(-4125,-800)',
 ROT='0',
 VER='2',
 PACK_TYPE='0402LF',
 CDS_LIB='pure_quanta',
 CDS_PART_NAME='Q_RES_0402LF-1K,1%,1/16W,EMPTYA',
 WATTAGE='1/16W',
 TOLERANCE='1%',
 MATERIAL='EMPTY',
 VALUE='1K',
 PRIM_FILE='./archive_libs/logical/q_res/chips/chips.prt';

PART_NAME
 R3271 'Q_RES_0402LF-1K,1%,1/16W,EMPTYA':;

SECTION_NUMBER 1
 '@S9S_MB_2U_LIB.S9S_MB_2U(SCH_1):PAGE136_I9@PURE_QUANTA.Q_RES(CHIPS)':
 C_PATH='@s9s_mb_2u_lib.s9s_mb_2u(sch_1):page136_i9@pure_quanta.q_res(chips)',
 P_PATH='@s9s_mb_2u_lib.s9s_mb_2u(sch_1):page166_i9@pure_quanta.q_res(chips)',
 PATH='I9',
 DRAWING='@S9S_MB_2U_LIB.S9S_MB_2U(SCH_1):PAGE136',
 PHYS_PAGE='166',
 XY='(-3950,-2000)',
 ROT='0',
 VER='2',
 PACK_TYPE='0402LF',
 CDS_LIB='pure_quanta',
 CDS_PART_NAME='Q_RES_0402LF-1K,1%,1/16W,EMPTYA',
 WATTAGE='1/16W',
 TOLERANCE='1%',
 MATERIAL='EMPTY',
 VALUE='1K',
 PRIM_FILE='./archive_libs/logical/q_res/chips/chips.prt';

PART_NAME
 R3272 'Q_RES_0402LF-1K,1%,1/16W,EMPTYA':;

SECTION_NUMBER 1
 '@S9S_MB_2U_LIB.S9S_MB_2U(SCH_1):PAGE136_I4@PURE_QUANTA.Q_RES(CHIPS)':
 C_PATH='@s9s_mb_2u_lib.s9s_mb_2u(sch_1):page136_i4@pure_quanta.q_res(chips)',
 P_PATH='@s9s_mb_2u_lib.s9s_mb_2u(sch_1):page166_i4@pure_quanta.q_res(chips)',
 PATH='I4',
 DRAWING='@S9S_MB_2U_LIB.S9S_MB_2U(SCH_1):PAGE136',
 PHYS_PAGE='166',
 XY='(-3950,-2525)',
 ROT='0',
 VER='2',
 PACK_TYPE='0402LF',
 CDS_LIB='pure_quanta',
 CDS_PART_NAME='Q_RES_0402LF-1K,1%,1/16W,EMPTYA',
 WATTAGE='1/16W',
 TOLERANCE='1%',
 MATERIAL='EMPTY',
 VALUE='1K',
 PRIM_FILE='./archive_libs/logical/q_res/chips/chips.prt';

PART_NAME
 R3273 'Q_RES_0402LF-68K,1%,1/16W,EMPTA':;

SECTION_NUMBER 1
 '@S9S_MB_2U_LIB.S9S_MB_2U(SCH_1):PAGE136_I18@PURE_QUANTA.Q_RES(CHIPS)':
 C_PATH='@s9s_mb_2u_lib.s9s_mb_2u(sch_1):page136_i18@pure_quanta.q_res(chips)',
 P_PATH='@s9s_mb_2u_lib.s9s_mb_2u(sch_1):page166_i18@pure_quanta.q_res(chips)',
 PATH='I18',
 DRAWING='@S9S_MB_2U_LIB.S9S_MB_2U(SCH_1):PAGE136',
 PHYS_PAGE='166',
 XY='(-3650,-825)',
 ROT='0',
 VER='2',
 PACK_TYPE='0402LF',
 CDS_LIB='pure_quanta',
 CDS_PART_NAME='Q_RES_0402LF-68K,1%,1/16W,EMPTA',
 WATTAGE='1/16W',
 TOLERANCE='1%',
 MATERIAL='EMPTY',
 VALUE='68K',
 PRIM_FILE='./archive_libs/logical/q_res/chips/chips.prt';

PART_NAME
 R3274 'Q_RES_0402LF-68K,1%,1/16W,EMPTA':;

SECTION_NUMBER 1
 '@S9S_MB_2U_LIB.S9S_MB_2U(SCH_1):PAGE136_I6@PURE_QUANTA.Q_RES(CHIPS)':
 C_PATH='@s9s_mb_2u_lib.s9s_mb_2u(sch_1):page136_i6@pure_quanta.q_res(chips)',
 P_PATH='@s9s_mb_2u_lib.s9s_mb_2u(sch_1):page166_i6@pure_quanta.q_res(chips)',
 PATH='I6',
 DRAWING='@S9S_MB_2U_LIB.S9S_MB_2U(SCH_1):PAGE136',
 PHYS_PAGE='166',
 XY='(-3475,-2550)',
 ROT='0',
 VER='2',
 PACK_TYPE='0402LF',
 CDS_LIB='pure_quanta',
 CDS_PART_NAME='Q_RES_0402LF-68K,1%,1/16W,EMPTA',
 WATTAGE='1/16W',
 TOLERANCE='1%',
 MATERIAL='EMPTY',
 VALUE='68K',
 PRIM_FILE='./archive_libs/logical/q_res/chips/chips.prt';

PART_NAME
 R3275 'Q_RES_0402LF-1K,1%,1/16W,EMPTYA':;

SECTION_NUMBER 1
 '@S9S_MB_2U_LIB.S9S_MB_2U(SCH_1):PAGE136_I21@PURE_QUANTA.Q_RES(CHIPS)':
 C_PATH='@s9s_mb_2u_lib.s9s_mb_2u(sch_1):page136_i21@pure_quanta.q_res(chips)',
 P_PATH='@s9s_mb_2u_lib.s9s_mb_2u(sch_1):page166_i21@pure_quanta.q_res(chips)',
 PATH='I21',
 DRAWING='@S9S_MB_2U_LIB.S9S_MB_2U(SCH_1):PAGE136',
 PHYS_PAGE='166',
 XY='(-3250,-275)',
 ROT='0',
 VER='2',
 PACK_TYPE='0402LF',
 CDS_LIB='pure_quanta',
 CDS_PART_NAME='Q_RES_0402LF-1K,1%,1/16W,EMPTYA',
 WATTAGE='1/16W',
 TOLERANCE='1%',
 MATERIAL='EMPTY',
 VALUE='1K',
 PRIM_FILE='./archive_libs/logical/q_res/chips/chips.prt';

PART_NAME
 R3276 'Q_RES_0402LF-1K,1%,1/16W,EMPTYA':;

SECTION_NUMBER 1
 '@S9S_MB_2U_LIB.S9S_MB_2U(SCH_1):PAGE136_I20@PURE_QUANTA.Q_RES(CHIPS)':
 C_PATH='@s9s_mb_2u_lib.s9s_mb_2u(sch_1):page136_i20@pure_quanta.q_res(chips)',
 P_PATH='@s9s_mb_2u_lib.s9s_mb_2u(sch_1):page166_i20@pure_quanta.q_res(chips)',
 PATH='I20',
 DRAWING='@S9S_MB_2U_LIB.S9S_MB_2U(SCH_1):PAGE136',
 PHYS_PAGE='166',
 XY='(-3250,-850)',
 ROT='0',
 VER='2',
 PACK_TYPE='0402LF',
 CDS_LIB='pure_quanta',
 CDS_PART_NAME='Q_RES_0402LF-1K,1%,1/16W,EMPTYA',
 WATTAGE='1/16W',
 TOLERANCE='1%',
 MATERIAL='EMPTY',
 VALUE='1K',
 PRIM_FILE='./archive_libs/logical/q_res/chips/chips.prt';

PART_NAME
 R3277 'Q_RES_0402LF-1K,1%,1/16W,EMPTYA':;

SECTION_NUMBER 1
 '@S9S_MB_2U_LIB.S9S_MB_2U(SCH_1):PAGE136_I16@PURE_QUANTA.Q_RES(CHIPS)':
 C_PATH='@s9s_mb_2u_lib.s9s_mb_2u(sch_1):page136_i16@pure_quanta.q_res(chips)',
 P_PATH='@s9s_mb_2u_lib.s9s_mb_2u(sch_1):page166_i16@pure_quanta.q_res(chips)',
 PATH='I16',
 DRAWING='@S9S_MB_2U_LIB.S9S_MB_2U(SCH_1):PAGE136',
 PHYS_PAGE='166',
 XY='(-3075,-2000)',
 ROT='0',
 VER='2',
 PACK_TYPE='0402LF',
 CDS_LIB='pure_quanta',
 CDS_PART_NAME='Q_RES_0402LF-1K,1%,1/16W,EMPTYA',
 WATTAGE='1/16W',
 TOLERANCE='1%',
 MATERIAL='EMPTY',
 VALUE='1K',
 PRIM_FILE='./archive_libs/logical/q_res/chips/chips.prt';

PART_NAME
 R3278 'Q_RES_0402LF-1K,1%,1/16W,CHIP,A':
 ROOM='PCIE REDRIVER1_BOM1';

SECTION_NUMBER 1
 '@S9S_MB_2U_LIB.S9S_MB_2U(SCH_1):PAGE136_I8@PURE_QUANTA.Q_RES(CHIPS)':
 C_PATH='@s9s_mb_2u_lib.s9s_mb_2u(sch_1):page136_i8@pure_quanta.q_res(chips)',
 P_PATH='@s9s_mb_2u_lib.s9s_mb_2u(sch_1):page166_i8@pure_quanta.q_res(chips)',
 PATH='I8',
 DRAWING='@S9S_MB_2U_LIB.S9S_MB_2U(SCH_1):PAGE136',
 PHYS_PAGE='166',
 XY='(-3075,-2575)',
 ROT='0',
 VER='2',
 PACK_TYPE='0402LF',
 CDS_LIB='pure_quanta',
 CDS_PART_NAME='Q_RES_0402LF-1K,1%,1/16W,CHIP,A',
 WATTAGE='1/16W',
 TOLERANCE='1%',
 MATERIAL='CHIP',
 ROOM='PCIE REDRIVER1_BOM1',
 VALUE='1K',
 PRIM_FILE='./archive_libs/logical/q_res/chips/chips.prt';

PART_NAME
 R3279 'Q_RES_0402LF-68K,1%,1/16W,EMPTA':;

SECTION_NUMBER 1
 '@S9S_MB_2U_LIB.S9S_MB_2U(SCH_1):PAGE136_I23@PURE_QUANTA.Q_RES(CHIPS)':
 C_PATH='@s9s_mb_2u_lib.s9s_mb_2u(sch_1):page136_i23@pure_quanta.q_res(chips)',
 P_PATH='@s9s_mb_2u_lib.s9s_mb_2u(sch_1):page166_i23@pure_quanta.q_res(chips)',
 PATH='I23',
 DRAWING='@S9S_MB_2U_LIB.S9S_MB_2U(SCH_1):PAGE136',
 PHYS_PAGE='166',
 XY='(-2075,-2550)',
 ROT='0',
 VER='2',
 PACK_TYPE='0402LF',
 CDS_LIB='pure_quanta',
 CDS_PART_NAME='Q_RES_0402LF-68K,1%,1/16W,EMPTA',
 WATTAGE='1/16W',
 TOLERANCE='1%',
 MATERIAL='EMPTY',
 VALUE='68K',
 PRIM_FILE='./archive_libs/logical/q_res/chips/chips.prt';

PART_NAME
 R3280 'Q_RES_0402LF-1K,1%,1/16W,EMPTYA':;

SECTION_NUMBER 1
 '@S9S_MB_2U_LIB.S9S_MB_2U(SCH_1):PAGE136_I32@PURE_QUANTA.Q_RES(CHIPS)':
 C_PATH='@s9s_mb_2u_lib.s9s_mb_2u(sch_1):page136_i32@pure_quanta.q_res(chips)',
 P_PATH='@s9s_mb_2u_lib.s9s_mb_2u(sch_1):page166_i32@pure_quanta.q_res(chips)',
 PATH='I32',
 DRAWING='@S9S_MB_2U_LIB.S9S_MB_2U(SCH_1):PAGE136',
 PHYS_PAGE='166',
 XY='(-1700,-2025)',
 ROT='0',
 VER='2',
 PACK_TYPE='0402LF',
 CDS_LIB='pure_quanta',
 CDS_PART_NAME='Q_RES_0402LF-1K,1%,1/16W,EMPTYA',
 WATTAGE='1/16W',
 TOLERANCE='1%',
 MATERIAL='EMPTY',
 VALUE='1K',
 PRIM_FILE='./archive_libs/logical/q_res/chips/chips.prt';

PART_NAME
 R3281 'Q_RES_0402LF-1K,1%,1/16W,EMPTYA':;

SECTION_NUMBER 1
 '@S9S_MB_2U_LIB.S9S_MB_2U(SCH_1):PAGE136_I25@PURE_QUANTA.Q_RES(CHIPS)':
 C_PATH='@s9s_mb_2u_lib.s9s_mb_2u(sch_1):page136_i25@pure_quanta.q_res(chips)',
 P_PATH='@s9s_mb_2u_lib.s9s_mb_2u(sch_1):page166_i25@pure_quanta.q_res(chips)',
 PATH='I25',
 DRAWING='@S9S_MB_2U_LIB.S9S_MB_2U(SCH_1):PAGE136',
 PHYS_PAGE='166',
 XY='(-1700,-2550)',
 ROT='0',
 VER='2',
 PACK_TYPE='0402LF',
 CDS_LIB='pure_quanta',
 CDS_PART_NAME='Q_RES_0402LF-1K,1%,1/16W,EMPTYA',
 WATTAGE='1/16W',
 TOLERANCE='1%',
 MATERIAL='EMPTY',
 VALUE='1K',
 PRIM_FILE='./archive_libs/logical/q_res/chips/chips.prt';

PART_NAME
 R3282 'Q_RES_0402LF-68K,1%,1/16W,EMPTA':;

SECTION_NUMBER 1
 '@S9S_MB_2U_LIB.S9S_MB_2U(SCH_1):PAGE136_I27@PURE_QUANTA.Q_RES(CHIPS)':
 C_PATH='@s9s_mb_2u_lib.s9s_mb_2u(sch_1):page136_i27@pure_quanta.q_res(chips)',
 P_PATH='@s9s_mb_2u_lib.s9s_mb_2u(sch_1):page166_i27@pure_quanta.q_res(chips)',
 PATH='I27',
 DRAWING='@S9S_MB_2U_LIB.S9S_MB_2U(SCH_1):PAGE136',
 PHYS_PAGE='166',
 XY='(-1225,-2575)',
 ROT='0',
 VER='2',
 PACK_TYPE='0402LF',
 CDS_LIB='pure_quanta',
 CDS_PART_NAME='Q_RES_0402LF-68K,1%,1/16W,EMPTA',
 WATTAGE='1/16W',
 TOLERANCE='1%',
 MATERIAL='EMPTY',
 VALUE='68K',
 PRIM_FILE='./archive_libs/logical/q_res/chips/chips.prt';

PART_NAME
 R3283 'Q_RES_0402LF-1K,1%,1/16W,EMPTYA':;

SECTION_NUMBER 1
 '@S9S_MB_2U_LIB.S9S_MB_2U(SCH_1):PAGE136_I57@PURE_QUANTA.Q_RES(CHIPS)':
 C_PATH='@s9s_mb_2u_lib.s9s_mb_2u(sch_1):page136_i57@pure_quanta.q_res(chips)',
 P_PATH='@s9s_mb_2u_lib.s9s_mb_2u(sch_1):page166_i57@pure_quanta.q_res(chips)',
 PATH='I57',
 DRAWING='@S9S_MB_2U_LIB.S9S_MB_2U(SCH_1):PAGE136',
 PHYS_PAGE='166',
 XY='(-825,-2025)',
 ROT='0',
 VER='2',
 PACK_TYPE='0402LF',
 CDS_LIB='pure_quanta',
 CDS_PART_NAME='Q_RES_0402LF-1K,1%,1/16W,EMPTYA',
 WATTAGE='1/16W',
 TOLERANCE='1%',
 MATERIAL='EMPTY',
 VALUE='1K',
 PRIM_FILE='./archive_libs/logical/q_res/chips/chips.prt';

PART_NAME
 R3284 'Q_RES_0402LF-1K,1%,1/16W,CHIP,A':
 ROOM='PCIE REDRIVER1_BOM1';

SECTION_NUMBER 1
 '@S9S_MB_2U_LIB.S9S_MB_2U(SCH_1):PAGE136_I56@PURE_QUANTA.Q_RES(CHIPS)':
 C_PATH='@s9s_mb_2u_lib.s9s_mb_2u(sch_1):page136_i56@pure_quanta.q_res(chips)',
 P_PATH='@s9s_mb_2u_lib.s9s_mb_2u(sch_1):page166_i56@pure_quanta.q_res(chips)',
 PATH='I56',
 DRAWING='@S9S_MB_2U_LIB.S9S_MB_2U(SCH_1):PAGE136',
 PHYS_PAGE='166',
 XY='(-825,-2600)',
 ROT='0',
 VER='2',
 PACK_TYPE='0402LF',
 CDS_LIB='pure_quanta',
 CDS_PART_NAME='Q_RES_0402LF-1K,1%,1/16W,CHIP,A',
 WATTAGE='1/16W',
 TOLERANCE='1%',
 MATERIAL='CHIP',
 ROOM='PCIE REDRIVER1_BOM1',
 VALUE='1K',
 PRIM_FILE='./archive_libs/logical/q_res/chips/chips.prt';

PART_NAME
 R3285 'Q_RES_0402LF-68K,1%,1/16W,EMPTA':;

SECTION_NUMBER 1
 '@S9S_MB_2U_LIB.S9S_MB_2U(SCH_1):PAGE136_I61@PURE_QUANTA.Q_RES(CHIPS)':
 C_PATH='@s9s_mb_2u_lib.s9s_mb_2u(sch_1):page136_i61@pure_quanta.q_res(chips)',
 P_PATH='@s9s_mb_2u_lib.s9s_mb_2u(sch_1):page166_i61@pure_quanta.q_res(chips)',
 PATH='I61',
 DRAWING='@S9S_MB_2U_LIB.S9S_MB_2U(SCH_1):PAGE136',
 PHYS_PAGE='166',
 XY='(-50,-800)',
 ROT='0',
 VER='2',
 PACK_TYPE='0402LF',
 CDS_LIB='pure_quanta',
 CDS_PART_NAME='Q_RES_0402LF-68K,1%,1/16W,EMPTA',
 WATTAGE='1/16W',
 TOLERANCE='1%',
 MATERIAL='EMPTY',
 VALUE='68K',
 PRIM_FILE='./archive_libs/logical/q_res/chips/chips.prt';

PART_NAME
 R3286 'Q_RES_0402LF-1K,1%,1/16W,EMPTYA':;

SECTION_NUMBER 1
 '@S9S_MB_2U_LIB.S9S_MB_2U(SCH_1):PAGE136_I64@PURE_QUANTA.Q_RES(CHIPS)':
 C_PATH='@s9s_mb_2u_lib.s9s_mb_2u(sch_1):page136_i64@pure_quanta.q_res(chips)',
 P_PATH='@s9s_mb_2u_lib.s9s_mb_2u(sch_1):page166_i64@pure_quanta.q_res(chips)',
 PATH='I64',
 DRAWING='@S9S_MB_2U_LIB.S9S_MB_2U(SCH_1):PAGE136',
 PHYS_PAGE='166',
 XY='(325,-275)',
 ROT='0',
 VER='2',
 PACK_TYPE='0402LF',
 CDS_LIB='pure_quanta',
 CDS_PART_NAME='Q_RES_0402LF-1K,1%,1/16W,EMPTYA',
 WATTAGE='1/16W',
 TOLERANCE='1%',
 MATERIAL='EMPTY',
 VALUE='1K',
 PRIM_FILE='./archive_libs/logical/q_res/chips/chips.prt';

PART_NAME
 R3287 'Q_RES_0402LF-1K,1%,1/16W,EMPTYA':;

SECTION_NUMBER 1
 '@S9S_MB_2U_LIB.S9S_MB_2U(SCH_1):PAGE136_I63@PURE_QUANTA.Q_RES(CHIPS)':
 C_PATH='@s9s_mb_2u_lib.s9s_mb_2u(sch_1):page136_i63@pure_quanta.q_res(chips)',
 P_PATH='@s9s_mb_2u_lib.s9s_mb_2u(sch_1):page166_i63@pure_quanta.q_res(chips)',
 PATH='I63',
 DRAWING='@S9S_MB_2U_LIB.S9S_MB_2U(SCH_1):PAGE136',
 PHYS_PAGE='166',
 XY='(325,-800)',
 ROT='0',
 VER='2',
 PACK_TYPE='0402LF',
 CDS_LIB='pure_quanta',
 CDS_PART_NAME='Q_RES_0402LF-1K,1%,1/16W,EMPTYA',
 WATTAGE='1/16W',
 TOLERANCE='1%',
 MATERIAL='EMPTY',
 VALUE='1K',
 PRIM_FILE='./archive_libs/logical/q_res/chips/chips.prt';

PART_NAME
 R3288 'Q_RES_0402LF-68K,1%,1/16W,EMPTA':;

SECTION_NUMBER 1
 '@S9S_MB_2U_LIB.S9S_MB_2U(SCH_1):PAGE136_I66@PURE_QUANTA.Q_RES(CHIPS)':
 C_PATH='@s9s_mb_2u_lib.s9s_mb_2u(sch_1):page136_i66@pure_quanta.q_res(chips)',
 P_PATH='@s9s_mb_2u_lib.s9s_mb_2u(sch_1):page166_i66@pure_quanta.q_res(chips)',
 PATH='I66',
 DRAWING='@S9S_MB_2U_LIB.S9S_MB_2U(SCH_1):PAGE136',
 PHYS_PAGE='166',
 XY='(800,-825)',
 ROT='0',
 VER='2',
 PACK_TYPE='0402LF',
 CDS_LIB='pure_quanta',
 CDS_PART_NAME='Q_RES_0402LF-68K,1%,1/16W,EMPTA',
 WATTAGE='1/16W',
 TOLERANCE='1%',
 MATERIAL='EMPTY',
 VALUE='68K',
 PRIM_FILE='./archive_libs/logical/q_res/chips/chips.prt';

PART_NAME
 R3289 'Q_RES_0402LF-1K,1%,1/16W,EMPTYA':;

SECTION_NUMBER 1
 '@S9S_MB_2U_LIB.S9S_MB_2U(SCH_1):PAGE136_I69@PURE_QUANTA.Q_RES(CHIPS)':
 C_PATH='@s9s_mb_2u_lib.s9s_mb_2u(sch_1):page136_i69@pure_quanta.q_res(chips)',
 P_PATH='@s9s_mb_2u_lib.s9s_mb_2u(sch_1):page166_i69@pure_quanta.q_res(chips)',
 PATH='I69',
 DRAWING='@S9S_MB_2U_LIB.S9S_MB_2U(SCH_1):PAGE136',
 PHYS_PAGE='166',
 XY='(1200,-275)',
 ROT='0',
 VER='2',
 PACK_TYPE='0402LF',
 CDS_LIB='pure_quanta',
 CDS_PART_NAME='Q_RES_0402LF-1K,1%,1/16W,EMPTYA',
 WATTAGE='1/16W',
 TOLERANCE='1%',
 MATERIAL='EMPTY',
 VALUE='1K',
 PRIM_FILE='./archive_libs/logical/q_res/chips/chips.prt';

PART_NAME
 R3290 'Q_RES_0402LF-1K,1%,1/16W,EMPTYA':;

SECTION_NUMBER 1
 '@S9S_MB_2U_LIB.S9S_MB_2U(SCH_1):PAGE136_I68@PURE_QUANTA.Q_RES(CHIPS)':
 C_PATH='@s9s_mb_2u_lib.s9s_mb_2u(sch_1):page136_i68@pure_quanta.q_res(chips)',
 P_PATH='@s9s_mb_2u_lib.s9s_mb_2u(sch_1):page166_i68@pure_quanta.q_res(chips)',
 PATH='I68',
 DRAWING='@S9S_MB_2U_LIB.S9S_MB_2U(SCH_1):PAGE136',
 PHYS_PAGE='166',
 XY='(1200,-850)',
 ROT='0',
 VER='2',
 PACK_TYPE='0402LF',
 CDS_LIB='pure_quanta',
 CDS_PART_NAME='Q_RES_0402LF-1K,1%,1/16W,EMPTYA',
 WATTAGE='1/16W',
 TOLERANCE='1%',
 MATERIAL='EMPTY',
 VALUE='1K',
 PRIM_FILE='./archive_libs/logical/q_res/chips/chips.prt';

PART_NAME
 R3291 'Q_RES_0402LF-4.7K,1%,1/16W,EMPA':;

SECTION_NUMBER 1
 '@S9S_MB_2U_LIB.S9S_MB_2U(SCH_1):PAGE136_I82@PURE_QUANTA.Q_RES(CHIPS)':
 C_PATH='@s9s_mb_2u_lib.s9s_mb_2u(sch_1):page136_i82@pure_quanta.q_res(chips)',
 P_PATH='@s9s_mb_2u_lib.s9s_mb_2u(sch_1):page166_i82@pure_quanta.q_res(chips)',
 PATH='I82',
 DRAWING='@S9S_MB_2U_LIB.S9S_MB_2U(SCH_1):PAGE136',
 PHYS_PAGE='166',
 XY='(1850,1375)',
 ROT='0',
 VER='2',
 PACK_TYPE='0402LF',
 CDS_LIB='pure_quanta',
 CDS_PART_NAME='Q_RES_0402LF-4.7K,1%,1/16W,EMPA',
 WATTAGE='1/16W',
 TOLERANCE='1%',
 MATERIAL='EMPTY',
 VALUE='4.7K',
 PRIM_FILE='./archive_libs/logical/q_res/chips/chips.prt';

PART_NAME
 R3292 'Q_RES_0402LF-4.7K,1%,1/16W,CHIA':
 ROOM='PCIE REDRIVER1_BOM1';

SECTION_NUMBER 1
 '@S9S_MB_2U_LIB.S9S_MB_2U(SCH_1):PAGE136_I85@PURE_QUANTA.Q_RES(CHIPS)':
 C_PATH='@s9s_mb_2u_lib.s9s_mb_2u(sch_1):page136_i85@pure_quanta.q_res(chips)',
 P_PATH='@s9s_mb_2u_lib.s9s_mb_2u(sch_1):page166_i85@pure_quanta.q_res(chips)',
 PATH='I85',
 DRAWING='@S9S_MB_2U_LIB.S9S_MB_2U(SCH_1):PAGE136',
 PHYS_PAGE='166',
 XY='(3100,900)',
 ROT='0',
 VER='2',
 PACK_TYPE='0402LF',
 CDS_LIB='pure_quanta',
 CDS_PART_NAME='Q_RES_0402LF-4.7K,1%,1/16W,CHIA',
 WATTAGE='1/16W',
 TOLERANCE='1%',
 MATERIAL='CHIP',
 ROOM='PCIE REDRIVER1_BOM1',
 VALUE='4.7K',
 PRIM_FILE='./archive_libs/logical/q_res/chips/chips.prt';

PART_NAME
 R3293 'Q_RES_0402LF-4.7K,1%,1/16W,EMPA':;

SECTION_NUMBER 1
 '@S9S_MB_2U_LIB.S9S_MB_2U(SCH_1):PAGE136_I88@PURE_QUANTA.Q_RES(CHIPS)':
 C_PATH='@s9s_mb_2u_lib.s9s_mb_2u(sch_1):page136_i88@pure_quanta.q_res(chips)',
 P_PATH='@s9s_mb_2u_lib.s9s_mb_2u(sch_1):page166_i88@pure_quanta.q_res(chips)',
 PATH='I88',
 DRAWING='@S9S_MB_2U_LIB.S9S_MB_2U(SCH_1):PAGE136',
 PHYS_PAGE='166',
 XY='(3100,1850)',
 ROT='0',
 VER='2',
 PACK_TYPE='0402LF',
 CDS_LIB='pure_quanta',
 CDS_PART_NAME='Q_RES_0402LF-4.7K,1%,1/16W,EMPA',
 WATTAGE='1/16W',
 TOLERANCE='1%',
 MATERIAL='EMPTY',
 VALUE='4.7K',
 PRIM_FILE='./archive_libs/logical/q_res/chips/chips.prt';

PART_NAME
 R3294 'Q_RES_0402LF-0,5%,1/16W,CHIP,CA':;

SECTION_NUMBER 1
 '@S9S_MB_2U_LIB.S9S_MB_2U(SCH_1):PAGE182_I320@PURE_QUANTA.Q_RES(CHIPS)':
 C_PATH='@s9s_mb_2u_lib.s9s_mb_2u(sch_1):page182_i320@pure_quanta.q_res(chips)',
 P_PATH='@s9s_mb_2u_lib.s9s_mb_2u(sch_1):page190_i320@pure_quanta.q_res(chips)',
 PATH='I320',
 DRAWING='@S9S_MB_2U_LIB.S9S_MB_2U(SCH_1):PAGE182',
 PHYS_PAGE='190',
 XY='(7075,1225)',
 ROT='0',
 VER='1',
 PACK_TYPE='0402LF',
 CDS_LIB='pure_quanta',
 CDS_PART_NAME='Q_RES_0402LF-0,5%,1/16W,CHIP,CA',
 WATTAGE='1/16W',
 TOLERANCE='5%',
 MATERIAL='CHIP',
 VALUE='0',
 PRIM_FILE='./archive_libs/logical/q_res/chips/chips.prt';

PART_NAME
 R3295 'Q_RES_0402LF-4.7K,1%,1/16W,CHIA':;

SECTION_NUMBER 1
 '@S9S_MB_2U_LIB.S9S_MB_2U(SCH_1):PAGE182_I317@PURE_QUANTA.Q_RES(CHIPS)':
 C_PATH='@s9s_mb_2u_lib.s9s_mb_2u(sch_1):page182_i317@pure_quanta.q_res(chips)',
 P_PATH='@s9s_mb_2u_lib.s9s_mb_2u(sch_1):page190_i317@pure_quanta.q_res(chips)',
 PATH='I317',
 DRAWING='@S9S_MB_2U_LIB.S9S_MB_2U(SCH_1):PAGE182',
 PHYS_PAGE='190',
 XY='(7650,1525)',
 ROT='0',
 VER='2',
 PACK_TYPE='0402LF',
 CDS_LIB='pure_quanta',
 CDS_PART_NAME='Q_RES_0402LF-4.7K,1%,1/16W,CHIA',
 WATTAGE='1/16W',
 TOLERANCE='1%',
 MATERIAL='CHIP',
 VALUE='4.7K',
 PRIM_FILE='./archive_libs/logical/q_res/chips/chips.prt';

PART_NAME
 R3296 'Q_RES_0402LF-4.7K,1%,1/16W,CHIA':;

SECTION_NUMBER 1
 '@S9S_MB_2U_LIB.S9S_MB_2U(SCH_1):PAGE182_I324@PURE_QUANTA.Q_RES(CHIPS)':
 C_PATH='@s9s_mb_2u_lib.s9s_mb_2u(sch_1):page182_i324@pure_quanta.q_res(chips)',
 P_PATH='@s9s_mb_2u_lib.s9s_mb_2u(sch_1):page190_i324@pure_quanta.q_res(chips)',
 PATH='I324',
 DRAWING='@S9S_MB_2U_LIB.S9S_MB_2U(SCH_1):PAGE182',
 PHYS_PAGE='190',
 XY='(8625,300)',
 ROT='0',
 VER='2',
 PACK_TYPE='0402LF',
 CDS_LIB='pure_quanta',
 CDS_PART_NAME='Q_RES_0402LF-4.7K,1%,1/16W,CHIA',
 WATTAGE='1/16W',
 TOLERANCE='1%',
 MATERIAL='CHIP',
 VALUE='4.7K',
 PRIM_FILE='./archive_libs/logical/q_res/chips/chips.prt';

PART_NAME
 R3297 'Q_RES_0402LF-10K,1%,1/16W,CHIPA':;

SECTION_NUMBER 1
 '@S9S_MB_2U_LIB.S9S_MB_2U(SCH_1):PAGE182_I303@PURE_QUANTA.Q_RES(CHIPS)':
 C_PATH='@s9s_mb_2u_lib.s9s_mb_2u(sch_1):page182_i303@pure_quanta.q_res(chips)',
 P_PATH='@s9s_mb_2u_lib.s9s_mb_2u(sch_1):page190_i303@pure_quanta.q_res(chips)',
 PATH='I303',
 DRAWING='@S9S_MB_2U_LIB.S9S_MB_2U(SCH_1):PAGE182',
 PHYS_PAGE='190',
 XY='(10300,925)',
 ROT='2',
 VER='2',
 PACK_TYPE='0402LF',
 CDS_LIB='pure_quanta',
 CDS_PART_NAME='Q_RES_0402LF-10K,1%,1/16W,CHIPA',
 WATTAGE='1/16W',
 TOLERANCE='1%',
 MATERIAL='CHIP',
 VALUE='10K',
 PRIM_FILE='./archive_libs/logical/q_res/chips/chips.prt';

PART_NAME
 R3298 'Q_RES_0402LF-10K,1%,1/16W,CHIPA':;

SECTION_NUMBER 1
 '@S9S_MB_2U_LIB.S9S_MB_2U(SCH_1):PAGE182_I306@PURE_QUANTA.Q_RES(CHIPS)':
 C_PATH='@s9s_mb_2u_lib.s9s_mb_2u(sch_1):page182_i306@pure_quanta.q_res(chips)',
 P_PATH='@s9s_mb_2u_lib.s9s_mb_2u(sch_1):page190_i306@pure_quanta.q_res(chips)',
 PATH='I306',
 DRAWING='@S9S_MB_2U_LIB.S9S_MB_2U(SCH_1):PAGE182',
 PHYS_PAGE='190',
 XY='(10725,500)',
 ROT='2',
 VER='2',
 PACK_TYPE='0402LF',
 CDS_LIB='pure_quanta',
 CDS_PART_NAME='Q_RES_0402LF-10K,1%,1/16W,CHIPA',
 WATTAGE='1/16W',
 TOLERANCE='1%',
 MATERIAL='CHIP',
 VALUE='10K',
 PRIM_FILE='./archive_libs/logical/q_res/chips/chips.prt';

PART_NAME
 R3301 'Q_RES_0402LF-33.2,1%,1/16W,CHIA':;

SECTION_NUMBER 1
 '@S9S_MB_2U_LIB.S9S_MB_2U(SCH_1):PAGE182_I299@PURE_QUANTA.Q_RES(CHIPS)':
 C_PATH='@s9s_mb_2u_lib.s9s_mb_2u(sch_1):page182_i299@pure_quanta.q_res(chips)',
 P_PATH='@s9s_mb_2u_lib.s9s_mb_2u(sch_1):page190_i299@pure_quanta.q_res(chips)',
 PATH='I299',
 DRAWING='@S9S_MB_2U_LIB.S9S_MB_2U(SCH_1):PAGE182',
 PHYS_PAGE='190',
 XY='(6975,3300)',
 ROT='0',
 VER='1',
 PACK_TYPE='0402LF',
 LOCATION='R3301',
 CDS_LIB='pure_quanta',
 CDS_PART_NAME='Q_RES_0402LF-33.2,1%,1/16W,CHIA',
 WATTAGE='1/16W',
 TOLERANCE='1%',
 MATERIAL='CHIP',
 VALUE='33.2',
 PRIM_FILE='./archive_libs/logical/q_res/chips/chips.prt';

PART_NAME
 R3302 'Q_RES_0402LF-0,5%,1/16W,EMPTY,A':;

SECTION_NUMBER 1
 '@S9S_MB_2U_LIB.S9S_MB_2U(SCH_1):PAGE227_I48@PURE_QUANTA.Q_RES(CHIPS)':
 C_PATH='@s9s_mb_2u_lib.s9s_mb_2u(sch_1):page227_i48@pure_quanta.q_res(chips)',
 P_PATH='@s9s_mb_2u_lib.s9s_mb_2u(sch_1):page240_i48@pure_quanta.q_res(chips)',
 PATH='I48',
 DRAWING='@S9S_MB_2U_LIB.S9S_MB_2U(SCH_1):PAGE227',
 PHYS_PAGE='240',
 XY='(-7875,-2225)',
 ROT='0',
 VER='1',
 PACK_TYPE='0402LF',
 CDS_LIB='pure_quanta',
 CDS_PART_NAME='Q_RES_0402LF-0,5%,1/16W,EMPTY,A',
 WATTAGE='1/16W',
 TOLERANCE='5%',
 MATERIAL='EMPTY',
 VALUE='0',
 PRIM_FILE='./archive_libs/logical/q_res/chips/chips.prt';

PART_NAME
 R3303 'Q_RES_0402LF-0,5%,1/16W,CHIP,CA':;

SECTION_NUMBER 1
 '@S9S_MB_2U_LIB.S9S_MB_2U(SCH_1):PAGE170_I44@PURE_QUANTA.Q_RES(CHIPS)':
 C_PATH='@s9s_mb_2u_lib.s9s_mb_2u(sch_1):page170_i44@pure_quanta.q_res(chips)',
 P_PATH='@s9s_mb_2u_lib.s9s_mb_2u(sch_1):page165_i44@pure_quanta.q_res(chips)',
 PATH='I44',
 DRAWING='@S9S_MB_2U_LIB.S9S_MB_2U(SCH_1):PAGE170',
 PHYS_PAGE='165',
 XY='(825,2400)',
 ROT='0',
 VER='1',
 PACK_TYPE='0402LF',
 CDS_LIB='pure_quanta',
 CDS_PART_NAME='Q_RES_0402LF-0,5%,1/16W,CHIP,CA',
 WATTAGE='1/16W',
 TOLERANCE='5%',
 MATERIAL='CHIP',
 VALUE='0',
 PRIM_FILE='./archive_libs/logical/q_res/chips/chips.prt';

PART_NAME
 R3304 'Q_RES_0402LF-0,5%,1/16W,CHIP,CA':;

SECTION_NUMBER 1
 '@S9S_MB_2U_LIB.S9S_MB_2U(SCH_1):PAGE170_I45@PURE_QUANTA.Q_RES(CHIPS)':
 C_PATH='@s9s_mb_2u_lib.s9s_mb_2u(sch_1):page170_i45@pure_quanta.q_res(chips)',
 P_PATH='@s9s_mb_2u_lib.s9s_mb_2u(sch_1):page165_i45@pure_quanta.q_res(chips)',
 PATH='I45',
 DRAWING='@S9S_MB_2U_LIB.S9S_MB_2U(SCH_1):PAGE170',
 PHYS_PAGE='165',
 XY='(625,1550)',
 ROT='0',
 VER='1',
 PACK_TYPE='0402LF',
 CDS_LIB='pure_quanta',
 CDS_PART_NAME='Q_RES_0402LF-0,5%,1/16W,CHIP,CA',
 WATTAGE='1/16W',
 TOLERANCE='5%',
 MATERIAL='CHIP',
 VALUE='0',
 PRIM_FILE='./archive_libs/logical/q_res/chips/chips.prt';

PART_NAME
 R3305 'Q_RES_0402LF-0,5%,1/16W,CHIP,CA':;

SECTION_NUMBER 1
 '@S9S_MB_2U_LIB.S9S_MB_2U(SCH_1):PAGE170_I50@PURE_QUANTA.Q_RES(CHIPS)':
 C_PATH='@s9s_mb_2u_lib.s9s_mb_2u(sch_1):page170_i50@pure_quanta.q_res(chips)',
 P_PATH='@s9s_mb_2u_lib.s9s_mb_2u(sch_1):page165_i50@pure_quanta.q_res(chips)',
 PATH='I50',
 DRAWING='@S9S_MB_2U_LIB.S9S_MB_2U(SCH_1):PAGE170',
 PHYS_PAGE='165',
 XY='(625,1450)',
 ROT='0',
 VER='1',
 PACK_TYPE='0402LF',
 CDS_LIB='pure_quanta',
 CDS_PART_NAME='Q_RES_0402LF-0,5%,1/16W,CHIP,CA',
 WATTAGE='1/16W',
 TOLERANCE='5%',
 MATERIAL='CHIP',
 VALUE='0',
 PRIM_FILE='./archive_libs/logical/q_res/chips/chips.prt';

PART_NAME
 R3306 'Q_RES_0402LF-0,5%,1/16W,CHIP,CA':;

SECTION_NUMBER 1
 '@S9S_MB_2U_LIB.S9S_MB_2U(SCH_1):PAGE170_I47@PURE_QUANTA.Q_RES(CHIPS)':
 C_PATH='@s9s_mb_2u_lib.s9s_mb_2u(sch_1):page170_i47@pure_quanta.q_res(chips)',
 P_PATH='@s9s_mb_2u_lib.s9s_mb_2u(sch_1):page165_i47@pure_quanta.q_res(chips)',
 PATH='I47',
 DRAWING='@S9S_MB_2U_LIB.S9S_MB_2U(SCH_1):PAGE170',
 PHYS_PAGE='165',
 XY='(800,-575)',
 ROT='0',
 VER='1',
 PACK_TYPE='0402LF',
 CDS_LIB='pure_quanta',
 CDS_PART_NAME='Q_RES_0402LF-0,5%,1/16W,CHIP,CA',
 WATTAGE='1/16W',
 TOLERANCE='5%',
 MATERIAL='CHIP',
 VALUE='0',
 PRIM_FILE='./archive_libs/logical/q_res/chips/chips.prt';

PART_NAME
 R3307 'Q_RES_0402LF-0,5%,1/16W,CHIP,CA':;

SECTION_NUMBER 1
 '@S9S_MB_2U_LIB.S9S_MB_2U(SCH_1):PAGE170_I52@PURE_QUANTA.Q_RES(CHIPS)':
 C_PATH='@s9s_mb_2u_lib.s9s_mb_2u(sch_1):page170_i52@pure_quanta.q_res(chips)',
 P_PATH='@s9s_mb_2u_lib.s9s_mb_2u(sch_1):page165_i52@pure_quanta.q_res(chips)',
 PATH='I52',
 DRAWING='@S9S_MB_2U_LIB.S9S_MB_2U(SCH_1):PAGE170',
 PHYS_PAGE='165',
 XY='(800,-675)',
 ROT='0',
 VER='1',
 PACK_TYPE='0402LF',
 CDS_LIB='pure_quanta',
 CDS_PART_NAME='Q_RES_0402LF-0,5%,1/16W,CHIP,CA',
 WATTAGE='1/16W',
 TOLERANCE='5%',
 MATERIAL='CHIP',
 VALUE='0',
 PRIM_FILE='./archive_libs/logical/q_res/chips/chips.prt';

PART_NAME
 R3308 'Q_RES_0402LF-0,5%,1/16W,CHIP,CA':;

SECTION_NUMBER 1
 '@S9S_MB_2U_LIB.S9S_MB_2U(SCH_1):PAGE170_I46@PURE_QUANTA.Q_RES(CHIPS)':
 C_PATH='@s9s_mb_2u_lib.s9s_mb_2u(sch_1):page170_i46@pure_quanta.q_res(chips)',
 P_PATH='@s9s_mb_2u_lib.s9s_mb_2u(sch_1):page165_i46@pure_quanta.q_res(chips)',
 PATH='I46',
 DRAWING='@S9S_MB_2U_LIB.S9S_MB_2U(SCH_1):PAGE170',
 PHYS_PAGE='165',
 XY='(825,275)',
 ROT='0',
 VER='1',
 PACK_TYPE='0402LF',
 CDS_LIB='pure_quanta',
 CDS_PART_NAME='Q_RES_0402LF-0,5%,1/16W,CHIP,CA',
 WATTAGE='1/16W',
 TOLERANCE='5%',
 MATERIAL='CHIP',
 VALUE='0',
 PRIM_FILE='./archive_libs/logical/q_res/chips/chips.prt';

PART_NAME
 R3315 'Q_RES_0402LF-49.9,1%,1/16W,CHIA':;

SECTION_NUMBER 1
 '@S9S_MB_2U_LIB.S9S_MB_2U(SCH_1):PAGE140_I205@PURE_QUANTA.Q_RES(CHIPS)':
 C_PATH='@s9s_mb_2u_lib.s9s_mb_2u(sch_1):page140_i205@pure_quanta.q_res(chips)',
 P_PATH='@s9s_mb_2u_lib.s9s_mb_2u(sch_1):page151_i205@pure_quanta.q_res(chips)',
 PATH='I205',
 DRAWING='@S9S_MB_2U_LIB.S9S_MB_2U(SCH_1):PAGE140',
 PHYS_PAGE='151',
 XY='(2900,-525)',
 ROT='0',
 VER='1',
 PACK_TYPE='0402LF',
 LOCATION='R3315',
 CDS_LIB='pure_quanta',
 CDS_PART_NAME='Q_RES_0402LF-49.9,1%,1/16W,CHIA',
 WATTAGE='1/16W',
 TOLERANCE='1%',
 MATERIAL='CHIP',
 VALUE='49.9',
 PRIM_FILE='./archive_libs/logical/q_res/chips/chips.prt';

PART_NAME
 R3317 'Q_RES_0402LF-4.7K,5%,1/16W,EMPA':;

SECTION_NUMBER 1
 '@S9S_MB_2U_LIB.S9S_MB_2U(SCH_1):PAGE140_I190@PURE_QUANTA.Q_RES(CHIPS)':
 C_PATH='@s9s_mb_2u_lib.s9s_mb_2u(sch_1):page140_i190@pure_quanta.q_res(chips)',
 P_PATH='@s9s_mb_2u_lib.s9s_mb_2u(sch_1):page151_i190@pure_quanta.q_res(chips)',
 PATH='I190',
 DRAWING='@S9S_MB_2U_LIB.S9S_MB_2U(SCH_1):PAGE140',
 PHYS_PAGE='151',
 XY='(2650,-325)',
 ROT='0',
 VER='2',
 PACK_TYPE='0402LF',
 CDS_LIB='pure_quanta',
 CDS_PART_NAME='Q_RES_0402LF-4.7K,5%,1/16W,EMPA',
 WATTAGE='1/16W',
 TOLERANCE='5%',
 MATERIAL='EMPTY',
 VALUE='4.7K',
 PRIM_FILE='./archive_libs/logical/q_res/chips/chips.prt';

PART_NAME
 R3318 'Q_RES_0402LF-100K,1%,1/16W,EMPA':;

SECTION_NUMBER 1
 '@S9S_MB_2U_LIB.S9S_MB_2U(SCH_1):PAGE145_I171@PURE_QUANTA.Q_RES(CHIPS)':
 C_PATH='@s9s_mb_2u_lib.s9s_mb_2u(sch_1):page145_i171@pure_quanta.q_res(chips)',
 P_PATH='@s9s_mb_2u_lib.s9s_mb_2u(sch_1):page148_i171@pure_quanta.q_res(chips)',
 PATH='I171',
 DRAWING='@S9S_MB_2U_LIB.S9S_MB_2U(SCH_1):PAGE145',
 PHYS_PAGE='148',
 XY='(-175,3400)',
 ROT='0',
 VER='2',
 PACK_TYPE='0402LF',
 CDS_LIB='pure_quanta',
 CDS_PART_NAME='Q_RES_0402LF-100K,1%,1/16W,EMPA',
 WATTAGE='1/16W',
 TOLERANCE='1%',
 MATERIAL='EMPTY',
 VALUE='100K',
 PRIM_FILE='./archive_libs/logical/q_res/chips/chips.prt';

PART_NAME
 R3320 'Q_RES_0402LF-4.7K,5%,1/16W,CHIA':;

SECTION_NUMBER 1
 '@S9S_MB_2U_LIB.S9S_MB_2U(SCH_1):PAGE145_I162@PURE_QUANTA.Q_RES(CHIPS)':
 C_PATH='@s9s_mb_2u_lib.s9s_mb_2u(sch_1):page145_i162@pure_quanta.q_res(chips)',
 P_PATH='@s9s_mb_2u_lib.s9s_mb_2u(sch_1):page148_i162@pure_quanta.q_res(chips)',
 PATH='I162',
 DRAWING='@S9S_MB_2U_LIB.S9S_MB_2U(SCH_1):PAGE145',
 PHYS_PAGE='148',
 XY='(1075,3700)',
 ROT='0',
 VER='2',
 PACK_TYPE='0402LF',
 CDS_LIB='pure_quanta',
 CDS_PART_NAME='Q_RES_0402LF-4.7K,5%,1/16W,CHIA',
 WATTAGE='1/16W',
 TOLERANCE='5%',
 MATERIAL='CHIP',
 VALUE='4.7K',
 PRIM_FILE='./archive_libs/logical/q_res/chips/chips.prt';

PART_NAME
 R3321 'Q_RES_0402LF-4.7K,5%,1/16W,CHIA':;

SECTION_NUMBER 1
 '@S9S_MB_2U_LIB.S9S_MB_2U(SCH_1):PAGE145_I158@PURE_QUANTA.Q_RES(CHIPS)':
 C_PATH='@s9s_mb_2u_lib.s9s_mb_2u(sch_1):page145_i158@pure_quanta.q_res(chips)',
 P_PATH='@s9s_mb_2u_lib.s9s_mb_2u(sch_1):page148_i158@pure_quanta.q_res(chips)',
 PATH='I158',
 DRAWING='@S9S_MB_2U_LIB.S9S_MB_2U(SCH_1):PAGE145',
 PHYS_PAGE='148',
 XY='(2000,3950)',
 ROT='0',
 VER='2',
 PACK_TYPE='0402LF',
 CDS_LIB='pure_quanta',
 CDS_PART_NAME='Q_RES_0402LF-4.7K,5%,1/16W,CHIA',
 WATTAGE='1/16W',
 TOLERANCE='5%',
 MATERIAL='CHIP',
 VALUE='4.7K',
 PRIM_FILE='./archive_libs/logical/q_res/chips/chips.prt';

PART_NAME
 R3322 'Q_RES_0402LF-4.7K,1%,1/16W,CHIA':;

SECTION_NUMBER 1
 '@S9S_MB_2U_LIB.S9S_MB_2U(SCH_1):PAGE201_I157@PURE_QUANTA.Q_RES(CHIPS)':
 C_PATH='@s9s_mb_2u_lib.s9s_mb_2u(sch_1):page201_i157@pure_quanta.q_res(chips)',
 P_PATH='@s9s_mb_2u_lib.s9s_mb_2u(sch_1):page212_i157@pure_quanta.q_res(chips)',
 PATH='I157',
 DRAWING='@S9S_MB_2U_LIB.S9S_MB_2U(SCH_1):PAGE201',
 PHYS_PAGE='212',
 XY='(-3425,1600)',
 ROT='0',
 VER='2',
 PACK_TYPE='0402LF',
 CDS_LIB='pure_quanta',
 CDS_PART_NAME='Q_RES_0402LF-4.7K,1%,1/16W,CHIA',
 WATTAGE='1/16W',
 TOLERANCE='1%',
 MATERIAL='CHIP',
 VALUE='4.7K',
 PRIM_FILE='./archive_libs/logical/q_res/chips/chips.prt';

PART_NAME
 R3324 'Q_RES_0402LF-33.2,1%,1/16W,CHIA':;

SECTION_NUMBER 1
 '@S9S_MB_2U_LIB.S9S_MB_2U(SCH_1):PAGE314_I108@PURE_QUANTA.Q_RES(CHIPS)':
 C_PATH='@s9s_mb_2u_lib.s9s_mb_2u(sch_1):page314_i108@pure_quanta.q_res(chips)',
 P_PATH='@s9s_mb_2u_lib.s9s_mb_2u(sch_1):page213_i108@pure_quanta.q_res(chips)',
 PATH='I108',
 DRAWING='@S9S_MB_2U_LIB.S9S_MB_2U(SCH_1):PAGE314',
 PHYS_PAGE='213',
 XY='(2725,-1050)',
 ROT='0',
 VER='1',
 PACK_TYPE='0402LF',
 LOCATION='R3324',
 CDS_LIB='pure_quanta',
 CDS_PART_NAME='Q_RES_0402LF-33.2,1%,1/16W,CHIA',
 WATTAGE='1/16W',
 TOLERANCE='1%',
 MATERIAL='CHIP',
 VALUE='33.2',
 PRIM_FILE='./archive_libs/logical/q_res/chips/chips.prt';

PART_NAME
 R3325 'Q_RES_0402LF-10K,1%,1/16W,CHIPA':;

SECTION_NUMBER 1
 '@S9S_MB_2U_LIB.S9S_MB_2U(SCH_1):PAGE186_I92@PURE_QUANTA.Q_RES(CHIPS)':
 C_PATH='@s9s_mb_2u_lib.s9s_mb_2u(sch_1):page186_i92@pure_quanta.q_res(chips)',
 P_PATH='@s9s_mb_2u_lib.s9s_mb_2u(sch_1):page198_i92@pure_quanta.q_res(chips)',
 PATH='I92',
 DRAWING='@S9S_MB_2U_LIB.S9S_MB_2U(SCH_1):PAGE186',
 PHYS_PAGE='198',
 XY='(-3475,775)',
 ROT='0',
 VER='2',
 PACK_TYPE='0402LF',
 CDS_LIB='pure_quanta',
 CDS_PART_NAME='Q_RES_0402LF-10K,1%,1/16W,CHIPA',
 WATTAGE='1/16W',
 TOLERANCE='1%',
 MATERIAL='CHIP',
 VALUE='10K',
 PRIM_FILE='./archive_libs/logical/q_res/chips/chips.prt';

PART_NAME
 R3326 'Q_RES_0402LF-0,5%,1/16W,CHIP,CA':;

SECTION_NUMBER 1
 '@S9S_MB_2U_LIB.S9S_MB_2U(SCH_1):PAGE201_I84@PURE_QUANTA.Q_RES(CHIPS)':
 C_PATH='@s9s_mb_2u_lib.s9s_mb_2u(sch_1):page201_i84@pure_quanta.q_res(chips)',
 P_PATH='@s9s_mb_2u_lib.s9s_mb_2u(sch_1):page212_i84@pure_quanta.q_res(chips)',
 PATH='I84',
 DRAWING='@S9S_MB_2U_LIB.S9S_MB_2U(SCH_1):PAGE201',
 PHYS_PAGE='212',
 XY='(-3725,1300)',
 ROT='0',
 VER='1',
 PACK_TYPE='0402LF',
 CDS_LIB='pure_quanta',
 CDS_PART_NAME='Q_RES_0402LF-0,5%,1/16W,CHIP,CA',
 WATTAGE='1/16W',
 TOLERANCE='5%',
 MATERIAL='CHIP',
 VALUE='0',
 PRIM_FILE='./archive_libs/logical/q_res/chips/chips.prt';

PART_NAME
 R3327 'Q_RES_0402LF-0,5%,1/16W,CHIP,CA':;

SECTION_NUMBER 1
 '@S9S_MB_2U_LIB.S9S_MB_2U(SCH_1):PAGE201_I85@PURE_QUANTA.Q_RES(CHIPS)':
 C_PATH='@s9s_mb_2u_lib.s9s_mb_2u(sch_1):page201_i85@pure_quanta.q_res(chips)',
 P_PATH='@s9s_mb_2u_lib.s9s_mb_2u(sch_1):page212_i85@pure_quanta.q_res(chips)',
 PATH='I85',
 DRAWING='@S9S_MB_2U_LIB.S9S_MB_2U(SCH_1):PAGE201',
 PHYS_PAGE='212',
 XY='(-3725,1200)',
 ROT='0',
 VER='1',
 PACK_TYPE='0402LF',
 CDS_LIB='pure_quanta',
 CDS_PART_NAME='Q_RES_0402LF-0,5%,1/16W,CHIP,CA',
 WATTAGE='1/16W',
 TOLERANCE='5%',
 MATERIAL='CHIP',
 VALUE='0',
 PRIM_FILE='./archive_libs/logical/q_res/chips/chips.prt';

PART_NAME
 R3335 'Q_RES_0402LF-0,5%,1/16W,CHIP,CA':;

SECTION_NUMBER 1
 '@S9S_MB_2U_LIB.S9S_MB_2U(SCH_1):PAGE201_I69@PURE_QUANTA.Q_RES(CHIPS)':
 C_PATH='@s9s_mb_2u_lib.s9s_mb_2u(sch_1):page201_i69@pure_quanta.q_res(chips)',
 P_PATH='@s9s_mb_2u_lib.s9s_mb_2u(sch_1):page212_i69@pure_quanta.q_res(chips)',
 PATH='I69',
 DRAWING='@S9S_MB_2U_LIB.S9S_MB_2U(SCH_1):PAGE201',
 PHYS_PAGE='212',
 XY='(175,3750)',
 ROT='0',
 VER='1',
 PACK_TYPE='0402LF',
 CDS_LIB='pure_quanta',
 CDS_PART_NAME='Q_RES_0402LF-0,5%,1/16W,CHIP,CA',
 WATTAGE='1/16W',
 TOLERANCE='5%',
 MATERIAL='CHIP',
 VALUE='0',
 PRIM_FILE='./archive_libs/logical/q_res/chips/chips.prt';

PART_NAME
 R3336 'Q_RES_0402LF-0,5%,1/16W,CHIP,CA':;

SECTION_NUMBER 1
 '@S9S_MB_2U_LIB.S9S_MB_2U(SCH_1):PAGE201_I74@PURE_QUANTA.Q_RES(CHIPS)':
 C_PATH='@s9s_mb_2u_lib.s9s_mb_2u(sch_1):page201_i74@pure_quanta.q_res(chips)',
 P_PATH='@s9s_mb_2u_lib.s9s_mb_2u(sch_1):page212_i74@pure_quanta.q_res(chips)',
 PATH='I74',
 DRAWING='@S9S_MB_2U_LIB.S9S_MB_2U(SCH_1):PAGE201',
 PHYS_PAGE='212',
 XY='(175,3700)',
 ROT='0',
 VER='1',
 PACK_TYPE='0402LF',
 CDS_LIB='pure_quanta',
 CDS_PART_NAME='Q_RES_0402LF-0,5%,1/16W,CHIP,CA',
 WATTAGE='1/16W',
 TOLERANCE='5%',
 MATERIAL='CHIP',
 VALUE='0',
 PRIM_FILE='./archive_libs/logical/q_res/chips/chips.prt';

PART_NAME
 R3337 'Q_RES_0402LF-0,5%,1/16W,CHIP,CA':;

SECTION_NUMBER 1
 '@S9S_MB_2U_LIB.S9S_MB_2U(SCH_1):PAGE201_I75@PURE_QUANTA.Q_RES(CHIPS)':
 C_PATH='@s9s_mb_2u_lib.s9s_mb_2u(sch_1):page201_i75@pure_quanta.q_res(chips)',
 P_PATH='@s9s_mb_2u_lib.s9s_mb_2u(sch_1):page212_i75@pure_quanta.q_res(chips)',
 PATH='I75',
 DRAWING='@S9S_MB_2U_LIB.S9S_MB_2U(SCH_1):PAGE201',
 PHYS_PAGE='212',
 XY='(175,3600)',
 ROT='0',
 VER='1',
 PACK_TYPE='0402LF',
 CDS_LIB='pure_quanta',
 CDS_PART_NAME='Q_RES_0402LF-0,5%,1/16W,CHIP,CA',
 WATTAGE='1/16W',
 TOLERANCE='5%',
 MATERIAL='CHIP',
 VALUE='0',
 PRIM_FILE='./archive_libs/logical/q_res/chips/chips.prt';

PART_NAME
 R3338 'Q_RES_0402LF-0,5%,1/16W,CHIP,CA':;

SECTION_NUMBER 1
 '@S9S_MB_2U_LIB.S9S_MB_2U(SCH_1):PAGE201_I76@PURE_QUANTA.Q_RES(CHIPS)':
 C_PATH='@s9s_mb_2u_lib.s9s_mb_2u(sch_1):page201_i76@pure_quanta.q_res(chips)',
 P_PATH='@s9s_mb_2u_lib.s9s_mb_2u(sch_1):page212_i76@pure_quanta.q_res(chips)',
 PATH='I76',
 DRAWING='@S9S_MB_2U_LIB.S9S_MB_2U(SCH_1):PAGE201',
 PHYS_PAGE='212',
 XY='(175,3550)',
 ROT='0',
 VER='1',
 PACK_TYPE='0402LF',
 CDS_LIB='pure_quanta',
 CDS_PART_NAME='Q_RES_0402LF-0,5%,1/16W,CHIP,CA',
 WATTAGE='1/16W',
 TOLERANCE='5%',
 MATERIAL='CHIP',
 VALUE='0',
 PRIM_FILE='./archive_libs/logical/q_res/chips/chips.prt';

PART_NAME
 R3340 'Q_RES_0402LF-33.2,1%,1/16W,CHIA':;

SECTION_NUMBER 1
 '@S9S_MB_2U_LIB.S9S_MB_2U(SCH_1):PAGE228_I268@PURE_QUANTA.Q_RES(CHIPS)':
 C_PATH='@s9s_mb_2u_lib.s9s_mb_2u(sch_1):page228_i268@pure_quanta.q_res(chips)',
 P_PATH='@s9s_mb_2u_lib.s9s_mb_2u(sch_1):page241_i268@pure_quanta.q_res(chips)',
 PATH='I268',
 DRAWING='@S9S_MB_2U_LIB.S9S_MB_2U(SCH_1):PAGE228',
 PHYS_PAGE='241',
 XY='(-325,4850)',
 ROT='0',
 VER='1',
 PACK_TYPE='0402LF',
 CDS_LIB='pure_quanta',
 CDS_PART_NAME='Q_RES_0402LF-33.2,1%,1/16W,CHIA',
 WATTAGE='1/16W',
 TOLERANCE='1%',
 MATERIAL='CHIP',
 VALUE='33.2',
 PRIM_FILE='./archive_libs/logical/q_res/chips/chips.prt';

PART_NAME
 R3341 'Q_RES_0402LF-33.2,1%,1/16W,CHIA':;

SECTION_NUMBER 1
 '@S9S_MB_2U_LIB.S9S_MB_2U(SCH_1):PAGE228_I264@PURE_QUANTA.Q_RES(CHIPS)':
 C_PATH='@s9s_mb_2u_lib.s9s_mb_2u(sch_1):page228_i264@pure_quanta.q_res(chips)',
 P_PATH='@s9s_mb_2u_lib.s9s_mb_2u(sch_1):page241_i264@pure_quanta.q_res(chips)',
 PATH='I264',
 DRAWING='@S9S_MB_2U_LIB.S9S_MB_2U(SCH_1):PAGE228',
 PHYS_PAGE='241',
 XY='(-325,4800)',
 ROT='0',
 VER='1',
 PACK_TYPE='0402LF',
 CDS_LIB='pure_quanta',
 CDS_PART_NAME='Q_RES_0402LF-33.2,1%,1/16W,CHIA',
 WATTAGE='1/16W',
 TOLERANCE='1%',
 MATERIAL='CHIP',
 VALUE='33.2',
 PRIM_FILE='./archive_libs/logical/q_res/chips/chips.prt';

PART_NAME
 R3344 'Q_RES_0603LF-1,1%,1/10W,CHIP,CA':;

SECTION_NUMBER 1
 '@S9S_MB_2U_LIB.S9S_MB_2U(SCH_1):PAGE202_I108@PURE_QUANTA.Q_RES(CHIPS)':
 C_PATH='@s9s_mb_2u_lib.s9s_mb_2u(sch_1):page202_i108@pure_quanta.q_res(chips)',
 P_PATH='@s9s_mb_2u_lib.s9s_mb_2u(sch_1):page217_i108@pure_quanta.q_res(chips)',
 PATH='I108',
 DRAWING='@S9S_MB_2U_LIB.S9S_MB_2U(SCH_1):PAGE202',
 PHYS_PAGE='217',
 XY='(-5525,-1925)',
 ROT='0',
 VER='1',
 PACK_TYPE='0603LF',
 CDS_LIB='pure_quanta',
 CDS_PART_NAME='Q_RES_0603LF-1,1%,1/10W,CHIP,CA',
 WATTAGE='1/10W',
 TOLERANCE='1%',
 MATERIAL='CHIP',
 VALUE='1',
 PRIM_FILE='./archive_libs/logical/q_res/chips/chips.prt';

PART_NAME
 R3345 'Q_RES_0603LF-1,1%,1/10W,CHIP,CA':;

SECTION_NUMBER 1
 '@S9S_MB_2U_LIB.S9S_MB_2U(SCH_1):PAGE202_I81@PURE_QUANTA.Q_RES(CHIPS)':
 C_PATH='@s9s_mb_2u_lib.s9s_mb_2u(sch_1):page202_i81@pure_quanta.q_res(chips)',
 P_PATH='@s9s_mb_2u_lib.s9s_mb_2u(sch_1):page217_i81@pure_quanta.q_res(chips)',
 PATH='I81',
 DRAWING='@S9S_MB_2U_LIB.S9S_MB_2U(SCH_1):PAGE202',
 PHYS_PAGE='217',
 XY='(-2575,-1975)',
 ROT='0',
 VER='1',
 PACK_TYPE='0603LF',
 CDS_LIB='pure_quanta',
 CDS_PART_NAME='Q_RES_0603LF-1,1%,1/10W,CHIP,CA',
 WATTAGE='1/10W',
 TOLERANCE='1%',
 MATERIAL='CHIP',
 VALUE='1',
 PRIM_FILE='./archive_libs/logical/q_res/chips/chips.prt';

PART_NAME
 R3346 'Q_RES_0603LF-1,1%,1/10W,CHIP,CA':;

SECTION_NUMBER 1
 '@S9S_MB_2U_LIB.S9S_MB_2U(SCH_1):PAGE202_I63@PURE_QUANTA.Q_RES(CHIPS)':
 C_PATH='@s9s_mb_2u_lib.s9s_mb_2u(sch_1):page202_i63@pure_quanta.q_res(chips)',
 P_PATH='@s9s_mb_2u_lib.s9s_mb_2u(sch_1):page217_i63@pure_quanta.q_res(chips)',
 PATH='I63',
 DRAWING='@S9S_MB_2U_LIB.S9S_MB_2U(SCH_1):PAGE202',
 PHYS_PAGE='217',
 XY='(-1475,1350)',
 ROT='0',
 VER='1',
 PACK_TYPE='0603LF',
 CDS_LIB='pure_quanta',
 CDS_PART_NAME='Q_RES_0603LF-1,1%,1/10W,CHIP,CA',
 WATTAGE='1/10W',
 TOLERANCE='1%',
 MATERIAL='CHIP',
 VALUE='1',
 PRIM_FILE='./archive_libs/logical/q_res/chips/chips.prt';

PART_NAME
 R3347 'Q_RES_0603LF-1,1%,1/10W,CHIP,CA':;

SECTION_NUMBER 1
 '@S9S_MB_2U_LIB.S9S_MB_2U(SCH_1):PAGE202_I72@PURE_QUANTA.Q_RES(CHIPS)':
 C_PATH='@s9s_mb_2u_lib.s9s_mb_2u(sch_1):page202_i72@pure_quanta.q_res(chips)',
 P_PATH='@s9s_mb_2u_lib.s9s_mb_2u(sch_1):page217_i72@pure_quanta.q_res(chips)',
 PATH='I72',
 DRAWING='@S9S_MB_2U_LIB.S9S_MB_2U(SCH_1):PAGE202',
 PHYS_PAGE='217',
 XY='(-1450,-800)',
 ROT='0',
 VER='1',
 PACK_TYPE='0603LF',
 CDS_LIB='pure_quanta',
 CDS_PART_NAME='Q_RES_0603LF-1,1%,1/10W,CHIP,CA',
 WATTAGE='1/10W',
 TOLERANCE='1%',
 MATERIAL='CHIP',
 VALUE='1',
 PRIM_FILE='./archive_libs/logical/q_res/chips/chips.prt';

PART_NAME
 R3348 'Q_RES_0603LF-1,1%,1/10W,CHIP,CA':;

SECTION_NUMBER 1
 '@S9S_MB_2U_LIB.S9S_MB_2U(SCH_1):PAGE202_I67@PURE_QUANTA.Q_RES(CHIPS)':
 C_PATH='@s9s_mb_2u_lib.s9s_mb_2u(sch_1):page202_i67@pure_quanta.q_res(chips)',
 P_PATH='@s9s_mb_2u_lib.s9s_mb_2u(sch_1):page217_i67@pure_quanta.q_res(chips)',
 PATH='I67',
 DRAWING='@S9S_MB_2U_LIB.S9S_MB_2U(SCH_1):PAGE202',
 PHYS_PAGE='217',
 XY='(-1475,325)',
 ROT='0',
 VER='1',
 PACK_TYPE='0603LF',
 CDS_LIB='pure_quanta',
 CDS_PART_NAME='Q_RES_0603LF-1,1%,1/10W,CHIP,CA',
 WATTAGE='1/10W',
 TOLERANCE='1%',
 MATERIAL='CHIP',
 VALUE='1',
 PRIM_FILE='./archive_libs/logical/q_res/chips/chips.prt';

PART_NAME
 R3349 'Q_RES_0603LF-1,1%,1/10W,CHIP,CA':;

SECTION_NUMBER 1
 '@S9S_MB_2U_LIB.S9S_MB_2U(SCH_1):PAGE202_I60@PURE_QUANTA.Q_RES(CHIPS)':
 C_PATH='@s9s_mb_2u_lib.s9s_mb_2u(sch_1):page202_i60@pure_quanta.q_res(chips)',
 P_PATH='@s9s_mb_2u_lib.s9s_mb_2u(sch_1):page217_i60@pure_quanta.q_res(chips)',
 PATH='I60',
 DRAWING='@S9S_MB_2U_LIB.S9S_MB_2U(SCH_1):PAGE202',
 PHYS_PAGE='217',
 XY='(200,-2025)',
 ROT='0',
 VER='1',
 PACK_TYPE='0603LF',
 CDS_LIB='pure_quanta',
 CDS_PART_NAME='Q_RES_0603LF-1,1%,1/10W,CHIP,CA',
 WATTAGE='1/10W',
 TOLERANCE='1%',
 MATERIAL='CHIP',
 VALUE='1',
 PRIM_FILE='./archive_libs/logical/q_res/chips/chips.prt';

PART_NAME
 R3352 'Q_RES_0402LF-0,5%,1/16W,CHIP,CA':;

SECTION_NUMBER 1
 '@S9S_MB_2U_LIB.S9S_MB_2U(SCH_1):PAGE196_I26@PURE_QUANTA.Q_RES(CHIPS)':
 C_PATH='@s9s_mb_2u_lib.s9s_mb_2u(sch_1):page196_i26@pure_quanta.q_res(chips)',
 P_PATH='@s9s_mb_2u_lib.s9s_mb_2u(sch_1):page207_i26@pure_quanta.q_res(chips)',
 PATH='I26',
 DRAWING='@S9S_MB_2U_LIB.S9S_MB_2U(SCH_1):PAGE196',
 PHYS_PAGE='207',
 XY='(-150,-3350)',
 ROT='0',
 VER='1',
 PACK_TYPE='0402LF',
 CDS_LIB='pure_quanta',
 CDS_PART_NAME='Q_RES_0402LF-0,5%,1/16W,CHIP,CA',
 WATTAGE='1/16W',
 TOLERANCE='5%',
 MATERIAL='CHIP',
 VALUE='0',
 PRIM_FILE='./archive_libs/logical/q_res/chips/chips.prt';

PART_NAME
 R3353 'Q_RES_0402LF-0,5%,1/16W,CHIP,CA':;

SECTION_NUMBER 1
 '@S9S_MB_2U_LIB.S9S_MB_2U(SCH_1):PAGE196_I25@PURE_QUANTA.Q_RES(CHIPS)':
 C_PATH='@s9s_mb_2u_lib.s9s_mb_2u(sch_1):page196_i25@pure_quanta.q_res(chips)',
 P_PATH='@s9s_mb_2u_lib.s9s_mb_2u(sch_1):page207_i25@pure_quanta.q_res(chips)',
 PATH='I25',
 DRAWING='@S9S_MB_2U_LIB.S9S_MB_2U(SCH_1):PAGE196',
 PHYS_PAGE='207',
 XY='(-150,-3500)',
 ROT='0',
 VER='1',
 PACK_TYPE='0402LF',
 CDS_LIB='pure_quanta',
 CDS_PART_NAME='Q_RES_0402LF-0,5%,1/16W,CHIP,CA',
 WATTAGE='1/16W',
 TOLERANCE='5%',
 MATERIAL='CHIP',
 VALUE='0',
 PRIM_FILE='./archive_libs/logical/q_res/chips/chips.prt';

PART_NAME
 R3354 'Q_RES_0402LF-0,5%,1/16W,CHIP,CA':;

SECTION_NUMBER 1
 '@S9S_MB_2U_LIB.S9S_MB_2U(SCH_1):PAGE196_I24@PURE_QUANTA.Q_RES(CHIPS)':
 C_PATH='@s9s_mb_2u_lib.s9s_mb_2u(sch_1):page196_i24@pure_quanta.q_res(chips)',
 P_PATH='@s9s_mb_2u_lib.s9s_mb_2u(sch_1):page207_i24@pure_quanta.q_res(chips)',
 PATH='I24',
 DRAWING='@S9S_MB_2U_LIB.S9S_MB_2U(SCH_1):PAGE196',
 PHYS_PAGE='207',
 XY='(-150,-3725)',
 ROT='0',
 VER='1',
 PACK_TYPE='0402LF',
 CDS_LIB='pure_quanta',
 CDS_PART_NAME='Q_RES_0402LF-0,5%,1/16W,CHIP,CA',
 WATTAGE='1/16W',
 TOLERANCE='5%',
 MATERIAL='CHIP',
 VALUE='0',
 PRIM_FILE='./archive_libs/logical/q_res/chips/chips.prt';

PART_NAME
 R3355 'Q_RES_0402LF-0,5%,1/16W,CHIP,CA':;

SECTION_NUMBER 1
 '@S9S_MB_2U_LIB.S9S_MB_2U(SCH_1):PAGE196_I18@PURE_QUANTA.Q_RES(CHIPS)':
 C_PATH='@s9s_mb_2u_lib.s9s_mb_2u(sch_1):page196_i18@pure_quanta.q_res(chips)',
 P_PATH='@s9s_mb_2u_lib.s9s_mb_2u(sch_1):page207_i18@pure_quanta.q_res(chips)',
 PATH='I18',
 DRAWING='@S9S_MB_2U_LIB.S9S_MB_2U(SCH_1):PAGE196',
 PHYS_PAGE='207',
 XY='(-150,-3875)',
 ROT='0',
 VER='1',
 PACK_TYPE='0402LF',
 CDS_LIB='pure_quanta',
 CDS_PART_NAME='Q_RES_0402LF-0,5%,1/16W,CHIP,CA',
 WATTAGE='1/16W',
 TOLERANCE='5%',
 MATERIAL='CHIP',
 VALUE='0',
 PRIM_FILE='./archive_libs/logical/q_res/chips/chips.prt';

PART_NAME
 R3362 'Q_RES_0402LF-1K,1%,1/16W,CHIP,A':
 ROOM='PCIE REDRIVER1_BOM2';

SECTION_NUMBER 1
 '@S9S_MB_2U_LIB.S9S_MB_2U(SCH_1):PAGE159_I53@PURE_QUANTA.Q_RES(CHIPS)':
 C_PATH='@s9s_mb_2u_lib.s9s_mb_2u(sch_1):page159_i53@pure_quanta.q_res(chips)',
 P_PATH='@s9s_mb_2u_lib.s9s_mb_2u(sch_1):page167_i53@pure_quanta.q_res(chips)',
 PATH='I53',
 DRAWING='@S9S_MB_2U_LIB.S9S_MB_2U(SCH_1):PAGE159',
 PHYS_PAGE='167',
 XY='(-825,1150)',
 ROT='0',
 VER='2',
 PACK_TYPE='0402LF',
 CDS_LIB='pure_quanta',
 CDS_PART_NAME='Q_RES_0402LF-1K,1%,1/16W,CHIP,A',
 WATTAGE='1/16W',
 TOLERANCE='1%',
 MATERIAL='CHIP',
 ROOM='PCIE REDRIVER1_BOM2',
 VALUE='1K',
 PRIM_FILE='./archive_libs/logical/q_res/chips/chips.prt';

PART_NAME
 R3381 'Q_RES_0402LF-1K,1%,1/16W,EMPTYA':;

SECTION_NUMBER 1
 '@S9S_MB_2U_LIB.S9S_MB_2U(SCH_1):PAGE159_I61@PURE_QUANTA.Q_RES(CHIPS)':
 C_PATH='@s9s_mb_2u_lib.s9s_mb_2u(sch_1):page159_i61@pure_quanta.q_res(chips)',
 P_PATH='@s9s_mb_2u_lib.s9s_mb_2u(sch_1):page167_i61@pure_quanta.q_res(chips)',
 PATH='I61',
 DRAWING='@S9S_MB_2U_LIB.S9S_MB_2U(SCH_1):PAGE159',
 PHYS_PAGE='167',
 XY='(375,-2650)',
 ROT='0',
 VER='2',
 PACK_TYPE='0402LF',
 CDS_LIB='pure_quanta',
 CDS_PART_NAME='Q_RES_0402LF-1K,1%,1/16W,EMPTYA',
 WATTAGE='1/16W',
 TOLERANCE='1%',
 MATERIAL='EMPTY',
 VALUE='1K',
 PRIM_FILE='./archive_libs/logical/q_res/chips/chips.prt';

PART_NAME
 R3386 'Q_RES_0402LF-1K,1%,1/16W,CHIP,A':
 ROOM='PCIE REDRIVER1_BOM2';

SECTION_NUMBER 1
 '@S9S_MB_2U_LIB.S9S_MB_2U(SCH_1):PAGE159_I81@PURE_QUANTA.Q_RES(CHIPS)':
 C_PATH='@s9s_mb_2u_lib.s9s_mb_2u(sch_1):page159_i81@pure_quanta.q_res(chips)',
 P_PATH='@s9s_mb_2u_lib.s9s_mb_2u(sch_1):page167_i81@pure_quanta.q_res(chips)',
 PATH='I81',
 DRAWING='@S9S_MB_2U_LIB.S9S_MB_2U(SCH_1):PAGE159',
 PHYS_PAGE='167',
 XY='(2750,-2125)',
 ROT='0',
 VER='2',
 PACK_TYPE='0402LF',
 CDS_LIB='pure_quanta',
 CDS_PART_NAME='Q_RES_0402LF-1K,1%,1/16W,CHIP,A',
 WATTAGE='1/16W',
 TOLERANCE='1%',
 MATERIAL='CHIP',
 ROOM='PCIE REDRIVER1_BOM2',
 VALUE='1K',
 PRIM_FILE='./archive_libs/logical/q_res/chips/chips.prt';

PART_NAME
 R3390 'Q_RES_0402LF-49.9,1%,1/16W,CHIA':;

SECTION_NUMBER 1
 '@S9S_MB_2U_LIB.S9S_MB_2U(SCH_1):PAGE160_I201@PURE_QUANTA.Q_RES(CHIPS)':
 C_PATH='@s9s_mb_2u_lib.s9s_mb_2u(sch_1):page160_i201@pure_quanta.q_res(chips)',
 P_PATH='@s9s_mb_2u_lib.s9s_mb_2u(sch_1):page149_i201@pure_quanta.q_res(chips)',
 PATH='I201',
 DRAWING='@S9S_MB_2U_LIB.S9S_MB_2U(SCH_1):PAGE160',
 PHYS_PAGE='149',
 XY='(-4750,4125)',
 ROT='0',
 VER='1',
 PACK_TYPE='0402LF',
 LOCATION='R3390',
 CDS_LIB='pure_quanta',
 CDS_PART_NAME='Q_RES_0402LF-49.9,1%,1/16W,CHIA',
 WATTAGE='1/16W',
 TOLERANCE='1%',
 MATERIAL='CHIP',
 VALUE='49.9',
 PRIM_FILE='./archive_libs/logical/q_res/chips/chips.prt';

PART_NAME
 R3391 'Q_RES_0402LF-49.9,1%,1/16W,CHIA':;

SECTION_NUMBER 1
 '@S9S_MB_2U_LIB.S9S_MB_2U(SCH_1):PAGE160_I200@PURE_QUANTA.Q_RES(CHIPS)':
 C_PATH='@s9s_mb_2u_lib.s9s_mb_2u(sch_1):page160_i200@pure_quanta.q_res(chips)',
 P_PATH='@s9s_mb_2u_lib.s9s_mb_2u(sch_1):page149_i200@pure_quanta.q_res(chips)',
 PATH='I200',
 DRAWING='@S9S_MB_2U_LIB.S9S_MB_2U(SCH_1):PAGE160',
 PHYS_PAGE='149',
 XY='(-4625,1250)',
 ROT='0',
 VER='1',
 PACK_TYPE='0402LF',
 LOCATION='R3391',
 CDS_LIB='pure_quanta',
 CDS_PART_NAME='Q_RES_0402LF-49.9,1%,1/16W,CHIA',
 WATTAGE='1/16W',
 TOLERANCE='1%',
 MATERIAL='CHIP',
 VALUE='49.9',
 PRIM_FILE='./archive_libs/logical/q_res/chips/chips.prt';

PART_NAME
 R3392 'Q_RES_0402LF-49.9,1%,1/16W,CHIA':;

SECTION_NUMBER 1
 '@S9S_MB_2U_LIB.S9S_MB_2U(SCH_1):PAGE160_I202@PURE_QUANTA.Q_RES(CHIPS)':
 C_PATH='@s9s_mb_2u_lib.s9s_mb_2u(sch_1):page160_i202@pure_quanta.q_res(chips)',
 P_PATH='@s9s_mb_2u_lib.s9s_mb_2u(sch_1):page149_i202@pure_quanta.q_res(chips)',
 PATH='I202',
 DRAWING='@S9S_MB_2U_LIB.S9S_MB_2U(SCH_1):PAGE160',
 PHYS_PAGE='149',
 XY='(-4625,3000)',
 ROT='0',
 VER='1',
 PACK_TYPE='0402LF',
 LOCATION='R3392',
 CDS_LIB='pure_quanta',
 CDS_PART_NAME='Q_RES_0402LF-49.9,1%,1/16W,CHIA',
 WATTAGE='1/16W',
 TOLERANCE='1%',
 MATERIAL='CHIP',
 VALUE='49.9',
 PRIM_FILE='./archive_libs/logical/q_res/chips/chips.prt';

PART_NAME
 R3393 'Q_RES_0402LF-0,5%,1/16W,CHIP,CA':;

SECTION_NUMBER 1
 '@S9S_MB_2U_LIB.S9S_MB_2U(SCH_1):PAGE219_I38@PURE_QUANTA.Q_RES(CHIPS)':
 C_PATH='@s9s_mb_2u_lib.s9s_mb_2u(sch_1):page219_i38@pure_quanta.q_res(chips)',
 P_PATH='@s9s_mb_2u_lib.s9s_mb_2u(sch_1):page231_i38@pure_quanta.q_res(chips)',
 PATH='I38',
 DRAWING='@S9S_MB_2U_LIB.S9S_MB_2U(SCH_1):PAGE219',
 PHYS_PAGE='231',
 XY='(600,2625)',
 ROT='2',
 VER='1',
 PACK_TYPE='0402LF',
 SEC='1',
 CDS_LIB='pure_quanta',
 CDS_PART_NAME='Q_RES_0402LF-0,5%,1/16W,CHIP,CA',
 SEC_TYPE='0402LF',
 WATTAGE='1/16W',
 TOLERANCE='5%',
 MATERIAL='CHIP',
 VALUE='0',
 PRIM_FILE='./archive_libs/logical/q_res/chips/chips.prt';

PART_NAME
 R3394 'Q_RES_0402LF-0,5%,1/16W,CHIP,CA':;

SECTION_NUMBER 1
 '@S9S_MB_2U_LIB.S9S_MB_2U(SCH_1):PAGE219_I40@PURE_QUANTA.Q_RES(CHIPS)':
 C_PATH='@s9s_mb_2u_lib.s9s_mb_2u(sch_1):page219_i40@pure_quanta.q_res(chips)',
 P_PATH='@s9s_mb_2u_lib.s9s_mb_2u(sch_1):page231_i40@pure_quanta.q_res(chips)',
 PATH='I40',
 DRAWING='@S9S_MB_2U_LIB.S9S_MB_2U(SCH_1):PAGE219',
 PHYS_PAGE='231',
 XY='(600,2675)',
 ROT='2',
 VER='1',
 PACK_TYPE='0402LF',
 CDS_LIB='pure_quanta',
 CDS_PART_NAME='Q_RES_0402LF-0,5%,1/16W,CHIP,CA',
 WATTAGE='1/16W',
 TOLERANCE='5%',
 MATERIAL='CHIP',
 VALUE='0',
 PRIM_FILE='./archive_libs/logical/q_res/chips/chips.prt';

PART_NAME
 R3395 'Q_RES_0402LF-2.2K,5%,1/16W,CHIA':;

SECTION_NUMBER 1
 '@S9S_MB_2U_LIB.S9S_MB_2U(SCH_1):PAGE219_I54@PURE_QUANTA.Q_RES(CHIPS)':
 C_PATH='@s9s_mb_2u_lib.s9s_mb_2u(sch_1):page219_i54@pure_quanta.q_res(chips)',
 P_PATH='@s9s_mb_2u_lib.s9s_mb_2u(sch_1):page231_i54@pure_quanta.q_res(chips)',
 PATH='I54',
 DRAWING='@S9S_MB_2U_LIB.S9S_MB_2U(SCH_1):PAGE219',
 PHYS_PAGE='231',
 XY='(3850,650)',
 ROT='0',
 VER='1',
 PACK_TYPE='0402LF',
 CDS_LIB='pure_quanta',
 CDS_PART_NAME='Q_RES_0402LF-2.2K,5%,1/16W,CHIA',
 WATTAGE='1/16W',
 TOLERANCE='5%',
 MATERIAL='CHIP',
 VALUE='2.2K',
 PRIM_FILE='./archive_libs/logical/q_res/chips/chips.prt';

PART_NAME
 R3396 'Q_RES_0402LF-2.2K,5%,1/16W,CHIA':;

SECTION_NUMBER 1
 '@S9S_MB_2U_LIB.S9S_MB_2U(SCH_1):PAGE219_I53@PURE_QUANTA.Q_RES(CHIPS)':
 C_PATH='@s9s_mb_2u_lib.s9s_mb_2u(sch_1):page219_i53@pure_quanta.q_res(chips)',
 P_PATH='@s9s_mb_2u_lib.s9s_mb_2u(sch_1):page231_i53@pure_quanta.q_res(chips)',
 PATH='I53',
 DRAWING='@S9S_MB_2U_LIB.S9S_MB_2U(SCH_1):PAGE219',
 PHYS_PAGE='231',
 XY='(3850,600)',
 ROT='0',
 VER='1',
 PACK_TYPE='0402LF',
 CDS_LIB='pure_quanta',
 CDS_PART_NAME='Q_RES_0402LF-2.2K,5%,1/16W,CHIA',
 WATTAGE='1/16W',
 TOLERANCE='5%',
 MATERIAL='CHIP',
 VALUE='2.2K',
 PRIM_FILE='./archive_libs/logical/q_res/chips/chips.prt';

PART_NAME
 R3397 'Q_RES_0402LF-33.2,1%,1/16W,CHIA':;

SECTION_NUMBER 1
 '@S9S_MB_2U_LIB.S9S_MB_2U(SCH_1):PAGE296_I37@PURE_QUANTA.Q_RES(CHIPS)':
 C_PATH='@s9s_mb_2u_lib.s9s_mb_2u(sch_1):page296_i37@pure_quanta.q_res(chips)',
 P_PATH='@s9s_mb_2u_lib.s9s_mb_2u(sch_1):page150_i37@pure_quanta.q_res(chips)',
 PATH='I37',
 DRAWING='@S9S_MB_2U_LIB.S9S_MB_2U(SCH_1):PAGE296',
 PHYS_PAGE='150',
 XY='(2100,4300)',
 ROT='0',
 VER='1',
 PACK_TYPE='0402LF',
 CDS_LIB='pure_quanta',
 CDS_PART_NAME='Q_RES_0402LF-33.2,1%,1/16W,CHIA',
 WATTAGE='1/16W',
 TOLERANCE='1%',
 MATERIAL='CHIP',
 VALUE='33.2',
 PRIM_FILE='./archive_libs/logical/q_res/chips/chips.prt';

PART_NAME
 R3428 'Q_RES_0402LF-100K,1%,1/16W,EMPA':;

SECTION_NUMBER 1
 '@S9S_MB_2U_LIB.S9S_MB_2U(SCH_1):PAGE299_I17@PURE_QUANTA.Q_RES(CHIPS)':
 C_PATH='@s9s_mb_2u_lib.s9s_mb_2u(sch_1):page299_i17@pure_quanta.q_res(chips)',
 P_PATH='@s9s_mb_2u_lib.s9s_mb_2u(sch_1):page147_i17@pure_quanta.q_res(chips)',
 PATH='I17',
 DRAWING='@S9S_MB_2U_LIB.S9S_MB_2U(SCH_1):PAGE299',
 PHYS_PAGE='147',
 XY='(-2975,3525)',
 ROT='0',
 VER='2',
 PACK_TYPE='0402LF',
 CDS_LIB='pure_quanta',
 CDS_PART_NAME='Q_RES_0402LF-100K,1%,1/16W,EMPA',
 WATTAGE='1/16W',
 TOLERANCE='1%',
 MATERIAL='EMPTY',
 VALUE='100K',
 PRIM_FILE='./archive_libs/logical/q_res/chips/chips.prt';

PART_NAME
 R3429 'Q_RES_0402LF-100K,1%,1/16W,EMPA':;

SECTION_NUMBER 1
 '@S9S_MB_2U_LIB.S9S_MB_2U(SCH_1):PAGE299_I130@PURE_QUANTA.Q_RES(CHIPS)':
 C_PATH='@s9s_mb_2u_lib.s9s_mb_2u(sch_1):page299_i130@pure_quanta.q_res(chips)',
 P_PATH='@s9s_mb_2u_lib.s9s_mb_2u(sch_1):page147_i130@pure_quanta.q_res(chips)',
 PATH='I130',
 DRAWING='@S9S_MB_2U_LIB.S9S_MB_2U(SCH_1):PAGE299',
 PHYS_PAGE='147',
 XY='(-2975,2600)',
 ROT='0',
 VER='2',
 PACK_TYPE='0402LF',
 CDS_LIB='pure_quanta',
 CDS_PART_NAME='Q_RES_0402LF-100K,1%,1/16W,EMPA',
 WATTAGE='1/16W',
 TOLERANCE='1%',
 MATERIAL='EMPTY',
 VALUE='100K',
 PRIM_FILE='./archive_libs/logical/q_res/chips/chips.prt';

PART_NAME
 R3430 'Q_RES_0402LF-100K,1%,1/16W,EMPA':;

SECTION_NUMBER 1
 '@S9S_MB_2U_LIB.S9S_MB_2U(SCH_1):PAGE299_I3@PURE_QUANTA.Q_RES(CHIPS)':
 C_PATH='@s9s_mb_2u_lib.s9s_mb_2u(sch_1):page299_i3@pure_quanta.q_res(chips)',
 P_PATH='@s9s_mb_2u_lib.s9s_mb_2u(sch_1):page147_i3@pure_quanta.q_res(chips)',
 PATH='I3',
 DRAWING='@S9S_MB_2U_LIB.S9S_MB_2U(SCH_1):PAGE299',
 PHYS_PAGE='147',
 XY='(-2950,-800)',
 ROT='0',
 VER='2',
 PACK_TYPE='0402LF',
 CDS_LIB='pure_quanta',
 CDS_PART_NAME='Q_RES_0402LF-100K,1%,1/16W,EMPA',
 WATTAGE='1/16W',
 TOLERANCE='1%',
 MATERIAL='EMPTY',
 VALUE='100K',
 PRIM_FILE='./archive_libs/logical/q_res/chips/chips.prt';

PART_NAME
 R3431 'Q_RES_0402LF-100K,1%,1/16W,EMPA':;

SECTION_NUMBER 1
 '@S9S_MB_2U_LIB.S9S_MB_2U(SCH_1):PAGE299_I133@PURE_QUANTA.Q_RES(CHIPS)':
 C_PATH='@s9s_mb_2u_lib.s9s_mb_2u(sch_1):page299_i133@pure_quanta.q_res(chips)',
 P_PATH='@s9s_mb_2u_lib.s9s_mb_2u(sch_1):page147_i133@pure_quanta.q_res(chips)',
 PATH='I133',
 DRAWING='@S9S_MB_2U_LIB.S9S_MB_2U(SCH_1):PAGE299',
 PHYS_PAGE='147',
 XY='(-2900,775)',
 ROT='0',
 VER='2',
 PACK_TYPE='0402LF',
 CDS_LIB='pure_quanta',
 CDS_PART_NAME='Q_RES_0402LF-100K,1%,1/16W,EMPA',
 WATTAGE='1/16W',
 TOLERANCE='1%',
 MATERIAL='EMPTY',
 VALUE='100K',
 PRIM_FILE='./archive_libs/logical/q_res/chips/chips.prt';

PART_NAME
 R3432 'Q_RES_0402LF-4.7K,5%,1/16W,CHIA':;

SECTION_NUMBER 1
 '@S9S_MB_2U_LIB.S9S_MB_2U(SCH_1):PAGE299_I53@PURE_QUANTA.Q_RES(CHIPS)':
 C_PATH='@s9s_mb_2u_lib.s9s_mb_2u(sch_1):page299_i53@pure_quanta.q_res(chips)',
 P_PATH='@s9s_mb_2u_lib.s9s_mb_2u(sch_1):page147_i53@pure_quanta.q_res(chips)',
 PATH='I53',
 DRAWING='@S9S_MB_2U_LIB.S9S_MB_2U(SCH_1):PAGE299',
 PHYS_PAGE='147',
 XY='(-1825,4375)',
 ROT='0',
 VER='2',
 PACK_TYPE='0402LF',
 CDS_LIB='pure_quanta',
 CDS_PART_NAME='Q_RES_0402LF-4.7K,5%,1/16W,CHIA',
 WATTAGE='1/16W',
 TOLERANCE='5%',
 MATERIAL='CHIP',
 VALUE='4.7K',
 PRIM_FILE='./archive_libs/logical/q_res/chips/chips.prt';

PART_NAME
 R3433 'Q_RES_0402LF-4.7K,5%,1/16W,CHIA':;

SECTION_NUMBER 1
 '@S9S_MB_2U_LIB.S9S_MB_2U(SCH_1):PAGE299_I49@PURE_QUANTA.Q_RES(CHIPS)':
 C_PATH='@s9s_mb_2u_lib.s9s_mb_2u(sch_1):page299_i49@pure_quanta.q_res(chips)',
 P_PATH='@s9s_mb_2u_lib.s9s_mb_2u(sch_1):page147_i49@pure_quanta.q_res(chips)',
 PATH='I49',
 DRAWING='@S9S_MB_2U_LIB.S9S_MB_2U(SCH_1):PAGE299',
 PHYS_PAGE='147',
 XY='(-1775,2825)',
 ROT='0',
 VER='2',
 PACK_TYPE='0402LF',
 CDS_LIB='pure_quanta',
 CDS_PART_NAME='Q_RES_0402LF-4.7K,5%,1/16W,CHIA',
 WATTAGE='1/16W',
 TOLERANCE='5%',
 MATERIAL='CHIP',
 VALUE='4.7K',
 PRIM_FILE='./archive_libs/logical/q_res/chips/chips.prt';

PART_NAME
 R3434 'Q_RES_0402LF-4.7K,5%,1/16W,CHIA':;

SECTION_NUMBER 1
 '@S9S_MB_2U_LIB.S9S_MB_2U(SCH_1):PAGE299_I39@PURE_QUANTA.Q_RES(CHIPS)':
 C_PATH='@s9s_mb_2u_lib.s9s_mb_2u(sch_1):page299_i39@pure_quanta.q_res(chips)',
 P_PATH='@s9s_mb_2u_lib.s9s_mb_2u(sch_1):page147_i39@pure_quanta.q_res(chips)',
 PATH='I39',
 DRAWING='@S9S_MB_2U_LIB.S9S_MB_2U(SCH_1):PAGE299',
 PHYS_PAGE='147',
 XY='(-1750,1475)',
 ROT='0',
 VER='2',
 PACK_TYPE='0402LF',
 CDS_LIB='pure_quanta',
 CDS_PART_NAME='Q_RES_0402LF-4.7K,5%,1/16W,CHIA',
 WATTAGE='1/16W',
 TOLERANCE='5%',
 MATERIAL='CHIP',
 VALUE='4.7K',
 PRIM_FILE='./archive_libs/logical/q_res/chips/chips.prt';

PART_NAME
 R3435 'Q_RES_0402LF-4.7K,5%,1/16W,CHIA':;

SECTION_NUMBER 1
 '@S9S_MB_2U_LIB.S9S_MB_2U(SCH_1):PAGE299_I23@PURE_QUANTA.Q_RES(CHIPS)':
 C_PATH='@s9s_mb_2u_lib.s9s_mb_2u(sch_1):page299_i23@pure_quanta.q_res(chips)',
 P_PATH='@s9s_mb_2u_lib.s9s_mb_2u(sch_1):page147_i23@pure_quanta.q_res(chips)',
 PATH='I23',
 DRAWING='@S9S_MB_2U_LIB.S9S_MB_2U(SCH_1):PAGE299',
 PHYS_PAGE='147',
 XY='(-1725,-75)',
 ROT='0',
 VER='2',
 PACK_TYPE='0402LF',
 CDS_LIB='pure_quanta',
 CDS_PART_NAME='Q_RES_0402LF-4.7K,5%,1/16W,CHIA',
 WATTAGE='1/16W',
 TOLERANCE='5%',
 MATERIAL='CHIP',
 VALUE='4.7K',
 PRIM_FILE='./archive_libs/logical/q_res/chips/chips.prt';

PART_NAME
 R3436 'Q_RES_0402LF-4.7K,5%,1/16W,CHIA':;

SECTION_NUMBER 1
 '@S9S_MB_2U_LIB.S9S_MB_2U(SCH_1):PAGE299_I45@PURE_QUANTA.Q_RES(CHIPS)':
 C_PATH='@s9s_mb_2u_lib.s9s_mb_2u(sch_1):page299_i45@pure_quanta.q_res(chips)',
 P_PATH='@s9s_mb_2u_lib.s9s_mb_2u(sch_1):page147_i45@pure_quanta.q_res(chips)',
 PATH='I45',
 DRAWING='@S9S_MB_2U_LIB.S9S_MB_2U(SCH_1):PAGE299',
 PHYS_PAGE='147',
 XY='(-800,1725)',
 ROT='0',
 VER='2',
 PACK_TYPE='0402LF',
 CDS_LIB='pure_quanta',
 CDS_PART_NAME='Q_RES_0402LF-4.7K,5%,1/16W,CHIA',
 WATTAGE='1/16W',
 TOLERANCE='5%',
 MATERIAL='CHIP',
 VALUE='4.7K',
 PRIM_FILE='./archive_libs/logical/q_res/chips/chips.prt';

PART_NAME
 R3437 'Q_RES_0402LF-4.7K,5%,1/16W,CHIA':;

SECTION_NUMBER 1
 '@S9S_MB_2U_LIB.S9S_MB_2U(SCH_1):PAGE299_I27@PURE_QUANTA.Q_RES(CHIPS)':
 C_PATH='@s9s_mb_2u_lib.s9s_mb_2u(sch_1):page299_i27@pure_quanta.q_res(chips)',
 P_PATH='@s9s_mb_2u_lib.s9s_mb_2u(sch_1):page147_i27@pure_quanta.q_res(chips)',
 PATH='I27',
 DRAWING='@S9S_MB_2U_LIB.S9S_MB_2U(SCH_1):PAGE299',
 PHYS_PAGE='147',
 XY='(-800,175)',
 ROT='0',
 VER='2',
 PACK_TYPE='0402LF',
 CDS_LIB='pure_quanta',
 CDS_PART_NAME='Q_RES_0402LF-4.7K,5%,1/16W,CHIA',
 WATTAGE='1/16W',
 TOLERANCE='5%',
 MATERIAL='CHIP',
 VALUE='4.7K',
 PRIM_FILE='./archive_libs/logical/q_res/chips/chips.prt';

PART_NAME
 R3438 'Q_RES_0402LF-4.7K,5%,1/16W,CHIA':;

SECTION_NUMBER 1
 '@S9S_MB_2U_LIB.S9S_MB_2U(SCH_1):PAGE299_I55@PURE_QUANTA.Q_RES(CHIPS)':
 C_PATH='@s9s_mb_2u_lib.s9s_mb_2u(sch_1):page299_i55@pure_quanta.q_res(chips)',
 P_PATH='@s9s_mb_2u_lib.s9s_mb_2u(sch_1):page147_i55@pure_quanta.q_res(chips)',
 PATH='I55',
 DRAWING='@S9S_MB_2U_LIB.S9S_MB_2U(SCH_1):PAGE299',
 PHYS_PAGE='147',
 XY='(-775,3100)',
 ROT='0',
 VER='2',
 PACK_TYPE='0402LF',
 CDS_LIB='pure_quanta',
 CDS_PART_NAME='Q_RES_0402LF-4.7K,5%,1/16W,CHIA',
 WATTAGE='1/16W',
 TOLERANCE='5%',
 MATERIAL='CHIP',
 VALUE='4.7K',
 PRIM_FILE='./archive_libs/logical/q_res/chips/chips.prt';

PART_NAME
 R3439 'Q_RES_0402LF-4.7K,5%,1/16W,CHIA':;

SECTION_NUMBER 1
 '@S9S_MB_2U_LIB.S9S_MB_2U(SCH_1):PAGE299_I59@PURE_QUANTA.Q_RES(CHIPS)':
 C_PATH='@s9s_mb_2u_lib.s9s_mb_2u(sch_1):page299_i59@pure_quanta.q_res(chips)',
 P_PATH='@s9s_mb_2u_lib.s9s_mb_2u(sch_1):page147_i59@pure_quanta.q_res(chips)',
 PATH='I59',
 DRAWING='@S9S_MB_2U_LIB.S9S_MB_2U(SCH_1):PAGE299',
 PHYS_PAGE='147',
 XY='(-675,4500)',
 ROT='0',
 VER='2',
 PACK_TYPE='0402LF',
 CDS_LIB='pure_quanta',
 CDS_PART_NAME='Q_RES_0402LF-4.7K,5%,1/16W,CHIA',
 WATTAGE='1/16W',
 TOLERANCE='5%',
 MATERIAL='CHIP',
 VALUE='4.7K',
 PRIM_FILE='./archive_libs/logical/q_res/chips/chips.prt';

PART_NAME
 R3440 'Q_RES_0402LF-0,5%,1/16W,EMPTY,A':;

SECTION_NUMBER 1
 '@S9S_MB_2U_LIB.S9S_MB_2U(SCH_1):PAGE147_I8@PURE_QUANTA.Q_RES(CHIPS)':
 C_PATH='@s9s_mb_2u_lib.s9s_mb_2u(sch_1):page147_i8@pure_quanta.q_res(chips)',
 P_PATH='@s9s_mb_2u_lib.s9s_mb_2u(sch_1):page144_i8@pure_quanta.q_res(chips)',
 PATH='I8',
 DRAWING='@S9S_MB_2U_LIB.S9S_MB_2U(SCH_1):PAGE147',
 PHYS_PAGE='144',
 XY='(525,4050)',
 ROT='0',
 VER='1',
 PACK_TYPE='0402LF',
 CDS_LIB='pure_quanta',
 CDS_PART_NAME='Q_RES_0402LF-0,5%,1/16W,EMPTY,A',
 WATTAGE='1/16W',
 TOLERANCE='5%',
 MATERIAL='EMPTY',
 VALUE='0',
 PRIM_FILE='./archive_libs/logical/q_res/chips/chips.prt';

PART_NAME
 R3441 'Q_RES_0402LF-0,5%,1/16W,CHIP,CA':;

SECTION_NUMBER 1
 '@S9S_MB_2U_LIB.S9S_MB_2U(SCH_1):PAGE147_I7@PURE_QUANTA.Q_RES(CHIPS)':
 C_PATH='@s9s_mb_2u_lib.s9s_mb_2u(sch_1):page147_i7@pure_quanta.q_res(chips)',
 P_PATH='@s9s_mb_2u_lib.s9s_mb_2u(sch_1):page144_i7@pure_quanta.q_res(chips)',
 PATH='I7',
 DRAWING='@S9S_MB_2U_LIB.S9S_MB_2U(SCH_1):PAGE147',
 PHYS_PAGE='144',
 XY='(525,3850)',
 ROT='0',
 VER='1',
 PACK_TYPE='0402LF',
 CDS_LIB='pure_quanta',
 CDS_PART_NAME='Q_RES_0402LF-0,5%,1/16W,CHIP,CA',
 WATTAGE='1/16W',
 TOLERANCE='5%',
 MATERIAL='CHIP',
 VALUE='0',
 PRIM_FILE='./archive_libs/logical/q_res/chips/chips.prt';

PART_NAME
 R3442 'Q_RES_0402LF-0,5%,1/16W,CHIP,CA':;

SECTION_NUMBER 1
 '@S9S_MB_2U_LIB.S9S_MB_2U(SCH_1):PAGE147_I6@PURE_QUANTA.Q_RES(CHIPS)':
 C_PATH='@s9s_mb_2u_lib.s9s_mb_2u(sch_1):page147_i6@pure_quanta.q_res(chips)',
 P_PATH='@s9s_mb_2u_lib.s9s_mb_2u(sch_1):page144_i6@pure_quanta.q_res(chips)',
 PATH='I6',
 DRAWING='@S9S_MB_2U_LIB.S9S_MB_2U(SCH_1):PAGE147',
 PHYS_PAGE='144',
 XY='(525,3650)',
 ROT='0',
 VER='1',
 PACK_TYPE='0402LF',
 CDS_LIB='pure_quanta',
 CDS_PART_NAME='Q_RES_0402LF-0,5%,1/16W,CHIP,CA',
 WATTAGE='1/16W',
 TOLERANCE='5%',
 MATERIAL='CHIP',
 VALUE='0',
 PRIM_FILE='./archive_libs/logical/q_res/chips/chips.prt';

PART_NAME
 R3443 'Q_RES_0402LF-0,5%,1/16W,CHIP,CA':;

SECTION_NUMBER 1
 '@S9S_MB_2U_LIB.S9S_MB_2U(SCH_1):PAGE147_I5@PURE_QUANTA.Q_RES(CHIPS)':
 C_PATH='@s9s_mb_2u_lib.s9s_mb_2u(sch_1):page147_i5@pure_quanta.q_res(chips)',
 P_PATH='@s9s_mb_2u_lib.s9s_mb_2u(sch_1):page144_i5@pure_quanta.q_res(chips)',
 PATH='I5',
 DRAWING='@S9S_MB_2U_LIB.S9S_MB_2U(SCH_1):PAGE147',
 PHYS_PAGE='144',
 XY='(525,3450)',
 ROT='0',
 VER='1',
 PACK_TYPE='0402LF',
 CDS_LIB='pure_quanta',
 CDS_PART_NAME='Q_RES_0402LF-0,5%,1/16W,CHIP,CA',
 WATTAGE='1/16W',
 TOLERANCE='5%',
 MATERIAL='CHIP',
 VALUE='0',
 PRIM_FILE='./archive_libs/logical/q_res/chips/chips.prt';

PART_NAME
 R3448 'Q_RES_0402LF-4.7K,5%,1/16W,EMPA':;

SECTION_NUMBER 1
 '@S9S_MB_2U_LIB.S9S_MB_2U(SCH_1):PAGE160_I168@PURE_QUANTA.Q_RES(CHIPS)':
 C_PATH='@s9s_mb_2u_lib.s9s_mb_2u(sch_1):page160_i168@pure_quanta.q_res(chips)',
 P_PATH='@s9s_mb_2u_lib.s9s_mb_2u(sch_1):page149_i168@pure_quanta.q_res(chips)',
 PATH='I168',
 DRAWING='@S9S_MB_2U_LIB.S9S_MB_2U(SCH_1):PAGE160',
 PHYS_PAGE='149',
 XY='(-7600,4400)',
 ROT='0',
 VER='2',
 PACK_TYPE='0402LF',
 CDS_LIB='pure_quanta',
 CDS_PART_NAME='Q_RES_0402LF-4.7K,5%,1/16W,EMPA',
 WATTAGE='1/16W',
 TOLERANCE='5%',
 MATERIAL='EMPTY',
 VALUE='4.7K',
 PRIM_FILE='./archive_libs/logical/q_res/chips/chips.prt';

PART_NAME
 R3449 'Q_RES_0402LF-100K,1%,1/16W,CHIA':;

SECTION_NUMBER 1
 '@S9S_MB_2U_LIB.S9S_MB_2U(SCH_1):PAGE160_I170@PURE_QUANTA.Q_RES(CHIPS)':
 C_PATH='@s9s_mb_2u_lib.s9s_mb_2u(sch_1):page160_i170@pure_quanta.q_res(chips)',
 P_PATH='@s9s_mb_2u_lib.s9s_mb_2u(sch_1):page149_i170@pure_quanta.q_res(chips)',
 PATH='I170',
 DRAWING='@S9S_MB_2U_LIB.S9S_MB_2U(SCH_1):PAGE160',
 PHYS_PAGE='149',
 XY='(-7575,3925)',
 ROT='0',
 VER='2',
 PACK_TYPE='0402LF',
 CDS_LIB='pure_quanta',
 CDS_PART_NAME='Q_RES_0402LF-100K,1%,1/16W,CHIA',
 WATTAGE='1/16W',
 TOLERANCE='1%',
 MATERIAL='CHIP',
 VALUE='100K',
 PRIM_FILE='./archive_libs/logical/q_res/chips/chips.prt';

PART_NAME
 R3451 'Q_RES_0402LF-4.7K,5%,1/16W,EMPA':;

SECTION_NUMBER 1
 '@S9S_MB_2U_LIB.S9S_MB_2U(SCH_1):PAGE160_I127@PURE_QUANTA.Q_RES(CHIPS)':
 C_PATH='@s9s_mb_2u_lib.s9s_mb_2u(sch_1):page160_i127@pure_quanta.q_res(chips)',
 P_PATH='@s9s_mb_2u_lib.s9s_mb_2u(sch_1):page149_i127@pure_quanta.q_res(chips)',
 PATH='I127',
 DRAWING='@S9S_MB_2U_LIB.S9S_MB_2U(SCH_1):PAGE160',
 PHYS_PAGE='149',
 XY='(-7600,3350)',
 ROT='0',
 VER='2',
 PACK_TYPE='0402LF',
 CDS_LIB='pure_quanta',
 CDS_PART_NAME='Q_RES_0402LF-4.7K,5%,1/16W,EMPA',
 WATTAGE='1/16W',
 TOLERANCE='5%',
 MATERIAL='EMPTY',
 VALUE='4.7K',
 PRIM_FILE='./archive_libs/logical/q_res/chips/chips.prt';

PART_NAME
 R3452 'Q_RES_0402LF-100K,1%,1/16W,CHIA':;

SECTION_NUMBER 1
 '@S9S_MB_2U_LIB.S9S_MB_2U(SCH_1):PAGE160_I95@PURE_QUANTA.Q_RES(CHIPS)':
 C_PATH='@s9s_mb_2u_lib.s9s_mb_2u(sch_1):page160_i95@pure_quanta.q_res(chips)',
 P_PATH='@s9s_mb_2u_lib.s9s_mb_2u(sch_1):page149_i95@pure_quanta.q_res(chips)',
 PATH='I95',
 DRAWING='@S9S_MB_2U_LIB.S9S_MB_2U(SCH_1):PAGE160',
 PHYS_PAGE='149',
 XY='(-7575,2875)',
 ROT='0',
 VER='2',
 PACK_TYPE='0402LF',
 CDS_LIB='pure_quanta',
 CDS_PART_NAME='Q_RES_0402LF-100K,1%,1/16W,CHIA',
 WATTAGE='1/16W',
 TOLERANCE='1%',
 MATERIAL='CHIP',
 VALUE='100K',
 PRIM_FILE='./archive_libs/logical/q_res/chips/chips.prt';

PART_NAME
 R3453 'Q_RES_0402LF-100K,1%,1/16W,EMPA':;

SECTION_NUMBER 1
 '@S9S_MB_2U_LIB.S9S_MB_2U(SCH_1):PAGE160_I164@PURE_QUANTA.Q_RES(CHIPS)':
 C_PATH='@s9s_mb_2u_lib.s9s_mb_2u(sch_1):page160_i164@pure_quanta.q_res(chips)',
 P_PATH='@s9s_mb_2u_lib.s9s_mb_2u(sch_1):page149_i164@pure_quanta.q_res(chips)',
 PATH='I164',
 DRAWING='@S9S_MB_2U_LIB.S9S_MB_2U(SCH_1):PAGE160',
 PHYS_PAGE='149',
 XY='(-5000,4425)',
 ROT='0',
 VER='2',
 PACK_TYPE='0402LF',
 CDS_LIB='pure_quanta',
 CDS_PART_NAME='Q_RES_0402LF-100K,1%,1/16W,EMPA',
 WATTAGE='1/16W',
 TOLERANCE='1%',
 MATERIAL='EMPTY',
 VALUE='100K',
 PRIM_FILE='./archive_libs/logical/q_res/chips/chips.prt';

PART_NAME
 R3454 'Q_RES_0402LF-1K,1%,1/16W,CHIP,A':;

SECTION_NUMBER 1
 '@S9S_MB_2U_LIB.S9S_MB_2U(SCH_1):PAGE160_I165@PURE_QUANTA.Q_RES(CHIPS)':
 C_PATH='@s9s_mb_2u_lib.s9s_mb_2u(sch_1):page160_i165@pure_quanta.q_res(chips)',
 P_PATH='@s9s_mb_2u_lib.s9s_mb_2u(sch_1):page149_i165@pure_quanta.q_res(chips)',
 PATH='I165',
 DRAWING='@S9S_MB_2U_LIB.S9S_MB_2U(SCH_1):PAGE160',
 PHYS_PAGE='149',
 XY='(-4975,3825)',
 ROT='0',
 VER='2',
 PACK_TYPE='0402LF',
 CDS_LIB='pure_quanta',
 CDS_PART_NAME='Q_RES_0402LF-1K,1%,1/16W,CHIP,A',
 WATTAGE='1/16W',
 TOLERANCE='1%',
 MATERIAL='CHIP',
 VALUE='1K',
 PRIM_FILE='./archive_libs/logical/q_res/chips/chips.prt';

PART_NAME
 R3455 'Q_RES_0402LF-10K,1%,1/16W,CHIPA':;

SECTION_NUMBER 1
 '@S9S_MB_2U_LIB.S9S_MB_2U(SCH_1):PAGE160_I139@PURE_QUANTA.Q_RES(CHIPS)':
 C_PATH='@s9s_mb_2u_lib.s9s_mb_2u(sch_1):page160_i139@pure_quanta.q_res(chips)',
 P_PATH='@s9s_mb_2u_lib.s9s_mb_2u(sch_1):page149_i139@pure_quanta.q_res(chips)',
 PATH='I139',
 DRAWING='@S9S_MB_2U_LIB.S9S_MB_2U(SCH_1):PAGE160',
 PHYS_PAGE='149',
 XY='(-4950,975)',
 ROT='0',
 VER='2',
 PACK_TYPE='0402LF',
 CDS_LIB='pure_quanta',
 CDS_PART_NAME='Q_RES_0402LF-10K,1%,1/16W,CHIPA',
 WATTAGE='1/16W',
 TOLERANCE='1%',
 MATERIAL='CHIP',
 VALUE='10K',
 PRIM_FILE='./archive_libs/logical/q_res/chips/chips.prt';

PART_NAME
 R3456 'Q_RES_0402LF-100K,1%,1/16W,EMPA':;

SECTION_NUMBER 1
 '@S9S_MB_2U_LIB.S9S_MB_2U(SCH_1):PAGE160_I124@PURE_QUANTA.Q_RES(CHIPS)':
 C_PATH='@s9s_mb_2u_lib.s9s_mb_2u(sch_1):page160_i124@pure_quanta.q_res(chips)',
 P_PATH='@s9s_mb_2u_lib.s9s_mb_2u(sch_1):page149_i124@pure_quanta.q_res(chips)',
 PATH='I124',
 DRAWING='@S9S_MB_2U_LIB.S9S_MB_2U(SCH_1):PAGE160',
 PHYS_PAGE='149',
 XY='(-4975,3225)',
 ROT='0',
 VER='2',
 PACK_TYPE='0402LF',
 CDS_LIB='pure_quanta',
 CDS_PART_NAME='Q_RES_0402LF-100K,1%,1/16W,EMPA',
 WATTAGE='1/16W',
 TOLERANCE='1%',
 MATERIAL='EMPTY',
 VALUE='100K',
 PRIM_FILE='./archive_libs/logical/q_res/chips/chips.prt';

PART_NAME
 R3457 'Q_RES_0402LF-10K,1%,1/16W,CHIPA':;

SECTION_NUMBER 1
 '@S9S_MB_2U_LIB.S9S_MB_2U(SCH_1):PAGE160_I123@PURE_QUANTA.Q_RES(CHIPS)':
 C_PATH='@s9s_mb_2u_lib.s9s_mb_2u(sch_1):page160_i123@pure_quanta.q_res(chips)',
 P_PATH='@s9s_mb_2u_lib.s9s_mb_2u(sch_1):page149_i123@pure_quanta.q_res(chips)',
 PATH='I123',
 DRAWING='@S9S_MB_2U_LIB.S9S_MB_2U(SCH_1):PAGE160',
 PHYS_PAGE='149',
 XY='(-4950,2725)',
 ROT='0',
 VER='2',
 PACK_TYPE='0402LF',
 CDS_LIB='pure_quanta',
 CDS_PART_NAME='Q_RES_0402LF-10K,1%,1/16W,CHIPA',
 WATTAGE='1/16W',
 TOLERANCE='1%',
 MATERIAL='CHIP',
 VALUE='10K',
 PRIM_FILE='./archive_libs/logical/q_res/chips/chips.prt';

PART_NAME
 R3458 'Q_RES_0603LF-1,1%,1/10W,CHIP,CA':;

SECTION_NUMBER 1
 '@S9S_MB_2U_LIB.S9S_MB_2U(SCH_1):PAGE202_I119@PURE_QUANTA.Q_RES(CHIPS)':
 C_PATH='@s9s_mb_2u_lib.s9s_mb_2u(sch_1):page202_i119@pure_quanta.q_res(chips)',
 P_PATH='@s9s_mb_2u_lib.s9s_mb_2u(sch_1):page217_i119@pure_quanta.q_res(chips)',
 PATH='I119',
 DRAWING='@S9S_MB_2U_LIB.S9S_MB_2U(SCH_1):PAGE202',
 PHYS_PAGE='217',
 XY='(-1700,2575)',
 ROT='0',
 VER='1',
 PACK_TYPE='0603LF',
 CDS_LIB='pure_quanta',
 CDS_PART_NAME='Q_RES_0603LF-1,1%,1/10W,CHIP,CA',
 WATTAGE='1/10W',
 TOLERANCE='1%',
 MATERIAL='CHIP',
 VALUE='1',
 PRIM_FILE='./archive_libs/logical/q_res/chips/chips.prt';

PART_NAME
 R3459 'Q_RES_0402LF-4.7K,5%,1/16W,CHIA':;

SECTION_NUMBER 1
 '@S9S_MB_2U_LIB.S9S_MB_2U(SCH_1):PAGE296_I29@PURE_QUANTA.Q_RES(CHIPS)':
 C_PATH='@s9s_mb_2u_lib.s9s_mb_2u(sch_1):page296_i29@pure_quanta.q_res(chips)',
 P_PATH='@s9s_mb_2u_lib.s9s_mb_2u(sch_1):page150_i29@pure_quanta.q_res(chips)',
 PATH='I29',
 DRAWING='@S9S_MB_2U_LIB.S9S_MB_2U(SCH_1):PAGE296',
 PHYS_PAGE='150',
 XY='(-650,4575)',
 ROT='0',
 VER='2',
 PACK_TYPE='0402LF',
 CDS_LIB='pure_quanta',
 CDS_PART_NAME='Q_RES_0402LF-4.7K,5%,1/16W,CHIA',
 WATTAGE='1/16W',
 TOLERANCE='5%',
 MATERIAL='CHIP',
 VALUE='4.7K',
 PRIM_FILE='./archive_libs/logical/q_res/chips/chips.prt';

PART_NAME
 R3460 'Q_RES_0402LF-100K,1%,1/16W,EMPA':;

SECTION_NUMBER 1
 '@S9S_MB_2U_LIB.S9S_MB_2U(SCH_1):PAGE296_I31@PURE_QUANTA.Q_RES(CHIPS)':
 C_PATH='@s9s_mb_2u_lib.s9s_mb_2u(sch_1):page296_i31@pure_quanta.q_res(chips)',
 P_PATH='@s9s_mb_2u_lib.s9s_mb_2u(sch_1):page150_i31@pure_quanta.q_res(chips)',
 PATH='I31',
 DRAWING='@S9S_MB_2U_LIB.S9S_MB_2U(SCH_1):PAGE296',
 PHYS_PAGE='150',
 XY='(-625,4100)',
 ROT='0',
 VER='2',
 PACK_TYPE='0402LF',
 CDS_LIB='pure_quanta',
 CDS_PART_NAME='Q_RES_0402LF-100K,1%,1/16W,EMPA',
 WATTAGE='1/16W',
 TOLERANCE='1%',
 MATERIAL='EMPTY',
 VALUE='100K',
 PRIM_FILE='./archive_libs/logical/q_res/chips/chips.prt';

PART_NAME
 R3461 'Q_RES_0402LF-54.9K,1%,1/16W,CHA':;

SECTION_NUMBER 1
 '@S9S_MB_2U_LIB.S9S_MB_2U(SCH_1):PAGE296_I35@PURE_QUANTA.Q_RES(CHIPS)':
 C_PATH='@s9s_mb_2u_lib.s9s_mb_2u(sch_1):page296_i35@pure_quanta.q_res(chips)',
 P_PATH='@s9s_mb_2u_lib.s9s_mb_2u(sch_1):page150_i35@pure_quanta.q_res(chips)',
 PATH='I35',
 DRAWING='@S9S_MB_2U_LIB.S9S_MB_2U(SCH_1):PAGE296',
 PHYS_PAGE='150',
 XY='(1850,4600)',
 ROT='0',
 VER='2',
 PACK_TYPE='0402LF',
 CDS_LIB='pure_quanta',
 CDS_PART_NAME='Q_RES_0402LF-54.9K,1%,1/16W,CHA',
 WATTAGE='1/16W',
 TOLERANCE='1%',
 MATERIAL='CHIP',
 VALUE='54.9K',
 PRIM_FILE='./archive_libs/logical/q_res/chips/chips.prt';

PART_NAME
 R3462 'Q_RES_0402LF-100K,1%,1/16W,EMPA':;

SECTION_NUMBER 1
 '@S9S_MB_2U_LIB.S9S_MB_2U(SCH_1):PAGE296_I33@PURE_QUANTA.Q_RES(CHIPS)':
 C_PATH='@s9s_mb_2u_lib.s9s_mb_2u(sch_1):page296_i33@pure_quanta.q_res(chips)',
 P_PATH='@s9s_mb_2u_lib.s9s_mb_2u(sch_1):page150_i33@pure_quanta.q_res(chips)',
 PATH='I33',
 DRAWING='@S9S_MB_2U_LIB.S9S_MB_2U(SCH_1):PAGE296',
 PHYS_PAGE='150',
 XY='(1875,4000)',
 ROT='0',
 VER='2',
 PACK_TYPE='0402LF',
 CDS_LIB='pure_quanta',
 CDS_PART_NAME='Q_RES_0402LF-100K,1%,1/16W,EMPA',
 WATTAGE='1/16W',
 TOLERANCE='1%',
 MATERIAL='EMPTY',
 VALUE='100K',
 PRIM_FILE='./archive_libs/logical/q_res/chips/chips.prt';

PART_NAME
 R3463 'Q_RES_0402LF-54.9K,1%,1/16W,CHA':;

SECTION_NUMBER 1
 '@S9S_MB_2U_LIB.S9S_MB_2U(SCH_1):PAGE299_I131@PURE_QUANTA.Q_RES(CHIPS)':
 C_PATH='@s9s_mb_2u_lib.s9s_mb_2u(sch_1):page299_i131@pure_quanta.q_res(chips)',
 P_PATH='@s9s_mb_2u_lib.s9s_mb_2u(sch_1):page147_i131@pure_quanta.q_res(chips)',
 PATH='I131',
 DRAWING='@S9S_MB_2U_LIB.S9S_MB_2U(SCH_1):PAGE299',
 PHYS_PAGE='147',
 XY='(-2950,2125)',
 ROT='0',
 VER='2',
 PACK_TYPE='0402LF',
 CDS_LIB='pure_quanta',
 CDS_PART_NAME='Q_RES_0402LF-54.9K,1%,1/16W,CHA',
 WATTAGE='1/16W',
 TOLERANCE='1%',
 MATERIAL='CHIP',
 VALUE='54.9K',
 PRIM_FILE='./archive_libs/logical/q_res/chips/chips.prt';

PART_NAME
 R3464 'Q_RES_0402LF-54.9K,1%,1/16W,CHA':;

SECTION_NUMBER 1
 '@S9S_MB_2U_LIB.S9S_MB_2U(SCH_1):PAGE299_I134@PURE_QUANTA.Q_RES(CHIPS)':
 C_PATH='@s9s_mb_2u_lib.s9s_mb_2u(sch_1):page299_i134@pure_quanta.q_res(chips)',
 P_PATH='@s9s_mb_2u_lib.s9s_mb_2u(sch_1):page147_i134@pure_quanta.q_res(chips)',
 PATH='I134',
 DRAWING='@S9S_MB_2U_LIB.S9S_MB_2U(SCH_1):PAGE299',
 PHYS_PAGE='147',
 XY='(-2975,-375)',
 ROT='0',
 VER='2',
 PACK_TYPE='0402LF',
 CDS_LIB='pure_quanta',
 CDS_PART_NAME='Q_RES_0402LF-54.9K,1%,1/16W,CHA',
 WATTAGE='1/16W',
 TOLERANCE='1%',
 MATERIAL='CHIP',
 VALUE='54.9K',
 PRIM_FILE='./archive_libs/logical/q_res/chips/chips.prt';

PART_NAME
 R3465 'Q_RES_0402LF-10K,1%,1/16W,CHIPA':;

SECTION_NUMBER 1
 '@S9S_MB_2U_LIB.S9S_MB_2U(SCH_1):PAGE299_I132@PURE_QUANTA.Q_RES(CHIPS)':
 C_PATH='@s9s_mb_2u_lib.s9s_mb_2u(sch_1):page299_i132@pure_quanta.q_res(chips)',
 P_PATH='@s9s_mb_2u_lib.s9s_mb_2u(sch_1):page147_i132@pure_quanta.q_res(chips)',
 PATH='I132',
 DRAWING='@S9S_MB_2U_LIB.S9S_MB_2U(SCH_1):PAGE299',
 PHYS_PAGE='147',
 XY='(-2925,1250)',
 ROT='0',
 VER='2',
 PACK_TYPE='0402LF',
 CDS_LIB='pure_quanta',
 CDS_PART_NAME='Q_RES_0402LF-10K,1%,1/16W,CHIPA',
 WATTAGE='1/16W',
 TOLERANCE='1%',
 MATERIAL='CHIP',
 VALUE='10K',
 PRIM_FILE='./archive_libs/logical/q_res/chips/chips.prt';

PART_NAME
 R3466 'Q_RES_0402LF-10K,1%,1/16W,CHIPA':;

SECTION_NUMBER 1
 '@S9S_MB_2U_LIB.S9S_MB_2U(SCH_1):PAGE160_I184@PURE_QUANTA.Q_RES(CHIPS)':
 C_PATH='@s9s_mb_2u_lib.s9s_mb_2u(sch_1):page160_i184@pure_quanta.q_res(chips)',
 P_PATH='@s9s_mb_2u_lib.s9s_mb_2u(sch_1):page149_i184@pure_quanta.q_res(chips)',
 PATH='I184',
 DRAWING='@S9S_MB_2U_LIB.S9S_MB_2U(SCH_1):PAGE160',
 PHYS_PAGE='149',
 XY='(-4975,-175)',
 ROT='0',
 VER='2',
 PACK_TYPE='0402LF',
 CDS_LIB='pure_quanta',
 CDS_PART_NAME='Q_RES_0402LF-10K,1%,1/16W,CHIPA',
 WATTAGE='1/16W',
 TOLERANCE='1%',
 MATERIAL='CHIP',
 VALUE='10K',
 PRIM_FILE='./archive_libs/logical/q_res/chips/chips.prt';

PART_NAME
 R3467 'Q_RES_0402LF-10K,1%,1/16W,CHIPA':;

SECTION_NUMBER 1
 '@S9S_MB_2U_LIB.S9S_MB_2U(SCH_1):PAGE160_I181@PURE_QUANTA.Q_RES(CHIPS)':
 C_PATH='@s9s_mb_2u_lib.s9s_mb_2u(sch_1):page160_i181@pure_quanta.q_res(chips)',
 P_PATH='@s9s_mb_2u_lib.s9s_mb_2u(sch_1):page149_i181@pure_quanta.q_res(chips)',
 PATH='I181',
 DRAWING='@S9S_MB_2U_LIB.S9S_MB_2U(SCH_1):PAGE160',
 PHYS_PAGE='149',
 XY='(-4950,1625)',
 ROT='0',
 VER='2',
 PACK_TYPE='0402LF',
 CDS_LIB='pure_quanta',
 CDS_PART_NAME='Q_RES_0402LF-10K,1%,1/16W,CHIPA',
 WATTAGE='1/16W',
 TOLERANCE='1%',
 MATERIAL='CHIP',
 VALUE='10K',
 PRIM_FILE='./archive_libs/logical/q_res/chips/chips.prt';

PART_NAME
 R3468 'Q_RES_0402LF-49.9,1%,1/16W,CHIA':;

SECTION_NUMBER 1
 '@S9S_MB_2U_LIB.S9S_MB_2U(SCH_1):PAGE160_I197@PURE_QUANTA.Q_RES(CHIPS)':
 C_PATH='@s9s_mb_2u_lib.s9s_mb_2u(sch_1):page160_i197@pure_quanta.q_res(chips)',
 P_PATH='@s9s_mb_2u_lib.s9s_mb_2u(sch_1):page149_i197@pure_quanta.q_res(chips)',
 PATH='I197',
 DRAWING='@S9S_MB_2U_LIB.S9S_MB_2U(SCH_1):PAGE160',
 PHYS_PAGE='149',
 XY='(-4650,100)',
 ROT='0',
 VER='1',
 PACK_TYPE='0402LF',
 LOCATION='R3468',
 CDS_LIB='pure_quanta',
 CDS_PART_NAME='Q_RES_0402LF-49.9,1%,1/16W,CHIA',
 WATTAGE='1/16W',
 TOLERANCE='1%',
 MATERIAL='CHIP',
 VALUE='49.9',
 PRIM_FILE='./archive_libs/logical/q_res/chips/chips.prt';

PART_NAME
 R3469 'Q_RES_0402LF-49.9,1%,1/16W,CHIA':;

SECTION_NUMBER 1
 '@S9S_MB_2U_LIB.S9S_MB_2U(SCH_1):PAGE160_I199@PURE_QUANTA.Q_RES(CHIPS)':
 C_PATH='@s9s_mb_2u_lib.s9s_mb_2u(sch_1):page160_i199@pure_quanta.q_res(chips)',
 P_PATH='@s9s_mb_2u_lib.s9s_mb_2u(sch_1):page149_i199@pure_quanta.q_res(chips)',
 PATH='I199',
 DRAWING='@S9S_MB_2U_LIB.S9S_MB_2U(SCH_1):PAGE160',
 PHYS_PAGE='149',
 XY='(-4625,1900)',
 ROT='0',
 VER='1',
 PACK_TYPE='0402LF',
 LOCATION='R3469',
 CDS_LIB='pure_quanta',
 CDS_PART_NAME='Q_RES_0402LF-49.9,1%,1/16W,CHIA',
 WATTAGE='1/16W',
 TOLERANCE='1%',
 MATERIAL='CHIP',
 VALUE='49.9',
 PRIM_FILE='./archive_libs/logical/q_res/chips/chips.prt';

PART_NAME
 R3470 'Q_RES_0402LF-10K,1%,1/16W,EMPTA':;

SECTION_NUMBER 1
 '@S9S_MB_2U_LIB.S9S_MB_2U(SCH_1):PAGE299_I145@PURE_QUANTA.Q_RES(CHIPS)':
 C_PATH='@s9s_mb_2u_lib.s9s_mb_2u(sch_1):page299_i145@pure_quanta.q_res(chips)',
 P_PATH='@s9s_mb_2u_lib.s9s_mb_2u(sch_1):page147_i145@pure_quanta.q_res(chips)',
 PATH='I145',
 DRAWING='@S9S_MB_2U_LIB.S9S_MB_2U(SCH_1):PAGE299',
 PHYS_PAGE='147',
 XY='(2175,4450)',
 ROT='0',
 VER='2',
 PACK_TYPE='0402LF',
 CDS_LIB='pure_quanta',
 CDS_PART_NAME='Q_RES_0402LF-10K,1%,1/16W,EMPTA',
 WATTAGE='1/16W',
 TOLERANCE='1%',
 MATERIAL='EMPTY',
 VALUE='10K',
 PRIM_FILE='./archive_libs/logical/q_res/chips/chips.prt';

PART_NAME
 R3471 'Q_RES_0402LF-10K,1%,1/16W,CHIPA':;

SECTION_NUMBER 1
 '@S9S_MB_2U_LIB.S9S_MB_2U(SCH_1):PAGE299_I144@PURE_QUANTA.Q_RES(CHIPS)':
 C_PATH='@s9s_mb_2u_lib.s9s_mb_2u(sch_1):page299_i144@pure_quanta.q_res(chips)',
 P_PATH='@s9s_mb_2u_lib.s9s_mb_2u(sch_1):page147_i144@pure_quanta.q_res(chips)',
 PATH='I144',
 DRAWING='@S9S_MB_2U_LIB.S9S_MB_2U(SCH_1):PAGE299',
 PHYS_PAGE='147',
 XY='(2200,3900)',
 ROT='0',
 VER='2',
 PACK_TYPE='0402LF',
 CDS_LIB='pure_quanta',
 CDS_PART_NAME='Q_RES_0402LF-10K,1%,1/16W,CHIPA',
 WATTAGE='1/16W',
 TOLERANCE='1%',
 MATERIAL='CHIP',
 VALUE='10K',
 PRIM_FILE='./archive_libs/logical/q_res/chips/chips.prt';

PART_NAME
 R3472 'Q_RES_0402LF-0,5%,1/16W,EMPTY,A':;

SECTION_NUMBER 1
 '@S9S_MB_2U_LIB.S9S_MB_2U(SCH_1):PAGE299_I147@PURE_QUANTA.Q_RES(CHIPS)':
 C_PATH='@s9s_mb_2u_lib.s9s_mb_2u(sch_1):page299_i147@pure_quanta.q_res(chips)',
 P_PATH='@s9s_mb_2u_lib.s9s_mb_2u(sch_1):page147_i147@pure_quanta.q_res(chips)',
 PATH='I147',
 DRAWING='@S9S_MB_2U_LIB.S9S_MB_2U(SCH_1):PAGE299',
 PHYS_PAGE='147',
 XY='(4200,4175)',
 ROT='1',
 VER='1',
 PACK_TYPE='0402LF',
 CDS_LIB='pure_quanta',
 CDS_PART_NAME='Q_RES_0402LF-0,5%,1/16W,EMPTY,A',
 WATTAGE='1/16W',
 TOLERANCE='5%',
 MATERIAL='EMPTY',
 VALUE='0',
 PRIM_FILE='./archive_libs/logical/q_res/chips/chips.prt';

PART_NAME
 R3473 'Q_RES_0402LF-100K,1%,1/16W,EMPA':;

SECTION_NUMBER 1
 '@S9S_MB_2U_LIB.S9S_MB_2U(SCH_1):PAGE299_I163@PURE_QUANTA.Q_RES(CHIPS)':
 C_PATH='@s9s_mb_2u_lib.s9s_mb_2u(sch_1):page299_i163@pure_quanta.q_res(chips)',
 P_PATH='@s9s_mb_2u_lib.s9s_mb_2u(sch_1):page147_i163@pure_quanta.q_res(chips)',
 PATH='I163',
 DRAWING='@S9S_MB_2U_LIB.S9S_MB_2U(SCH_1):PAGE299',
 PHYS_PAGE='147',
 XY='(1750,2300)',
 ROT='0',
 VER='2',
 PACK_TYPE='0402LF',
 CDS_LIB='pure_quanta',
 CDS_PART_NAME='Q_RES_0402LF-100K,1%,1/16W,EMPA',
 WATTAGE='1/16W',
 TOLERANCE='1%',
 MATERIAL='EMPTY',
 VALUE='100K',
 PRIM_FILE='./archive_libs/logical/q_res/chips/chips.prt';

PART_NAME
 R3474 'Q_RES_0402LF-4.7K,5%,1/16W,CHIA':;

SECTION_NUMBER 1
 '@S9S_MB_2U_LIB.S9S_MB_2U(SCH_1):PAGE299_I158@PURE_QUANTA.Q_RES(CHIPS)':
 C_PATH='@s9s_mb_2u_lib.s9s_mb_2u(sch_1):page299_i158@pure_quanta.q_res(chips)',
 P_PATH='@s9s_mb_2u_lib.s9s_mb_2u(sch_1):page147_i158@pure_quanta.q_res(chips)',
 PATH='I158',
 DRAWING='@S9S_MB_2U_LIB.S9S_MB_2U(SCH_1):PAGE299',
 PHYS_PAGE='147',
 XY='(2975,3025)',
 ROT='0',
 VER='2',
 PACK_TYPE='0402LF',
 CDS_LIB='pure_quanta',
 CDS_PART_NAME='Q_RES_0402LF-4.7K,5%,1/16W,CHIA',
 WATTAGE='1/16W',
 TOLERANCE='5%',
 MATERIAL='CHIP',
 VALUE='4.7K',
 PRIM_FILE='./archive_libs/logical/q_res/chips/chips.prt';

PART_NAME
 R3475 'Q_RES_0402LF-4.7K,5%,1/16W,CHIA':;

SECTION_NUMBER 1
 '@S9S_MB_2U_LIB.S9S_MB_2U(SCH_1):PAGE299_I154@PURE_QUANTA.Q_RES(CHIPS)':
 C_PATH='@s9s_mb_2u_lib.s9s_mb_2u(sch_1):page299_i154@pure_quanta.q_res(chips)',
 P_PATH='@s9s_mb_2u_lib.s9s_mb_2u(sch_1):page147_i154@pure_quanta.q_res(chips)',
 PATH='I154',
 DRAWING='@S9S_MB_2U_LIB.S9S_MB_2U(SCH_1):PAGE299',
 PHYS_PAGE='147',
 XY='(3900,3275)',
 ROT='0',
 VER='2',
 PACK_TYPE='0402LF',
 CDS_LIB='pure_quanta',
 CDS_PART_NAME='Q_RES_0402LF-4.7K,5%,1/16W,CHIA',
 WATTAGE='1/16W',
 TOLERANCE='5%',
 MATERIAL='CHIP',
 VALUE='4.7K',
 PRIM_FILE='./archive_libs/logical/q_res/chips/chips.prt';

PART_NAME
 R3476 'Q_RES_0402LF-33.2,1%,1/16W,CHIA':;

SECTION_NUMBER 1
 '@S9S_MB_2U_LIB.S9S_MB_2U(SCH_1):PAGE314_I25@PURE_QUANTA.Q_RES(CHIPS)':
 C_PATH='@s9s_mb_2u_lib.s9s_mb_2u(sch_1):page314_i25@pure_quanta.q_res(chips)',
 P_PATH='@s9s_mb_2u_lib.s9s_mb_2u(sch_1):page213_i25@pure_quanta.q_res(chips)',
 PATH='I25',
 DRAWING='@S9S_MB_2U_LIB.S9S_MB_2U(SCH_1):PAGE314',
 PHYS_PAGE='213',
 XY='(-2225,-125)',
 ROT='0',
 VER='1',
 PACK_TYPE='0402LF',
 LOCATION='R3476',
 CDS_LIB='pure_quanta',
 CDS_PART_NAME='Q_RES_0402LF-33.2,1%,1/16W,CHIA',
 WATTAGE='1/16W',
 TOLERANCE='1%',
 MATERIAL='CHIP',
 VALUE='33.2',
 PRIM_FILE='./archive_libs/logical/q_res/chips/chips.prt';

PART_NAME
 R3477 'Q_RES_0402LF-33.2,1%,1/16W,CHIA':;

SECTION_NUMBER 1
 '@S9S_MB_2U_LIB.S9S_MB_2U(SCH_1):PAGE314_I26@PURE_QUANTA.Q_RES(CHIPS)':
 C_PATH='@s9s_mb_2u_lib.s9s_mb_2u(sch_1):page314_i26@pure_quanta.q_res(chips)',
 P_PATH='@s9s_mb_2u_lib.s9s_mb_2u(sch_1):page213_i26@pure_quanta.q_res(chips)',
 PATH='I26',
 DRAWING='@S9S_MB_2U_LIB.S9S_MB_2U(SCH_1):PAGE314',
 PHYS_PAGE='213',
 XY='(-2225,-250)',
 ROT='0',
 VER='1',
 PACK_TYPE='0402LF',
 LOCATION='R3477',
 CDS_LIB='pure_quanta',
 CDS_PART_NAME='Q_RES_0402LF-33.2,1%,1/16W,CHIA',
 WATTAGE='1/16W',
 TOLERANCE='1%',
 MATERIAL='CHIP',
 VALUE='33.2',
 PRIM_FILE='./archive_libs/logical/q_res/chips/chips.prt';

PART_NAME
 R3478 'Q_RES_0402LF-33.2,1%,1/16W,CHIA':;

SECTION_NUMBER 1
 '@S9S_MB_2U_LIB.S9S_MB_2U(SCH_1):PAGE314_I23@PURE_QUANTA.Q_RES(CHIPS)':
 C_PATH='@s9s_mb_2u_lib.s9s_mb_2u(sch_1):page314_i23@pure_quanta.q_res(chips)',
 P_PATH='@s9s_mb_2u_lib.s9s_mb_2u(sch_1):page213_i23@pure_quanta.q_res(chips)',
 PATH='I23',
 DRAWING='@S9S_MB_2U_LIB.S9S_MB_2U(SCH_1):PAGE314',
 PHYS_PAGE='213',
 XY='(-2225,-375)',
 ROT='0',
 VER='1',
 PACK_TYPE='0402LF',
 LOCATION='R3478',
 CDS_LIB='pure_quanta',
 CDS_PART_NAME='Q_RES_0402LF-33.2,1%,1/16W,CHIA',
 WATTAGE='1/16W',
 TOLERANCE='1%',
 MATERIAL='CHIP',
 VALUE='33.2',
 PRIM_FILE='./archive_libs/logical/q_res/chips/chips.prt';

PART_NAME
 R3479 'Q_RES_0402LF-33.2,1%,1/16W,CHIA':;

SECTION_NUMBER 1
 '@S9S_MB_2U_LIB.S9S_MB_2U(SCH_1):PAGE314_I24@PURE_QUANTA.Q_RES(CHIPS)':
 C_PATH='@s9s_mb_2u_lib.s9s_mb_2u(sch_1):page314_i24@pure_quanta.q_res(chips)',
 P_PATH='@s9s_mb_2u_lib.s9s_mb_2u(sch_1):page213_i24@pure_quanta.q_res(chips)',
 PATH='I24',
 DRAWING='@S9S_MB_2U_LIB.S9S_MB_2U(SCH_1):PAGE314',
 PHYS_PAGE='213',
 XY='(-2225,-500)',
 ROT='0',
 VER='1',
 PACK_TYPE='0402LF',
 LOCATION='R3479',
 CDS_LIB='pure_quanta',
 CDS_PART_NAME='Q_RES_0402LF-33.2,1%,1/16W,CHIA',
 WATTAGE='1/16W',
 TOLERANCE='1%',
 MATERIAL='CHIP',
 VALUE='33.2',
 PRIM_FILE='./archive_libs/logical/q_res/chips/chips.prt';

PART_NAME
 R3480 'Q_RES_0402LF-33.2,1%,1/16W,CHIA':;

SECTION_NUMBER 1
 '@S9S_MB_2U_LIB.S9S_MB_2U(SCH_1):PAGE314_I21@PURE_QUANTA.Q_RES(CHIPS)':
 C_PATH='@s9s_mb_2u_lib.s9s_mb_2u(sch_1):page314_i21@pure_quanta.q_res(chips)',
 P_PATH='@s9s_mb_2u_lib.s9s_mb_2u(sch_1):page213_i21@pure_quanta.q_res(chips)',
 PATH='I21',
 DRAWING='@S9S_MB_2U_LIB.S9S_MB_2U(SCH_1):PAGE314',
 PHYS_PAGE='213',
 XY='(-2225,-625)',
 ROT='0',
 VER='1',
 PACK_TYPE='0402LF',
 LOCATION='R3480',
 CDS_LIB='pure_quanta',
 CDS_PART_NAME='Q_RES_0402LF-33.2,1%,1/16W,CHIA',
 WATTAGE='1/16W',
 TOLERANCE='1%',
 MATERIAL='CHIP',
 VALUE='33.2',
 PRIM_FILE='./archive_libs/logical/q_res/chips/chips.prt';

PART_NAME
 R3481 'Q_RES_0402LF-33.2,1%,1/16W,CHIA':;

SECTION_NUMBER 1
 '@S9S_MB_2U_LIB.S9S_MB_2U(SCH_1):PAGE314_I22@PURE_QUANTA.Q_RES(CHIPS)':
 C_PATH='@s9s_mb_2u_lib.s9s_mb_2u(sch_1):page314_i22@pure_quanta.q_res(chips)',
 P_PATH='@s9s_mb_2u_lib.s9s_mb_2u(sch_1):page213_i22@pure_quanta.q_res(chips)',
 PATH='I22',
 DRAWING='@S9S_MB_2U_LIB.S9S_MB_2U(SCH_1):PAGE314',
 PHYS_PAGE='213',
 XY='(-2225,-750)',
 ROT='0',
 VER='1',
 PACK_TYPE='0402LF',
 LOCATION='R3481',
 CDS_LIB='pure_quanta',
 CDS_PART_NAME='Q_RES_0402LF-33.2,1%,1/16W,CHIA',
 WATTAGE='1/16W',
 TOLERANCE='1%',
 MATERIAL='CHIP',
 VALUE='33.2',
 PRIM_FILE='./archive_libs/logical/q_res/chips/chips.prt';

PART_NAME
 R3482 'Q_RES_0402LF-33.2,1%,1/16W,CHIA':;

SECTION_NUMBER 1
 '@S9S_MB_2U_LIB.S9S_MB_2U(SCH_1):PAGE314_I19@PURE_QUANTA.Q_RES(CHIPS)':
 C_PATH='@s9s_mb_2u_lib.s9s_mb_2u(sch_1):page314_i19@pure_quanta.q_res(chips)',
 P_PATH='@s9s_mb_2u_lib.s9s_mb_2u(sch_1):page213_i19@pure_quanta.q_res(chips)',
 PATH='I19',
 DRAWING='@S9S_MB_2U_LIB.S9S_MB_2U(SCH_1):PAGE314',
 PHYS_PAGE='213',
 XY='(-2225,-875)',
 ROT='0',
 VER='1',
 PACK_TYPE='0402LF',
 LOCATION='R3482',
 CDS_LIB='pure_quanta',
 CDS_PART_NAME='Q_RES_0402LF-33.2,1%,1/16W,CHIA',
 WATTAGE='1/16W',
 TOLERANCE='1%',
 MATERIAL='CHIP',
 VALUE='33.2',
 PRIM_FILE='./archive_libs/logical/q_res/chips/chips.prt';

PART_NAME
 R3483 'Q_RES_0402LF-33.2,1%,1/16W,CHIA':;

SECTION_NUMBER 1
 '@S9S_MB_2U_LIB.S9S_MB_2U(SCH_1):PAGE314_I20@PURE_QUANTA.Q_RES(CHIPS)':
 C_PATH='@s9s_mb_2u_lib.s9s_mb_2u(sch_1):page314_i20@pure_quanta.q_res(chips)',
 P_PATH='@s9s_mb_2u_lib.s9s_mb_2u(sch_1):page213_i20@pure_quanta.q_res(chips)',
 PATH='I20',
 DRAWING='@S9S_MB_2U_LIB.S9S_MB_2U(SCH_1):PAGE314',
 PHYS_PAGE='213',
 XY='(-2225,-1000)',
 ROT='0',
 VER='1',
 PACK_TYPE='0402LF',
 LOCATION='R3483',
 CDS_LIB='pure_quanta',
 CDS_PART_NAME='Q_RES_0402LF-33.2,1%,1/16W,CHIA',
 WATTAGE='1/16W',
 TOLERANCE='1%',
 MATERIAL='CHIP',
 VALUE='33.2',
 PRIM_FILE='./archive_libs/logical/q_res/chips/chips.prt';

PART_NAME
 R3484 'Q_RES_0402LF-33.2,1%,1/16W,CHIA':;

SECTION_NUMBER 1
 '@S9S_MB_2U_LIB.S9S_MB_2U(SCH_1):PAGE314_I17@PURE_QUANTA.Q_RES(CHIPS)':
 C_PATH='@s9s_mb_2u_lib.s9s_mb_2u(sch_1):page314_i17@pure_quanta.q_res(chips)',
 P_PATH='@s9s_mb_2u_lib.s9s_mb_2u(sch_1):page213_i17@pure_quanta.q_res(chips)',
 PATH='I17',
 DRAWING='@S9S_MB_2U_LIB.S9S_MB_2U(SCH_1):PAGE314',
 PHYS_PAGE='213',
 XY='(-2225,-1125)',
 ROT='0',
 VER='1',
 PACK_TYPE='0402LF',
 LOCATION='R3484',
 CDS_LIB='pure_quanta',
 CDS_PART_NAME='Q_RES_0402LF-33.2,1%,1/16W,CHIA',
 WATTAGE='1/16W',
 TOLERANCE='1%',
 MATERIAL='CHIP',
 VALUE='33.2',
 PRIM_FILE='./archive_libs/logical/q_res/chips/chips.prt';

PART_NAME
 R3485 'Q_RES_0402LF-33.2,1%,1/16W,CHIA':;

SECTION_NUMBER 1
 '@S9S_MB_2U_LIB.S9S_MB_2U(SCH_1):PAGE314_I18@PURE_QUANTA.Q_RES(CHIPS)':
 C_PATH='@s9s_mb_2u_lib.s9s_mb_2u(sch_1):page314_i18@pure_quanta.q_res(chips)',
 P_PATH='@s9s_mb_2u_lib.s9s_mb_2u(sch_1):page213_i18@pure_quanta.q_res(chips)',
 PATH='I18',
 DRAWING='@S9S_MB_2U_LIB.S9S_MB_2U(SCH_1):PAGE314',
 PHYS_PAGE='213',
 XY='(-2225,-1250)',
 ROT='0',
 VER='1',
 PACK_TYPE='0402LF',
 LOCATION='R3485',
 CDS_LIB='pure_quanta',
 CDS_PART_NAME='Q_RES_0402LF-33.2,1%,1/16W,CHIA',
 WATTAGE='1/16W',
 TOLERANCE='1%',
 MATERIAL='CHIP',
 VALUE='33.2',
 PRIM_FILE='./archive_libs/logical/q_res/chips/chips.prt';

PART_NAME
 R3486 'Q_RES_0402LF-33.2,1%,1/16W,CHIA':;

SECTION_NUMBER 1
 '@S9S_MB_2U_LIB.S9S_MB_2U(SCH_1):PAGE314_I15@PURE_QUANTA.Q_RES(CHIPS)':
 C_PATH='@s9s_mb_2u_lib.s9s_mb_2u(sch_1):page314_i15@pure_quanta.q_res(chips)',
 P_PATH='@s9s_mb_2u_lib.s9s_mb_2u(sch_1):page213_i15@pure_quanta.q_res(chips)',
 PATH='I15',
 DRAWING='@S9S_MB_2U_LIB.S9S_MB_2U(SCH_1):PAGE314',
 PHYS_PAGE='213',
 XY='(-2225,-1375)',
 ROT='0',
 VER='1',
 PACK_TYPE='0402LF',
 LOCATION='R3486',
 CDS_LIB='pure_quanta',
 CDS_PART_NAME='Q_RES_0402LF-33.2,1%,1/16W,CHIA',
 WATTAGE='1/16W',
 TOLERANCE='1%',
 MATERIAL='CHIP',
 VALUE='33.2',
 PRIM_FILE='./archive_libs/logical/q_res/chips/chips.prt';

PART_NAME
 R3487 'Q_RES_0402LF-10K,1%,1/16W,CHIPA':;

SECTION_NUMBER 1
 '@S9S_MB_2U_LIB.S9S_MB_2U(SCH_1):PAGE299_I166@PURE_QUANTA.Q_RES(CHIPS)':
 C_PATH='@s9s_mb_2u_lib.s9s_mb_2u(sch_1):page299_i166@pure_quanta.q_res(chips)',
 P_PATH='@s9s_mb_2u_lib.s9s_mb_2u(sch_1):page147_i166@pure_quanta.q_res(chips)',
 PATH='I166',
 DRAWING='@S9S_MB_2U_LIB.S9S_MB_2U(SCH_1):PAGE299',
 PHYS_PAGE='147',
 XY='(1725,2725)',
 ROT='0',
 VER='2',
 PACK_TYPE='0402LF',
 CDS_LIB='pure_quanta',
 CDS_PART_NAME='Q_RES_0402LF-10K,1%,1/16W,CHIPA',
 WATTAGE='1/16W',
 TOLERANCE='1%',
 MATERIAL='CHIP',
 VALUE='10K',
 PRIM_FILE='./archive_libs/logical/q_res/chips/chips.prt';

PART_NAME
 R3488 'Q_RES_0402LF-4.7K,5%,1/16W,CHIA':;

SECTION_NUMBER 1
 '@S9S_MB_2U_LIB.S9S_MB_2U(SCH_1):PAGE296_I40@PURE_QUANTA.Q_RES(CHIPS)':
 C_PATH='@s9s_mb_2u_lib.s9s_mb_2u(sch_1):page296_i40@pure_quanta.q_res(chips)',
 P_PATH='@s9s_mb_2u_lib.s9s_mb_2u(sch_1):page150_i40@pure_quanta.q_res(chips)',
 PATH='I40',
 DRAWING='@S9S_MB_2U_LIB.S9S_MB_2U(SCH_1):PAGE296',
 PHYS_PAGE='150',
 XY='(-650,3425)',
 ROT='0',
 VER='2',
 PACK_TYPE='0402LF',
 CDS_LIB='pure_quanta',
 CDS_PART_NAME='Q_RES_0402LF-4.7K,5%,1/16W,CHIA',
 WATTAGE='1/16W',
 TOLERANCE='5%',
 MATERIAL='CHIP',
 VALUE='4.7K',
 PRIM_FILE='./archive_libs/logical/q_res/chips/chips.prt';

PART_NAME
 R3489 'Q_RES_0402LF-100K,1%,1/16W,EMPA':;

SECTION_NUMBER 1
 '@S9S_MB_2U_LIB.S9S_MB_2U(SCH_1):PAGE296_I42@PURE_QUANTA.Q_RES(CHIPS)':
 C_PATH='@s9s_mb_2u_lib.s9s_mb_2u(sch_1):page296_i42@pure_quanta.q_res(chips)',
 P_PATH='@s9s_mb_2u_lib.s9s_mb_2u(sch_1):page150_i42@pure_quanta.q_res(chips)',
 PATH='I42',
 DRAWING='@S9S_MB_2U_LIB.S9S_MB_2U(SCH_1):PAGE296',
 PHYS_PAGE='150',
 XY='(-625,2950)',
 ROT='0',
 VER='2',
 PACK_TYPE='0402LF',
 CDS_LIB='pure_quanta',
 CDS_PART_NAME='Q_RES_0402LF-100K,1%,1/16W,EMPA',
 WATTAGE='1/16W',
 TOLERANCE='1%',
 MATERIAL='EMPTY',
 VALUE='100K',
 PRIM_FILE='./archive_libs/logical/q_res/chips/chips.prt';

PART_NAME
 R3490 'Q_RES_0402LF-4.7K,5%,1/16W,CHIA':;

SECTION_NUMBER 1
 '@S9S_MB_2U_LIB.S9S_MB_2U(SCH_1):PAGE296_I57@PURE_QUANTA.Q_RES(CHIPS)':
 C_PATH='@s9s_mb_2u_lib.s9s_mb_2u(sch_1):page296_i57@pure_quanta.q_res(chips)',
 P_PATH='@s9s_mb_2u_lib.s9s_mb_2u(sch_1):page150_i57@pure_quanta.q_res(chips)',
 PATH='I57',
 DRAWING='@S9S_MB_2U_LIB.S9S_MB_2U(SCH_1):PAGE296',
 PHYS_PAGE='150',
 XY='(-650,2075)',
 ROT='0',
 VER='2',
 PACK_TYPE='0402LF',
 CDS_LIB='pure_quanta',
 CDS_PART_NAME='Q_RES_0402LF-4.7K,5%,1/16W,CHIA',
 WATTAGE='1/16W',
 TOLERANCE='5%',
 MATERIAL='CHIP',
 VALUE='4.7K',
 PRIM_FILE='./archive_libs/logical/q_res/chips/chips.prt';

PART_NAME
 R3491 'Q_RES_0402LF-100K,1%,1/16W,EMPA':;

SECTION_NUMBER 1
 '@S9S_MB_2U_LIB.S9S_MB_2U(SCH_1):PAGE296_I70@PURE_QUANTA.Q_RES(CHIPS)':
 C_PATH='@s9s_mb_2u_lib.s9s_mb_2u(sch_1):page296_i70@pure_quanta.q_res(chips)',
 P_PATH='@s9s_mb_2u_lib.s9s_mb_2u(sch_1):page150_i70@pure_quanta.q_res(chips)',
 PATH='I70',
 DRAWING='@S9S_MB_2U_LIB.S9S_MB_2U(SCH_1):PAGE296',
 PHYS_PAGE='150',
 XY='(-600,1600)',
 ROT='0',
 VER='2',
 PACK_TYPE='0402LF',
 CDS_LIB='pure_quanta',
 CDS_PART_NAME='Q_RES_0402LF-100K,1%,1/16W,EMPA',
 WATTAGE='1/16W',
 TOLERANCE='1%',
 MATERIAL='EMPTY',
 VALUE='100K',
 PRIM_FILE='./archive_libs/logical/q_res/chips/chips.prt';

PART_NAME
 R3492 'Q_RES_0402LF-54.9K,1%,1/16W,CHA':;

SECTION_NUMBER 1
 '@S9S_MB_2U_LIB.S9S_MB_2U(SCH_1):PAGE296_I47@PURE_QUANTA.Q_RES(CHIPS)':
 C_PATH='@s9s_mb_2u_lib.s9s_mb_2u(sch_1):page296_i47@pure_quanta.q_res(chips)',
 P_PATH='@s9s_mb_2u_lib.s9s_mb_2u(sch_1):page150_i47@pure_quanta.q_res(chips)',
 PATH='I47',
 DRAWING='@S9S_MB_2U_LIB.S9S_MB_2U(SCH_1):PAGE296',
 PHYS_PAGE='150',
 XY='(1900,3400)',
 ROT='0',
 VER='2',
 PACK_TYPE='0402LF',
 CDS_LIB='pure_quanta',
 CDS_PART_NAME='Q_RES_0402LF-54.9K,1%,1/16W,CHA',
 WATTAGE='1/16W',
 TOLERANCE='1%',
 MATERIAL='CHIP',
 VALUE='54.9K',
 PRIM_FILE='./archive_libs/logical/q_res/chips/chips.prt';

PART_NAME
 R3493 'Q_RES_0402LF-100K,1%,1/16W,EMPA':;

SECTION_NUMBER 1
 '@S9S_MB_2U_LIB.S9S_MB_2U(SCH_1):PAGE296_I48@PURE_QUANTA.Q_RES(CHIPS)':
 C_PATH='@s9s_mb_2u_lib.s9s_mb_2u(sch_1):page296_i48@pure_quanta.q_res(chips)',
 P_PATH='@s9s_mb_2u_lib.s9s_mb_2u(sch_1):page150_i48@pure_quanta.q_res(chips)',
 PATH='I48',
 DRAWING='@S9S_MB_2U_LIB.S9S_MB_2U(SCH_1):PAGE296',
 PHYS_PAGE='150',
 XY='(1925,2800)',
 ROT='0',
 VER='2',
 PACK_TYPE='0402LF',
 CDS_LIB='pure_quanta',
 CDS_PART_NAME='Q_RES_0402LF-100K,1%,1/16W,EMPA',
 WATTAGE='1/16W',
 TOLERANCE='1%',
 MATERIAL='EMPTY',
 VALUE='100K',
 PRIM_FILE='./archive_libs/logical/q_res/chips/chips.prt';

PART_NAME
 R3494 'Q_RES_0402LF-54.9K,1%,1/16W,CHA':;

SECTION_NUMBER 1
 '@S9S_MB_2U_LIB.S9S_MB_2U(SCH_1):PAGE296_I55@PURE_QUANTA.Q_RES(CHIPS)':
 C_PATH='@s9s_mb_2u_lib.s9s_mb_2u(sch_1):page296_i55@pure_quanta.q_res(chips)',
 P_PATH='@s9s_mb_2u_lib.s9s_mb_2u(sch_1):page150_i55@pure_quanta.q_res(chips)',
 PATH='I55',
 DRAWING='@S9S_MB_2U_LIB.S9S_MB_2U(SCH_1):PAGE296',
 PHYS_PAGE='150',
 XY='(2075,2100)',
 ROT='0',
 VER='2',
 PACK_TYPE='0402LF',
 CDS_LIB='pure_quanta',
 CDS_PART_NAME='Q_RES_0402LF-54.9K,1%,1/16W,CHA',
 WATTAGE='1/16W',
 TOLERANCE='1%',
 MATERIAL='CHIP',
 VALUE='54.9K',
 PRIM_FILE='./archive_libs/logical/q_res/chips/chips.prt';

PART_NAME
 R3495 'Q_RES_0402LF-100K,1%,1/16W,EMPA':;

SECTION_NUMBER 1
 '@S9S_MB_2U_LIB.S9S_MB_2U(SCH_1):PAGE296_I62@PURE_QUANTA.Q_RES(CHIPS)':
 C_PATH='@s9s_mb_2u_lib.s9s_mb_2u(sch_1):page296_i62@pure_quanta.q_res(chips)',
 P_PATH='@s9s_mb_2u_lib.s9s_mb_2u(sch_1):page150_i62@pure_quanta.q_res(chips)',
 PATH='I62',
 DRAWING='@S9S_MB_2U_LIB.S9S_MB_2U(SCH_1):PAGE296',
 PHYS_PAGE='150',
 XY='(2100,1500)',
 ROT='0',
 VER='2',
 PACK_TYPE='0402LF',
 CDS_LIB='pure_quanta',
 CDS_PART_NAME='Q_RES_0402LF-100K,1%,1/16W,EMPA',
 WATTAGE='1/16W',
 TOLERANCE='1%',
 MATERIAL='EMPTY',
 VALUE='100K',
 PRIM_FILE='./archive_libs/logical/q_res/chips/chips.prt';

PART_NAME
 R3496 'Q_RES_0402LF-33.2,1%,1/16W,CHIA':;

SECTION_NUMBER 1
 '@S9S_MB_2U_LIB.S9S_MB_2U(SCH_1):PAGE296_I45@PURE_QUANTA.Q_RES(CHIPS)':
 C_PATH='@s9s_mb_2u_lib.s9s_mb_2u(sch_1):page296_i45@pure_quanta.q_res(chips)',
 P_PATH='@s9s_mb_2u_lib.s9s_mb_2u(sch_1):page150_i45@pure_quanta.q_res(chips)',
 PATH='I45',
 DRAWING='@S9S_MB_2U_LIB.S9S_MB_2U(SCH_1):PAGE296',
 PHYS_PAGE='150',
 XY='(2150,3100)',
 ROT='0',
 VER='1',
 PACK_TYPE='0402LF',
 CDS_LIB='pure_quanta',
 CDS_PART_NAME='Q_RES_0402LF-33.2,1%,1/16W,CHIA',
 WATTAGE='1/16W',
 TOLERANCE='1%',
 MATERIAL='CHIP',
 VALUE='33.2',
 PRIM_FILE='./archive_libs/logical/q_res/chips/chips.prt';

PART_NAME
 R3497 'Q_RES_0402LF-33.2,1%,1/16W,CHIA':;

SECTION_NUMBER 1
 '@S9S_MB_2U_LIB.S9S_MB_2U(SCH_1):PAGE296_I53@PURE_QUANTA.Q_RES(CHIPS)':
 C_PATH='@s9s_mb_2u_lib.s9s_mb_2u(sch_1):page296_i53@pure_quanta.q_res(chips)',
 P_PATH='@s9s_mb_2u_lib.s9s_mb_2u(sch_1):page150_i53@pure_quanta.q_res(chips)',
 PATH='I53',
 DRAWING='@S9S_MB_2U_LIB.S9S_MB_2U(SCH_1):PAGE296',
 PHYS_PAGE='150',
 XY='(2325,1800)',
 ROT='0',
 VER='1',
 PACK_TYPE='0402LF',
 CDS_LIB='pure_quanta',
 CDS_PART_NAME='Q_RES_0402LF-33.2,1%,1/16W,CHIA',
 WATTAGE='1/16W',
 TOLERANCE='1%',
 MATERIAL='CHIP',
 VALUE='33.2',
 PRIM_FILE='./archive_libs/logical/q_res/chips/chips.prt';

PART_NAME
 R3498 'Q_RES_0402LF-54.9K,1%,1/16W,CHA':;

SECTION_NUMBER 1
 '@S9S_MB_2U_LIB.S9S_MB_2U(SCH_1):PAGE299_I167@PURE_QUANTA.Q_RES(CHIPS)':
 C_PATH='@s9s_mb_2u_lib.s9s_mb_2u(sch_1):page299_i167@pure_quanta.q_res(chips)',
 P_PATH='@s9s_mb_2u_lib.s9s_mb_2u(sch_1):page147_i167@pure_quanta.q_res(chips)',
 PATH='I167',
 DRAWING='@S9S_MB_2U_LIB.S9S_MB_2U(SCH_1):PAGE299',
 PHYS_PAGE='147',
 XY='(-3000,4000)',
 ROT='0',
 VER='2',
 PACK_TYPE='0402LF',
 CDS_LIB='pure_quanta',
 CDS_PART_NAME='Q_RES_0402LF-54.9K,1%,1/16W,CHA',
 WATTAGE='1/16W',
 TOLERANCE='1%',
 MATERIAL='CHIP',
 VALUE='54.9K',
 PRIM_FILE='./archive_libs/logical/q_res/chips/chips.prt';

PART_NAME
 R3499 'Q_RES_0402LF-0,5%,1/16W,CHIP,CA':;

SECTION_NUMBER 1
 '@S9S_MB_2U_LIB.S9S_MB_2U(SCH_1):PAGE214_I118@PURE_QUANTA.Q_RES(CHIPS)':
 C_PATH='@s9s_mb_2u_lib.s9s_mb_2u(sch_1):page214_i118@pure_quanta.q_res(chips)',
 P_PATH='@s9s_mb_2u_lib.s9s_mb_2u(sch_1):page227_i118@pure_quanta.q_res(chips)',
 PATH='I118',
 DRAWING='@S9S_MB_2U_LIB.S9S_MB_2U(SCH_1):PAGE214',
 PHYS_PAGE='227',
 XY='(8675,3125)',
 ROT='0',
 VER='1',
 PACK_TYPE='0402LF',
 CDS_LIB='pure_quanta',
 CDS_PART_NAME='Q_RES_0402LF-0,5%,1/16W,CHIP,CA',
 WATTAGE='1/16W',
 TOLERANCE='5%',
 MATERIAL='CHIP',
 VALUE='0',
 PRIM_FILE='./archive_libs/logical/q_res/chips/chips.prt';

PART_NAME
 R3500 'Q_RES_0402LF-4.7K,5%,1/16W,CHIA':;

SECTION_NUMBER 1
 '@S9S_MB_2U_LIB.S9S_MB_2U(SCH_1):PAGE216_I31@PURE_QUANTA.Q_RES(CHIPS)':
 C_PATH='@s9s_mb_2u_lib.s9s_mb_2u(sch_1):page216_i31@pure_quanta.q_res(chips)',
 P_PATH='@s9s_mb_2u_lib.s9s_mb_2u(sch_1):page238_i31@pure_quanta.q_res(chips)',
 PATH='I31',
 DRAWING='@S9S_MB_2U_LIB.S9S_MB_2U(SCH_1):PAGE216',
 PHYS_PAGE='238',
 XY='(-5400,5675)',
 ROT='0',
 VER='2',
 PACK_TYPE='0402LF',
 CDS_LIB='pure_quanta',
 CDS_PART_NAME='Q_RES_0402LF-4.7K,5%,1/16W,CHIA',
 WATTAGE='1/16W',
 TOLERANCE='5%',
 MATERIAL='CHIP',
 VALUE='4.7K',
 PRIM_FILE='./archive_libs/logical/q_res/chips/chips.prt';

PART_NAME
 R3501 'Q_RES_0402LF-4.7K,5%,1/16W,CHIA':;

SECTION_NUMBER 1
 '@S9S_MB_2U_LIB.S9S_MB_2U(SCH_1):PAGE216_I30@PURE_QUANTA.Q_RES(CHIPS)':
 C_PATH='@s9s_mb_2u_lib.s9s_mb_2u(sch_1):page216_i30@pure_quanta.q_res(chips)',
 P_PATH='@s9s_mb_2u_lib.s9s_mb_2u(sch_1):page238_i30@pure_quanta.q_res(chips)',
 PATH='I30',
 DRAWING='@S9S_MB_2U_LIB.S9S_MB_2U(SCH_1):PAGE216',
 PHYS_PAGE='238',
 XY='(-5150,5675)',
 ROT='0',
 VER='2',
 PACK_TYPE='0402LF',
 CDS_LIB='pure_quanta',
 CDS_PART_NAME='Q_RES_0402LF-4.7K,5%,1/16W,CHIA',
 WATTAGE='1/16W',
 TOLERANCE='5%',
 MATERIAL='CHIP',
 VALUE='4.7K',
 PRIM_FILE='./archive_libs/logical/q_res/chips/chips.prt';

PART_NAME
 R3502 'Q_RES_0402LF-100K,1%,1/16W,EMPA':;

SECTION_NUMBER 1
 '@S9S_MB_2U_LIB.S9S_MB_2U(SCH_1):PAGE299_I181@PURE_QUANTA.Q_RES(CHIPS)':
 C_PATH='@s9s_mb_2u_lib.s9s_mb_2u(sch_1):page299_i181@pure_quanta.q_res(chips)',
 P_PATH='@s9s_mb_2u_lib.s9s_mb_2u(sch_1):page147_i181@pure_quanta.q_res(chips)',
 PATH='I181',
 DRAWING='@S9S_MB_2U_LIB.S9S_MB_2U(SCH_1):PAGE299',
 PHYS_PAGE='147',
 XY='(1725,675)',
 ROT='0',
 VER='2',
 PACK_TYPE='0402LF',
 CDS_LIB='pure_quanta',
 CDS_PART_NAME='Q_RES_0402LF-100K,1%,1/16W,EMPA',
 WATTAGE='1/16W',
 TOLERANCE='1%',
 MATERIAL='EMPTY',
 VALUE='100K',
 PRIM_FILE='./archive_libs/logical/q_res/chips/chips.prt';

PART_NAME
 R3503 'Q_RES_0402LF-4.7K,5%,1/16W,CHIA':;

SECTION_NUMBER 1
 '@S9S_MB_2U_LIB.S9S_MB_2U(SCH_1):PAGE299_I177@PURE_QUANTA.Q_RES(CHIPS)':
 C_PATH='@s9s_mb_2u_lib.s9s_mb_2u(sch_1):page299_i177@pure_quanta.q_res(chips)',
 P_PATH='@s9s_mb_2u_lib.s9s_mb_2u(sch_1):page147_i177@pure_quanta.q_res(chips)',
 PATH='I177',
 DRAWING='@S9S_MB_2U_LIB.S9S_MB_2U(SCH_1):PAGE299',
 PHYS_PAGE='147',
 XY='(2950,1400)',
 ROT='0',
 VER='2',
 PACK_TYPE='0402LF',
 CDS_LIB='pure_quanta',
 CDS_PART_NAME='Q_RES_0402LF-4.7K,5%,1/16W,CHIA',
 WATTAGE='1/16W',
 TOLERANCE='5%',
 MATERIAL='CHIP',
 VALUE='4.7K',
 PRIM_FILE='./archive_libs/logical/q_res/chips/chips.prt';

PART_NAME
 R3504 'Q_RES_0402LF-4.7K,5%,1/16W,CHIA':;

SECTION_NUMBER 1
 '@S9S_MB_2U_LIB.S9S_MB_2U(SCH_1):PAGE299_I174@PURE_QUANTA.Q_RES(CHIPS)':
 C_PATH='@s9s_mb_2u_lib.s9s_mb_2u(sch_1):page299_i174@pure_quanta.q_res(chips)',
 P_PATH='@s9s_mb_2u_lib.s9s_mb_2u(sch_1):page147_i174@pure_quanta.q_res(chips)',
 PATH='I174',
 DRAWING='@S9S_MB_2U_LIB.S9S_MB_2U(SCH_1):PAGE299',
 PHYS_PAGE='147',
 XY='(3875,1650)',
 ROT='0',
 VER='2',
 PACK_TYPE='0402LF',
 CDS_LIB='pure_quanta',
 CDS_PART_NAME='Q_RES_0402LF-4.7K,5%,1/16W,CHIA',
 WATTAGE='1/16W',
 TOLERANCE='5%',
 MATERIAL='CHIP',
 VALUE='4.7K',
 PRIM_FILE='./archive_libs/logical/q_res/chips/chips.prt';

PART_NAME
 R3505 'Q_RES_0402LF-33.2,1%,1/16W,CHIA':;

SECTION_NUMBER 1
 '@S9S_MB_2U_LIB.S9S_MB_2U(SCH_1):PAGE314_I16@PURE_QUANTA.Q_RES(CHIPS)':
 C_PATH='@s9s_mb_2u_lib.s9s_mb_2u(sch_1):page314_i16@pure_quanta.q_res(chips)',
 P_PATH='@s9s_mb_2u_lib.s9s_mb_2u(sch_1):page213_i16@pure_quanta.q_res(chips)',
 PATH='I16',
 DRAWING='@S9S_MB_2U_LIB.S9S_MB_2U(SCH_1):PAGE314',
 PHYS_PAGE='213',
 XY='(-2225,-1500)',
 ROT='0',
 VER='1',
 PACK_TYPE='0402LF',
 LOCATION='R3505',
 CDS_LIB='pure_quanta',
 CDS_PART_NAME='Q_RES_0402LF-33.2,1%,1/16W,CHIA',
 WATTAGE='1/16W',
 TOLERANCE='1%',
 MATERIAL='CHIP',
 VALUE='33.2',
 PRIM_FILE='./archive_libs/logical/q_res/chips/chips.prt';

PART_NAME
 R3506 'Q_RES_0402LF-4.7K,5%,1/16W,EMPA':;

SECTION_NUMBER 1
 '@S9S_MB_2U_LIB.S9S_MB_2U(SCH_1):PAGE140_I193@PURE_QUANTA.Q_RES(CHIPS)':
 C_PATH='@s9s_mb_2u_lib.s9s_mb_2u(sch_1):page140_i193@pure_quanta.q_res(chips)',
 P_PATH='@s9s_mb_2u_lib.s9s_mb_2u(sch_1):page151_i193@pure_quanta.q_res(chips)',
 PATH='I193',
 DRAWING='@S9S_MB_2U_LIB.S9S_MB_2U(SCH_1):PAGE140',
 PHYS_PAGE='151',
 XY='(0,-250)',
 ROT='0',
 VER='2',
 PACK_TYPE='0402LF',
 CDS_LIB='pure_quanta',
 CDS_PART_NAME='Q_RES_0402LF-4.7K,5%,1/16W,EMPA',
 WATTAGE='1/16W',
 TOLERANCE='5%',
 MATERIAL='EMPTY',
 VALUE='4.7K',
 PRIM_FILE='./archive_libs/logical/q_res/chips/chips.prt';

PART_NAME
 R3507 'Q_RES_0402LF-10K,1%,1/16W,CHIPA':;

SECTION_NUMBER 1
 '@S9S_MB_2U_LIB.S9S_MB_2U(SCH_1):PAGE140_I192@PURE_QUANTA.Q_RES(CHIPS)':
 C_PATH='@s9s_mb_2u_lib.s9s_mb_2u(sch_1):page140_i192@pure_quanta.q_res(chips)',
 P_PATH='@s9s_mb_2u_lib.s9s_mb_2u(sch_1):page151_i192@pure_quanta.q_res(chips)',
 PATH='I192',
 DRAWING='@S9S_MB_2U_LIB.S9S_MB_2U(SCH_1):PAGE140',
 PHYS_PAGE='151',
 XY='(25,-725)',
 ROT='0',
 VER='2',
 PACK_TYPE='0402LF',
 CDS_LIB='pure_quanta',
 CDS_PART_NAME='Q_RES_0402LF-10K,1%,1/16W,CHIPA',
 WATTAGE='1/16W',
 TOLERANCE='1%',
 MATERIAL='CHIP',
 VALUE='10K',
 PRIM_FILE='./archive_libs/logical/q_res/chips/chips.prt';

PART_NAME
 R3508 'Q_RES_0402LF-54.9K,1%,1/16W,CHA':;

SECTION_NUMBER 1
 '@S9S_MB_2U_LIB.S9S_MB_2U(SCH_1):PAGE140_I194@PURE_QUANTA.Q_RES(CHIPS)':
 C_PATH='@s9s_mb_2u_lib.s9s_mb_2u(sch_1):page140_i194@pure_quanta.q_res(chips)',
 P_PATH='@s9s_mb_2u_lib.s9s_mb_2u(sch_1):page151_i194@pure_quanta.q_res(chips)',
 PATH='I194',
 DRAWING='@S9S_MB_2U_LIB.S9S_MB_2U(SCH_1):PAGE140',
 PHYS_PAGE='151',
 XY='(2625,325)',
 ROT='0',
 VER='2',
 PACK_TYPE='0402LF',
 CDS_LIB='pure_quanta',
 CDS_PART_NAME='Q_RES_0402LF-54.9K,1%,1/16W,CHA',
 WATTAGE='1/16W',
 TOLERANCE='1%',
 MATERIAL='CHIP',
 VALUE='54.9K',
 PRIM_FILE='./archive_libs/logical/q_res/chips/chips.prt';

PART_NAME
 R3509 'Q_RES_0402LF-10K,1%,1/16W,CHIPA':;

SECTION_NUMBER 1
 '@S9S_MB_2U_LIB.S9S_MB_2U(SCH_1):PAGE140_I191@PURE_QUANTA.Q_RES(CHIPS)':
 C_PATH='@s9s_mb_2u_lib.s9s_mb_2u(sch_1):page140_i191@pure_quanta.q_res(chips)',
 P_PATH='@s9s_mb_2u_lib.s9s_mb_2u(sch_1):page151_i191@pure_quanta.q_res(chips)',
 PATH='I191',
 DRAWING='@S9S_MB_2U_LIB.S9S_MB_2U(SCH_1):PAGE140',
 PHYS_PAGE='151',
 XY='(2650,-800)',
 ROT='0',
 VER='2',
 PACK_TYPE='0402LF',
 CDS_LIB='pure_quanta',
 CDS_PART_NAME='Q_RES_0402LF-10K,1%,1/16W,CHIPA',
 WATTAGE='1/16W',
 TOLERANCE='1%',
 MATERIAL='CHIP',
 VALUE='10K',
 PRIM_FILE='./archive_libs/logical/q_res/chips/chips.prt';

PART_NAME
 R3510 'Q_RES_0402LF-54.9K,1%,1/16W,CHA':;

SECTION_NUMBER 1
 '@S9S_MB_2U_LIB.S9S_MB_2U(SCH_1):PAGE145_I176@PURE_QUANTA.Q_RES(CHIPS)':
 C_PATH='@s9s_mb_2u_lib.s9s_mb_2u(sch_1):page145_i176@pure_quanta.q_res(chips)',
 P_PATH='@s9s_mb_2u_lib.s9s_mb_2u(sch_1):page148_i176@pure_quanta.q_res(chips)',
 PATH='I176',
 DRAWING='@S9S_MB_2U_LIB.S9S_MB_2U(SCH_1):PAGE145',
 PHYS_PAGE='148',
 XY='(-4675,3250)',
 ROT='0',
 VER='2',
 PACK_TYPE='0402LF',
 CDS_LIB='pure_quanta',
 CDS_PART_NAME='Q_RES_0402LF-54.9K,1%,1/16W,CHA',
 WATTAGE='1/16W',
 TOLERANCE='1%',
 MATERIAL='CHIP',
 VALUE='54.9K',
 PRIM_FILE='./archive_libs/logical/q_res/chips/chips.prt';

PART_NAME
 R3511 'Q_RES_0402LF-54.9K,1%,1/16W,CHA':;

SECTION_NUMBER 1
 '@S9S_MB_2U_LIB.S9S_MB_2U(SCH_1):PAGE145_I172@PURE_QUANTA.Q_RES(CHIPS)':
 C_PATH='@s9s_mb_2u_lib.s9s_mb_2u(sch_1):page145_i172@pure_quanta.q_res(chips)',
 P_PATH='@s9s_mb_2u_lib.s9s_mb_2u(sch_1):page148_i172@pure_quanta.q_res(chips)',
 PATH='I172',
 DRAWING='@S9S_MB_2U_LIB.S9S_MB_2U(SCH_1):PAGE145',
 PHYS_PAGE='148',
 XY='(-150,2975)',
 ROT='0',
 VER='2',
 PACK_TYPE='0402LF',
 CDS_LIB='pure_quanta',
 CDS_PART_NAME='Q_RES_0402LF-54.9K,1%,1/16W,CHA',
 WATTAGE='1/16W',
 TOLERANCE='1%',
 MATERIAL='CHIP',
 VALUE='54.9K',
 PRIM_FILE='./archive_libs/logical/q_res/chips/chips.prt';

PART_NAME
 R3512 'Q_RES_0402LF-100K,1%,1/16W,EMPA':;

SECTION_NUMBER 1
 '@S9S_MB_2U_LIB.S9S_MB_2U(SCH_1):PAGE145_I174@PURE_QUANTA.Q_RES(CHIPS)':
 C_PATH='@s9s_mb_2u_lib.s9s_mb_2u(sch_1):page145_i174@pure_quanta.q_res(chips)',
 P_PATH='@s9s_mb_2u_lib.s9s_mb_2u(sch_1):page148_i174@pure_quanta.q_res(chips)',
 PATH='I174',
 DRAWING='@S9S_MB_2U_LIB.S9S_MB_2U(SCH_1):PAGE145',
 PHYS_PAGE='148',
 XY='(-150,6325)',
 ROT='0',
 VER='2',
 PACK_TYPE='0402LF',
 CDS_LIB='pure_quanta',
 CDS_PART_NAME='Q_RES_0402LF-100K,1%,1/16W,EMPA',
 WATTAGE='1/16W',
 TOLERANCE='1%',
 MATERIAL='EMPTY',
 VALUE='100K',
 PRIM_FILE='./archive_libs/logical/q_res/chips/chips.prt';

PART_NAME
 R3513 'Q_RES_0402LF-54.9K,1%,1/16W,CHA':;

SECTION_NUMBER 1
 '@S9S_MB_2U_LIB.S9S_MB_2U(SCH_1):PAGE145_I173@PURE_QUANTA.Q_RES(CHIPS)':
 C_PATH='@s9s_mb_2u_lib.s9s_mb_2u(sch_1):page145_i173@pure_quanta.q_res(chips)',
 P_PATH='@s9s_mb_2u_lib.s9s_mb_2u(sch_1):page148_i173@pure_quanta.q_res(chips)',
 PATH='I173',
 DRAWING='@S9S_MB_2U_LIB.S9S_MB_2U(SCH_1):PAGE145',
 PHYS_PAGE='148',
 XY='(-125,5900)',
 ROT='0',
 VER='2',
 PACK_TYPE='0402LF',
 CDS_LIB='pure_quanta',
 CDS_PART_NAME='Q_RES_0402LF-54.9K,1%,1/16W,CHA',
 WATTAGE='1/16W',
 TOLERANCE='1%',
 MATERIAL='CHIP',
 VALUE='54.9K',
 PRIM_FILE='./archive_libs/logical/q_res/chips/chips.prt';

PART_NAME
 R3514 'Q_RES_0402LF-54.9K,1%,1/16W,CHA':;

SECTION_NUMBER 1
 '@S9S_MB_2U_LIB.S9S_MB_2U(SCH_1):PAGE145_I175@PURE_QUANTA.Q_RES(CHIPS)':
 C_PATH='@s9s_mb_2u_lib.s9s_mb_2u(sch_1):page145_i175@pure_quanta.q_res(chips)',
 P_PATH='@s9s_mb_2u_lib.s9s_mb_2u(sch_1):page148_i175@pure_quanta.q_res(chips)',
 PATH='I175',
 DRAWING='@S9S_MB_2U_LIB.S9S_MB_2U(SCH_1):PAGE145',
 PHYS_PAGE='148',
 XY='(-125,4950)',
 ROT='0',
 VER='2',
 PACK_TYPE='0402LF',
 CDS_LIB='pure_quanta',
 CDS_PART_NAME='Q_RES_0402LF-54.9K,1%,1/16W,CHA',
 WATTAGE='1/16W',
 TOLERANCE='1%',
 MATERIAL='CHIP',
 VALUE='54.9K',
 PRIM_FILE='./archive_libs/logical/q_res/chips/chips.prt';

PART_NAME
 R3515 'Q_RES_0402LF-49.9,1%,1/16W,CHIA':;

SECTION_NUMBER 1
 '@S9S_MB_2U_LIB.S9S_MB_2U(SCH_1):PAGE160_I198@PURE_QUANTA.Q_RES(CHIPS)':
 C_PATH='@s9s_mb_2u_lib.s9s_mb_2u(sch_1):page160_i198@pure_quanta.q_res(chips)',
 P_PATH='@s9s_mb_2u_lib.s9s_mb_2u(sch_1):page149_i198@pure_quanta.q_res(chips)',
 PATH='I198',
 DRAWING='@S9S_MB_2U_LIB.S9S_MB_2U(SCH_1):PAGE160',
 PHYS_PAGE='149',
 XY='(-3875,-525)',
 ROT='0',
 VER='1',
 PACK_TYPE='0402LF',
 LOCATION='R3515',
 CDS_LIB='pure_quanta',
 CDS_PART_NAME='Q_RES_0402LF-49.9,1%,1/16W,CHIA',
 WATTAGE='1/16W',
 TOLERANCE='1%',
 MATERIAL='CHIP',
 VALUE='49.9',
 PRIM_FILE='./archive_libs/logical/q_res/chips/chips.prt';

PART_NAME
 R3516 'Q_RES_0402LF-0,5%,1/16W,CHIP,CA':;

SECTION_NUMBER 1
 '@S9S_MB_2U_LIB.S9S_MB_2U(SCH_1):PAGE214_I127@PURE_QUANTA.Q_RES(CHIPS)':
 C_PATH='@s9s_mb_2u_lib.s9s_mb_2u(sch_1):page214_i127@pure_quanta.q_res(chips)',
 P_PATH='@s9s_mb_2u_lib.s9s_mb_2u(sch_1):page227_i127@pure_quanta.q_res(chips)',
 PATH='I127',
 DRAWING='@S9S_MB_2U_LIB.S9S_MB_2U(SCH_1):PAGE214',
 PHYS_PAGE='227',
 XY='(8675,2925)',
 ROT='0',
 VER='1',
 PACK_TYPE='0402LF',
 CDS_LIB='pure_quanta',
 CDS_PART_NAME='Q_RES_0402LF-0,5%,1/16W,CHIP,CA',
 WATTAGE='1/16W',
 TOLERANCE='5%',
 MATERIAL='CHIP',
 VALUE='0',
 PRIM_FILE='./archive_libs/logical/q_res/chips/chips.prt';

PART_NAME
 R3517 'Q_RES_0402LF-0,5%,1/16W,CHIP,CA':;

SECTION_NUMBER 1
 '@S9S_MB_2U_LIB.S9S_MB_2U(SCH_1):PAGE214_I128@PURE_QUANTA.Q_RES(CHIPS)':
 C_PATH='@s9s_mb_2u_lib.s9s_mb_2u(sch_1):page214_i128@pure_quanta.q_res(chips)',
 P_PATH='@s9s_mb_2u_lib.s9s_mb_2u(sch_1):page227_i128@pure_quanta.q_res(chips)',
 PATH='I128',
 DRAWING='@S9S_MB_2U_LIB.S9S_MB_2U(SCH_1):PAGE214',
 PHYS_PAGE='227',
 XY='(8675,2725)',
 ROT='0',
 VER='1',
 PACK_TYPE='0402LF',
 CDS_LIB='pure_quanta',
 CDS_PART_NAME='Q_RES_0402LF-0,5%,1/16W,CHIP,CA',
 WATTAGE='1/16W',
 TOLERANCE='5%',
 MATERIAL='CHIP',
 VALUE='0',
 PRIM_FILE='./archive_libs/logical/q_res/chips/chips.prt';

PART_NAME
 R3518 'Q_RES_0402LF-0,5%,1/16W,CHIP,CA':;

SECTION_NUMBER 1
 '@S9S_MB_2U_LIB.S9S_MB_2U(SCH_1):PAGE214_I129@PURE_QUANTA.Q_RES(CHIPS)':
 C_PATH='@s9s_mb_2u_lib.s9s_mb_2u(sch_1):page214_i129@pure_quanta.q_res(chips)',
 P_PATH='@s9s_mb_2u_lib.s9s_mb_2u(sch_1):page227_i129@pure_quanta.q_res(chips)',
 PATH='I129',
 DRAWING='@S9S_MB_2U_LIB.S9S_MB_2U(SCH_1):PAGE214',
 PHYS_PAGE='227',
 XY='(8675,2525)',
 ROT='0',
 VER='1',
 PACK_TYPE='0402LF',
 CDS_LIB='pure_quanta',
 CDS_PART_NAME='Q_RES_0402LF-0,5%,1/16W,CHIP,CA',
 WATTAGE='1/16W',
 TOLERANCE='5%',
 MATERIAL='CHIP',
 VALUE='0',
 PRIM_FILE='./archive_libs/logical/q_res/chips/chips.prt';

PART_NAME
 R3519 'Q_RES_0402LF-4.7K,5%,1/16W,CHIA':;

SECTION_NUMBER 1
 '@S9S_MB_2U_LIB.S9S_MB_2U(SCH_1):PAGE216_I34@PURE_QUANTA.Q_RES(CHIPS)':
 C_PATH='@s9s_mb_2u_lib.s9s_mb_2u(sch_1):page216_i34@pure_quanta.q_res(chips)',
 P_PATH='@s9s_mb_2u_lib.s9s_mb_2u(sch_1):page238_i34@pure_quanta.q_res(chips)',
 PATH='I34',
 DRAWING='@S9S_MB_2U_LIB.S9S_MB_2U(SCH_1):PAGE216',
 PHYS_PAGE='238',
 XY='(-5575,3850)',
 ROT='0',
 VER='2',
 PACK_TYPE='0402LF',
 CDS_LIB='pure_quanta',
 CDS_PART_NAME='Q_RES_0402LF-4.7K,5%,1/16W,CHIA',
 WATTAGE='1/16W',
 TOLERANCE='5%',
 MATERIAL='CHIP',
 VALUE='4.7K',
 PRIM_FILE='./archive_libs/logical/q_res/chips/chips.prt';

PART_NAME
 R3520 'Q_RES_0402LF-4.7K,5%,1/16W,CHIA':;

SECTION_NUMBER 1
 '@S9S_MB_2U_LIB.S9S_MB_2U(SCH_1):PAGE216_I33@PURE_QUANTA.Q_RES(CHIPS)':
 C_PATH='@s9s_mb_2u_lib.s9s_mb_2u(sch_1):page216_i33@pure_quanta.q_res(chips)',
 P_PATH='@s9s_mb_2u_lib.s9s_mb_2u(sch_1):page238_i33@pure_quanta.q_res(chips)',
 PATH='I33',
 DRAWING='@S9S_MB_2U_LIB.S9S_MB_2U(SCH_1):PAGE216',
 PHYS_PAGE='238',
 XY='(-5325,3850)',
 ROT='0',
 VER='2',
 PACK_TYPE='0402LF',
 CDS_LIB='pure_quanta',
 CDS_PART_NAME='Q_RES_0402LF-4.7K,5%,1/16W,CHIA',
 WATTAGE='1/16W',
 TOLERANCE='5%',
 MATERIAL='CHIP',
 VALUE='4.7K',
 PRIM_FILE='./archive_libs/logical/q_res/chips/chips.prt';

PART_NAME
 R3521 'Q_RES_0402LF-54.9K,1%,1/16W,CHA':;

SECTION_NUMBER 1
 '@S9S_MB_2U_LIB.S9S_MB_2U(SCH_1):PAGE222_I23@PURE_QUANTA.Q_RES(CHIPS)':
 C_PATH='@s9s_mb_2u_lib.s9s_mb_2u(sch_1):page222_i23@pure_quanta.q_res(chips)',
 P_PATH='@s9s_mb_2u_lib.s9s_mb_2u(sch_1):page234_i23@pure_quanta.q_res(chips)',
 PATH='I23',
 DRAWING='@S9S_MB_2U_LIB.S9S_MB_2U(SCH_1):PAGE222',
 PHYS_PAGE='234',
 XY='(-3375,6400)',
 ROT='0',
 VER='2',
 PACK_TYPE='0402LF',
 CDS_LIB='pure_quanta',
 CDS_PART_NAME='Q_RES_0402LF-54.9K,1%,1/16W,CHA',
 WATTAGE='1/16W',
 TOLERANCE='1%',
 MATERIAL='CHIP',
 VALUE='54.9K',
 PRIM_FILE='./archive_libs/logical/q_res/chips/chips.prt';

PART_NAME
 R3522 'Q_RES_0402LF-54.9K,1%,1/16W,CHA':;

SECTION_NUMBER 1
 '@S9S_MB_2U_LIB.S9S_MB_2U(SCH_1):PAGE222_I25@PURE_QUANTA.Q_RES(CHIPS)':
 C_PATH='@s9s_mb_2u_lib.s9s_mb_2u(sch_1):page222_i25@pure_quanta.q_res(chips)',
 P_PATH='@s9s_mb_2u_lib.s9s_mb_2u(sch_1):page234_i25@pure_quanta.q_res(chips)',
 PATH='I25',
 DRAWING='@S9S_MB_2U_LIB.S9S_MB_2U(SCH_1):PAGE222',
 PHYS_PAGE='234',
 XY='(-3125,6400)',
 ROT='0',
 VER='2',
 PACK_TYPE='0402LF',
 CDS_LIB='pure_quanta',
 CDS_PART_NAME='Q_RES_0402LF-54.9K,1%,1/16W,CHA',
 WATTAGE='1/16W',
 TOLERANCE='1%',
 MATERIAL='CHIP',
 VALUE='54.9K',
 PRIM_FILE='./archive_libs/logical/q_res/chips/chips.prt';

PART_NAME
 R3523 'Q_RES_0402LF-54.9K,1%,1/16W,CHA':;

SECTION_NUMBER 1
 '@S9S_MB_2U_LIB.S9S_MB_2U(SCH_1):PAGE222_I80@PURE_QUANTA.Q_RES(CHIPS)':
 C_PATH='@s9s_mb_2u_lib.s9s_mb_2u(sch_1):page222_i80@pure_quanta.q_res(chips)',
 P_PATH='@s9s_mb_2u_lib.s9s_mb_2u(sch_1):page234_i80@pure_quanta.q_res(chips)',
 PATH='I80',
 DRAWING='@S9S_MB_2U_LIB.S9S_MB_2U(SCH_1):PAGE222',
 PHYS_PAGE='234',
 XY='(-775,7750)',
 ROT='0',
 VER='2',
 PACK_TYPE='0402LF',
 CDS_LIB='pure_quanta',
 CDS_PART_NAME='Q_RES_0402LF-54.9K,1%,1/16W,CHA',
 WATTAGE='1/16W',
 TOLERANCE='1%',
 MATERIAL='CHIP',
 VALUE='54.9K',
 PRIM_FILE='./archive_libs/logical/q_res/chips/chips.prt';

PART_NAME
 R3524 'Q_RES_0402LF-54.9K,1%,1/16W,CHA':;

SECTION_NUMBER 1
 '@S9S_MB_2U_LIB.S9S_MB_2U(SCH_1):PAGE222_I81@PURE_QUANTA.Q_RES(CHIPS)':
 C_PATH='@s9s_mb_2u_lib.s9s_mb_2u(sch_1):page222_i81@pure_quanta.q_res(chips)',
 P_PATH='@s9s_mb_2u_lib.s9s_mb_2u(sch_1):page234_i81@pure_quanta.q_res(chips)',
 PATH='I81',
 DRAWING='@S9S_MB_2U_LIB.S9S_MB_2U(SCH_1):PAGE222',
 PHYS_PAGE='234',
 XY='(-525,7750)',
 ROT='0',
 VER='2',
 PACK_TYPE='0402LF',
 CDS_LIB='pure_quanta',
 CDS_PART_NAME='Q_RES_0402LF-54.9K,1%,1/16W,CHA',
 WATTAGE='1/16W',
 TOLERANCE='1%',
 MATERIAL='CHIP',
 VALUE='54.9K',
 PRIM_FILE='./archive_libs/logical/q_res/chips/chips.prt';

PART_NAME
 R3525 'Q_RES_0402LF-54.9K,1%,1/16W,CHA':;

SECTION_NUMBER 1
 '@S9S_MB_2U_LIB.S9S_MB_2U(SCH_1):PAGE299_I184@PURE_QUANTA.Q_RES(CHIPS)':
 C_PATH='@s9s_mb_2u_lib.s9s_mb_2u(sch_1):page299_i184@pure_quanta.q_res(chips)',
 P_PATH='@s9s_mb_2u_lib.s9s_mb_2u(sch_1):page147_i184@pure_quanta.q_res(chips)',
 PATH='I184',
 DRAWING='@S9S_MB_2U_LIB.S9S_MB_2U(SCH_1):PAGE299',
 PHYS_PAGE='147',
 XY='(1700,1100)',
 ROT='0',
 VER='2',
 PACK_TYPE='0402LF',
 CDS_LIB='pure_quanta',
 CDS_PART_NAME='Q_RES_0402LF-54.9K,1%,1/16W,CHA',
 WATTAGE='1/16W',
 TOLERANCE='1%',
 MATERIAL='CHIP',
 VALUE='54.9K',
 PRIM_FILE='./archive_libs/logical/q_res/chips/chips.prt';

PART_NAME
 R3526 'Q_RES_0402LF-0,5%,1/16W,CHIP,CA':;

SECTION_NUMBER 1
 '@S9S_MB_2U_LIB.S9S_MB_2U(SCH_1):PAGE219_I35@PURE_QUANTA.Q_RES(CHIPS)':
 C_PATH='@s9s_mb_2u_lib.s9s_mb_2u(sch_1):page219_i35@pure_quanta.q_res(chips)',
 P_PATH='@s9s_mb_2u_lib.s9s_mb_2u(sch_1):page231_i35@pure_quanta.q_res(chips)',
 PATH='I35',
 DRAWING='@S9S_MB_2U_LIB.S9S_MB_2U(SCH_1):PAGE219',
 PHYS_PAGE='231',
 XY='(600,2425)',
 ROT='2',
 VER='1',
 PACK_TYPE='0402LF',
 CDS_LIB='pure_quanta',
 CDS_PART_NAME='Q_RES_0402LF-0,5%,1/16W,CHIP,CA',
 WATTAGE='1/16W',
 TOLERANCE='5%',
 MATERIAL='CHIP',
 VALUE='0',
 PRIM_FILE='./archive_libs/logical/q_res/chips/chips.prt';

PART_NAME
 R3527 'Q_RES_0402LF-0,5%,1/16W,CHIP,CA':;

SECTION_NUMBER 1
 '@S9S_MB_2U_LIB.S9S_MB_2U(SCH_1):PAGE219_I37@PURE_QUANTA.Q_RES(CHIPS)':
 C_PATH='@s9s_mb_2u_lib.s9s_mb_2u(sch_1):page219_i37@pure_quanta.q_res(chips)',
 P_PATH='@s9s_mb_2u_lib.s9s_mb_2u(sch_1):page231_i37@pure_quanta.q_res(chips)',
 PATH='I37',
 DRAWING='@S9S_MB_2U_LIB.S9S_MB_2U(SCH_1):PAGE219',
 PHYS_PAGE='231',
 XY='(600,2475)',
 ROT='2',
 VER='1',
 PACK_TYPE='0402LF',
 CDS_LIB='pure_quanta',
 CDS_PART_NAME='Q_RES_0402LF-0,5%,1/16W,CHIP,CA',
 WATTAGE='1/16W',
 TOLERANCE='5%',
 MATERIAL='CHIP',
 VALUE='0',
 PRIM_FILE='./archive_libs/logical/q_res/chips/chips.prt';

PART_NAME
 R3529 'Q_RES_0402LF-10K,1%,1/16W,CHIPA':;

SECTION_NUMBER 1
 '@S9S_MB_2U_LIB.S9S_MB_2U(SCH_1):PAGE183_I99@PURE_QUANTA.Q_RES(CHIPS)':
 C_PATH='@s9s_mb_2u_lib.s9s_mb_2u(sch_1):page183_i99@pure_quanta.q_res(chips)',
 P_PATH='@s9s_mb_2u_lib.s9s_mb_2u(sch_1):page194_i99@pure_quanta.q_res(chips)',
 PATH='I99',
 DRAWING='@S9S_MB_2U_LIB.S9S_MB_2U(SCH_1):PAGE183',
 PHYS_PAGE='194',
 XY='(-25,1600)',
 ROT='0',
 VER='2',
 PACK_TYPE='0402LF',
 LOCATION='R3529',
 CDS_LIB='pure_quanta',
 CDS_PART_NAME='Q_RES_0402LF-10K,1%,1/16W,CHIPA',
 WATTAGE='1/16W',
 TOLERANCE='1%',
 MATERIAL='CHIP',
 VALUE='10K',
 PRIM_FILE='./archive_libs/logical/q_res/chips/chips.prt';

PART_NAME
 R3530 'Q_RES_0402LF-4.7K,5%,1/16W,CHIA':;

SECTION_NUMBER 1
 '@S9S_MB_2U_LIB.S9S_MB_2U(SCH_1):PAGE183_I80@PURE_QUANTA.Q_RES(CHIPS)':
 C_PATH='@s9s_mb_2u_lib.s9s_mb_2u(sch_1):page183_i80@pure_quanta.q_res(chips)',
 P_PATH='@s9s_mb_2u_lib.s9s_mb_2u(sch_1):page194_i80@pure_quanta.q_res(chips)',
 PATH='I80',
 DRAWING='@S9S_MB_2U_LIB.S9S_MB_2U(SCH_1):PAGE183',
 PHYS_PAGE='194',
 XY='(2125,1575)',
 ROT='0',
 VER='2',
 PACK_TYPE='0402LF',
 CDS_LIB='pure_quanta',
 CDS_PART_NAME='Q_RES_0402LF-4.7K,5%,1/16W,CHIA',
 WATTAGE='1/16W',
 TOLERANCE='5%',
 MATERIAL='CHIP',
 VALUE='4.7K',
 PRIM_FILE='./archive_libs/logical/q_res/chips/chips.prt';

PART_NAME
 R3531 'Q_RES_0402LF-200K,1%,1/16W,EMPA':;

SECTION_NUMBER 1
 '@S9S_MB_2U_LIB.S9S_MB_2U(SCH_1):PAGE183_I96@PURE_QUANTA.Q_RES(CHIPS)':
 C_PATH='@s9s_mb_2u_lib.s9s_mb_2u(sch_1):page183_i96@pure_quanta.q_res(chips)',
 P_PATH='@s9s_mb_2u_lib.s9s_mb_2u(sch_1):page194_i96@pure_quanta.q_res(chips)',
 PATH='I96',
 DRAWING='@S9S_MB_2U_LIB.S9S_MB_2U(SCH_1):PAGE183',
 PHYS_PAGE='194',
 XY='(-1500,975)',
 ROT='0',
 VER='1',
 PACK_TYPE='0402LF',
 CDS_LIB='pure_quanta',
 CDS_PART_NAME='Q_RES_0402LF-200K,1%,1/16W,EMPA',
 WATTAGE='1/16W',
 TOLERANCE='1%',
 MATERIAL='EMPTY',
 VALUE='200K',
 PRIM_FILE='./archive_libs/logical/q_res/chips/chips.prt';

PART_NAME
 R3532 'Q_RES_0402LF-4.7K,5%,1/16W,CHIA':;

SECTION_NUMBER 1
 '@S9S_MB_2U_LIB.S9S_MB_2U(SCH_1):PAGE183_I78@PURE_QUANTA.Q_RES(CHIPS)':
 C_PATH='@s9s_mb_2u_lib.s9s_mb_2u(sch_1):page183_i78@pure_quanta.q_res(chips)',
 P_PATH='@s9s_mb_2u_lib.s9s_mb_2u(sch_1):page194_i78@pure_quanta.q_res(chips)',
 PATH='I78',
 DRAWING='@S9S_MB_2U_LIB.S9S_MB_2U(SCH_1):PAGE183',
 PHYS_PAGE='194',
 XY='(2375,1575)',
 ROT='0',
 VER='2',
 PACK_TYPE='0402LF',
 CDS_LIB='pure_quanta',
 CDS_PART_NAME='Q_RES_0402LF-4.7K,5%,1/16W,CHIA',
 WATTAGE='1/16W',
 TOLERANCE='5%',
 MATERIAL='CHIP',
 VALUE='4.7K',
 PRIM_FILE='./archive_libs/logical/q_res/chips/chips.prt';

PART_NAME
 R3533 'Q_RES_0402LF-33.2,1%,1/16W,CHIA':;

SECTION_NUMBER 1
 '@S9S_MB_2U_LIB.S9S_MB_2U(SCH_1):PAGE183_I76@PURE_QUANTA.Q_RES(CHIPS)':
 C_PATH='@s9s_mb_2u_lib.s9s_mb_2u(sch_1):page183_i76@pure_quanta.q_res(chips)',
 P_PATH='@s9s_mb_2u_lib.s9s_mb_2u(sch_1):page194_i76@pure_quanta.q_res(chips)',
 PATH='I76',
 DRAWING='@S9S_MB_2U_LIB.S9S_MB_2U(SCH_1):PAGE183',
 PHYS_PAGE='194',
 XY='(2700,1225)',
 ROT='0',
 VER='1',
 PACK_TYPE='0402LF',
 CDS_LIB='pure_quanta',
 CDS_PART_NAME='Q_RES_0402LF-33.2,1%,1/16W,CHIA',
 WATTAGE='1/16W',
 TOLERANCE='1%',
 MATERIAL='CHIP',
 VALUE='33.2',
 PRIM_FILE='./archive_libs/logical/q_res/chips/chips.prt';

PART_NAME
 R3534 'Q_RES_0402LF-33.2,1%,1/16W,CHIA':;

SECTION_NUMBER 1
 '@S9S_MB_2U_LIB.S9S_MB_2U(SCH_1):PAGE183_I77@PURE_QUANTA.Q_RES(CHIPS)':
 C_PATH='@s9s_mb_2u_lib.s9s_mb_2u(sch_1):page183_i77@pure_quanta.q_res(chips)',
 P_PATH='@s9s_mb_2u_lib.s9s_mb_2u(sch_1):page194_i77@pure_quanta.q_res(chips)',
 PATH='I77',
 DRAWING='@S9S_MB_2U_LIB.S9S_MB_2U(SCH_1):PAGE183',
 PHYS_PAGE='194',
 XY='(2700,1125)',
 ROT='0',
 VER='1',
 PACK_TYPE='0402LF',
 CDS_LIB='pure_quanta',
 CDS_PART_NAME='Q_RES_0402LF-33.2,1%,1/16W,CHIA',
 WATTAGE='1/16W',
 TOLERANCE='1%',
 MATERIAL='CHIP',
 VALUE='33.2',
 PRIM_FILE='./archive_libs/logical/q_res/chips/chips.prt';

PART_NAME
 R3535 'Q_RES_0402LF-2.2K,5%,1/16W,CHIA':;

SECTION_NUMBER 1
 '@S9S_MB_2U_LIB.S9S_MB_2U(SCH_1):PAGE219_I49@PURE_QUANTA.Q_RES(CHIPS)':
 C_PATH='@s9s_mb_2u_lib.s9s_mb_2u(sch_1):page219_i49@pure_quanta.q_res(chips)',
 P_PATH='@s9s_mb_2u_lib.s9s_mb_2u(sch_1):page231_i49@pure_quanta.q_res(chips)',
 PATH='I49',
 DRAWING='@S9S_MB_2U_LIB.S9S_MB_2U(SCH_1):PAGE219',
 PHYS_PAGE='231',
 XY='(3875,75)',
 ROT='0',
 VER='1',
 PACK_TYPE='0402LF',
 CDS_LIB='pure_quanta',
 CDS_PART_NAME='Q_RES_0402LF-2.2K,5%,1/16W,CHIA',
 WATTAGE='1/16W',
 TOLERANCE='5%',
 MATERIAL='CHIP',
 VALUE='2.2K',
 PRIM_FILE='./archive_libs/logical/q_res/chips/chips.prt';

PART_NAME
 R3536 'Q_RES_0402LF-2.2K,5%,1/16W,CHIA':;

SECTION_NUMBER 1
 '@S9S_MB_2U_LIB.S9S_MB_2U(SCH_1):PAGE219_I50@PURE_QUANTA.Q_RES(CHIPS)':
 C_PATH='@s9s_mb_2u_lib.s9s_mb_2u(sch_1):page219_i50@pure_quanta.q_res(chips)',
 P_PATH='@s9s_mb_2u_lib.s9s_mb_2u(sch_1):page231_i50@pure_quanta.q_res(chips)',
 PATH='I50',
 DRAWING='@S9S_MB_2U_LIB.S9S_MB_2U(SCH_1):PAGE219',
 PHYS_PAGE='231',
 XY='(3875,25)',
 ROT='0',
 VER='1',
 PACK_TYPE='0402LF',
 CDS_LIB='pure_quanta',
 CDS_PART_NAME='Q_RES_0402LF-2.2K,5%,1/16W,CHIA',
 WATTAGE='1/16W',
 TOLERANCE='5%',
 MATERIAL='CHIP',
 VALUE='2.2K',
 PRIM_FILE='./archive_libs/logical/q_res/chips/chips.prt';

PART_NAME
 R3553 'Q_RES_0402LF-33.2,1%,1/16W,CHIA':;

SECTION_NUMBER 1
 '@S9S_MB_2U_LIB.S9S_MB_2U(SCH_1):PAGE161_I134@PURE_QUANTA.Q_RES(CHIPS)':
 C_PATH='@s9s_mb_2u_lib.s9s_mb_2u(sch_1):page161_i134@pure_quanta.q_res(chips)',
 P_PATH='@s9s_mb_2u_lib.s9s_mb_2u(sch_1):page170_i134@pure_quanta.q_res(chips)',
 PATH='I134',
 DRAWING='@S9S_MB_2U_LIB.S9S_MB_2U(SCH_1):PAGE161',
 PHYS_PAGE='170',
 XY='(225,-2975)',
 ROT='0',
 VER='1',
 PACK_TYPE='0402LF',
 CDS_LIB='pure_quanta',
 CDS_PART_NAME='Q_RES_0402LF-33.2,1%,1/16W,CHIA',
 WATTAGE='1/16W',
 TOLERANCE='1%',
 MATERIAL='CHIP',
 VALUE='33.2',
 PRIM_FILE='./archive_libs/logical/q_res/chips/chips.prt';

PART_NAME
 R3554 'Q_RES_0402LF-33.2,1%,1/16W,CHIA':;

SECTION_NUMBER 1
 '@S9S_MB_2U_LIB.S9S_MB_2U(SCH_1):PAGE161_I136@PURE_QUANTA.Q_RES(CHIPS)':
 C_PATH='@s9s_mb_2u_lib.s9s_mb_2u(sch_1):page161_i136@pure_quanta.q_res(chips)',
 P_PATH='@s9s_mb_2u_lib.s9s_mb_2u(sch_1):page170_i136@pure_quanta.q_res(chips)',
 PATH='I136',
 DRAWING='@S9S_MB_2U_LIB.S9S_MB_2U(SCH_1):PAGE161',
 PHYS_PAGE='170',
 XY='(225,-2825)',
 ROT='0',
 VER='1',
 PACK_TYPE='0402LF',
 CDS_LIB='pure_quanta',
 CDS_PART_NAME='Q_RES_0402LF-33.2,1%,1/16W,CHIA',
 WATTAGE='1/16W',
 TOLERANCE='1%',
 MATERIAL='CHIP',
 VALUE='33.2',
 PRIM_FILE='./archive_libs/logical/q_res/chips/chips.prt';

PART_NAME
 R3559 'Q_RES_0402LF-0,5%,1/16W,CHIP,CA':;

SECTION_NUMBER 1
 '@S9S_MB_2U_LIB.S9S_MB_2U(SCH_1):PAGE163_I96@PURE_QUANTA.Q_RES(CHIPS)':
 C_PATH='@s9s_mb_2u_lib.s9s_mb_2u(sch_1):page163_i96@pure_quanta.q_res(chips)',
 P_PATH='@s9s_mb_2u_lib.s9s_mb_2u(sch_1):page172_i96@pure_quanta.q_res(chips)',
 PATH='I96',
 DRAWING='@S9S_MB_2U_LIB.S9S_MB_2U(SCH_1):PAGE163',
 PHYS_PAGE='172',
 XY='(3275,375)',
 ROT='0',
 VER='1',
 PACK_TYPE='0402LF',
 CDS_LIB='pure_quanta',
 CDS_PART_NAME='Q_RES_0402LF-0,5%,1/16W,CHIP,CA',
 WATTAGE='1/16W',
 TOLERANCE='5%',
 MATERIAL='CHIP',
 VALUE='0',
 PRIM_FILE='./archive_libs/logical/q_res/chips/chips.prt';

PART_NAME
 R3560 'Q_RES_0402LF-0,5%,1/16W,CHIP,CA':;

SECTION_NUMBER 1
 '@S9S_MB_2U_LIB.S9S_MB_2U(SCH_1):PAGE163_I41@PURE_QUANTA.Q_RES(CHIPS)':
 C_PATH='@s9s_mb_2u_lib.s9s_mb_2u(sch_1):page163_i41@pure_quanta.q_res(chips)',
 P_PATH='@s9s_mb_2u_lib.s9s_mb_2u(sch_1):page172_i41@pure_quanta.q_res(chips)',
 PATH='I41',
 DRAWING='@S9S_MB_2U_LIB.S9S_MB_2U(SCH_1):PAGE163',
 PHYS_PAGE='172',
 XY='(2700,-1725)',
 ROT='0',
 VER='1',
 PACK_TYPE='0402LF',
 CDS_LIB='pure_quanta',
 CDS_PART_NAME='Q_RES_0402LF-0,5%,1/16W,CHIP,CA',
 WATTAGE='1/16W',
 TOLERANCE='5%',
 MATERIAL='CHIP',
 VALUE='0',
 PRIM_FILE='./archive_libs/logical/q_res/chips/chips.prt';

PART_NAME
 R3561 'Q_RES_0402LF-0,5%,1/16W,CHIP,CA':;

SECTION_NUMBER 1
 '@S9S_MB_2U_LIB.S9S_MB_2U(SCH_1):PAGE163_I64@PURE_QUANTA.Q_RES(CHIPS)':
 C_PATH='@s9s_mb_2u_lib.s9s_mb_2u(sch_1):page163_i64@pure_quanta.q_res(chips)',
 P_PATH='@s9s_mb_2u_lib.s9s_mb_2u(sch_1):page172_i64@pure_quanta.q_res(chips)',
 PATH='I64',
 DRAWING='@S9S_MB_2U_LIB.S9S_MB_2U(SCH_1):PAGE163',
 PHYS_PAGE='172',
 XY='(2825,-3875)',
 ROT='0',
 VER='1',
 PACK_TYPE='0402LF',
 CDS_LIB='pure_quanta',
 CDS_PART_NAME='Q_RES_0402LF-0,5%,1/16W,CHIP,CA',
 WATTAGE='1/16W',
 TOLERANCE='5%',
 MATERIAL='CHIP',
 VALUE='0',
 PRIM_FILE='./archive_libs/logical/q_res/chips/chips.prt';

PART_NAME
 R3563 'Q_RES_0402LF-0,5%,1/16W,CHIP,CA':;

SECTION_NUMBER 1
 '@S9S_MB_2U_LIB.S9S_MB_2U(SCH_1):PAGE295_I35@PURE_QUANTA.Q_RES(CHIPS)':
 C_PATH='@s9s_mb_2u_lib.s9s_mb_2u(sch_1):page295_i35@pure_quanta.q_res(chips)',
 P_PATH='@s9s_mb_2u_lib.s9s_mb_2u(sch_1):page171_i35@pure_quanta.q_res(chips)',
 PATH='I35',
 DRAWING='@S9S_MB_2U_LIB.S9S_MB_2U(SCH_1):PAGE295',
 PHYS_PAGE='171',
 XY='(4350,3325)',
 ROT='0',
 VER='1',
 PACK_TYPE='0402LF',
 CDS_LIB='pure_quanta',
 CDS_PART_NAME='Q_RES_0402LF-0,5%,1/16W,CHIP,CA',
 WATTAGE='1/16W',
 TOLERANCE='5%',
 MATERIAL='CHIP',
 VALUE='0',
 PRIM_FILE='./archive_libs/logical/q_res/chips/chips.prt';

PART_NAME
 R3568 'Q_RES_0402LF-33.2,1%,1/16W,CHIA':;

SECTION_NUMBER 1
 '@S9S_MB_2U_LIB.S9S_MB_2U(SCH_1):PAGE163_I101@PURE_QUANTA.Q_RES(CHIPS)':
 C_PATH='@s9s_mb_2u_lib.s9s_mb_2u(sch_1):page163_i101@pure_quanta.q_res(chips)',
 P_PATH='@s9s_mb_2u_lib.s9s_mb_2u(sch_1):page172_i101@pure_quanta.q_res(chips)',
 PATH='I101',
 DRAWING='@S9S_MB_2U_LIB.S9S_MB_2U(SCH_1):PAGE163',
 PHYS_PAGE='172',
 XY='(100,125)',
 ROT='0',
 VER='1',
 PACK_TYPE='0402LF',
 CDS_LIB='pure_quanta',
 CDS_PART_NAME='Q_RES_0402LF-33.2,1%,1/16W,CHIA',
 WATTAGE='1/16W',
 TOLERANCE='1%',
 MATERIAL='CHIP',
 VALUE='33.2',
 PRIM_FILE='./archive_libs/logical/q_res/chips/chips.prt';

PART_NAME
 R3569 'Q_RES_0402LF-33.2,1%,1/16W,CHIA':;

SECTION_NUMBER 1
 '@S9S_MB_2U_LIB.S9S_MB_2U(SCH_1):PAGE163_I102@PURE_QUANTA.Q_RES(CHIPS)':
 C_PATH='@s9s_mb_2u_lib.s9s_mb_2u(sch_1):page163_i102@pure_quanta.q_res(chips)',
 P_PATH='@s9s_mb_2u_lib.s9s_mb_2u(sch_1):page172_i102@pure_quanta.q_res(chips)',
 PATH='I102',
 DRAWING='@S9S_MB_2U_LIB.S9S_MB_2U(SCH_1):PAGE163',
 PHYS_PAGE='172',
 XY='(100,75)',
 ROT='0',
 VER='1',
 PACK_TYPE='0402LF',
 CDS_LIB='pure_quanta',
 CDS_PART_NAME='Q_RES_0402LF-33.2,1%,1/16W,CHIA',
 WATTAGE='1/16W',
 TOLERANCE='1%',
 MATERIAL='CHIP',
 VALUE='33.2',
 PRIM_FILE='./archive_libs/logical/q_res/chips/chips.prt';

PART_NAME
 R3570 'Q_RES_0402LF-10,1%,1/16W,CHIP,A':;

SECTION_NUMBER 1
 '@S9S_MB_2U_LIB.S9S_MB_2U(SCH_1):PAGE163_I109@PURE_QUANTA.Q_RES(CHIPS)':
 C_PATH='@s9s_mb_2u_lib.s9s_mb_2u(sch_1):page163_i109@pure_quanta.q_res(chips)',
 P_PATH='@s9s_mb_2u_lib.s9s_mb_2u(sch_1):page172_i109@pure_quanta.q_res(chips)',
 PATH='I109',
 DRAWING='@S9S_MB_2U_LIB.S9S_MB_2U(SCH_1):PAGE163',
 PHYS_PAGE='172',
 XY='(150,-475)',
 ROT='0',
 VER='1',
 PACK_TYPE='0402LF',
 CDS_LIB='pure_quanta',
 CDS_PART_NAME='Q_RES_0402LF-10,1%,1/16W,CHIP,A',
 WATTAGE='1/16W',
 TOLERANCE='1%',
 MATERIAL='CHIP',
 VALUE='10',
 PRIM_FILE='./archive_libs/logical/q_res/chips/chips.prt';

PART_NAME
 R3571 'Q_RES_0402LF-10,1%,1/16W,CHIP,A':;

SECTION_NUMBER 1
 '@S9S_MB_2U_LIB.S9S_MB_2U(SCH_1):PAGE163_I110@PURE_QUANTA.Q_RES(CHIPS)':
 C_PATH='@s9s_mb_2u_lib.s9s_mb_2u(sch_1):page163_i110@pure_quanta.q_res(chips)',
 P_PATH='@s9s_mb_2u_lib.s9s_mb_2u(sch_1):page172_i110@pure_quanta.q_res(chips)',
 PATH='I110',
 DRAWING='@S9S_MB_2U_LIB.S9S_MB_2U(SCH_1):PAGE163',
 PHYS_PAGE='172',
 XY='(150,-750)',
 ROT='0',
 VER='1',
 PACK_TYPE='0402LF',
 CDS_LIB='pure_quanta',
 CDS_PART_NAME='Q_RES_0402LF-10,1%,1/16W,CHIP,A',
 WATTAGE='1/16W',
 TOLERANCE='1%',
 MATERIAL='CHIP',
 VALUE='10',
 PRIM_FILE='./archive_libs/logical/q_res/chips/chips.prt';

PART_NAME
 R3572 'Q_RES_0402LF-33.2,1%,1/16W,CHIA':;

SECTION_NUMBER 1
 '@S9S_MB_2U_LIB.S9S_MB_2U(SCH_1):PAGE163_I38@PURE_QUANTA.Q_RES(CHIPS)':
 C_PATH='@s9s_mb_2u_lib.s9s_mb_2u(sch_1):page163_i38@pure_quanta.q_res(chips)',
 P_PATH='@s9s_mb_2u_lib.s9s_mb_2u(sch_1):page172_i38@pure_quanta.q_res(chips)',
 PATH='I38',
 DRAWING='@S9S_MB_2U_LIB.S9S_MB_2U(SCH_1):PAGE163',
 PHYS_PAGE='172',
 XY='(-300,-1975)',
 ROT='0',
 VER='1',
 PACK_TYPE='0402LF',
 CDS_LIB='pure_quanta',
 CDS_PART_NAME='Q_RES_0402LF-33.2,1%,1/16W,CHIA',
 WATTAGE='1/16W',
 TOLERANCE='1%',
 MATERIAL='CHIP',
 VALUE='33.2',
 PRIM_FILE='./archive_libs/logical/q_res/chips/chips.prt';

PART_NAME
 R3573 'Q_RES_0402LF-33.2,1%,1/16W,CHIA':;

SECTION_NUMBER 1
 '@S9S_MB_2U_LIB.S9S_MB_2U(SCH_1):PAGE163_I37@PURE_QUANTA.Q_RES(CHIPS)':
 C_PATH='@s9s_mb_2u_lib.s9s_mb_2u(sch_1):page163_i37@pure_quanta.q_res(chips)',
 P_PATH='@s9s_mb_2u_lib.s9s_mb_2u(sch_1):page172_i37@pure_quanta.q_res(chips)',
 PATH='I37',
 DRAWING='@S9S_MB_2U_LIB.S9S_MB_2U(SCH_1):PAGE163',
 PHYS_PAGE='172',
 XY='(-300,-2025)',
 ROT='0',
 VER='1',
 PACK_TYPE='0402LF',
 CDS_LIB='pure_quanta',
 CDS_PART_NAME='Q_RES_0402LF-33.2,1%,1/16W,CHIA',
 WATTAGE='1/16W',
 TOLERANCE='1%',
 MATERIAL='CHIP',
 VALUE='33.2',
 PRIM_FILE='./archive_libs/logical/q_res/chips/chips.prt';

PART_NAME
 R3574 'Q_RES_0402LF-10,1%,1/16W,CHIP,A':;

SECTION_NUMBER 1
 '@S9S_MB_2U_LIB.S9S_MB_2U(SCH_1):PAGE163_I35@PURE_QUANTA.Q_RES(CHIPS)':
 C_PATH='@s9s_mb_2u_lib.s9s_mb_2u(sch_1):page163_i35@pure_quanta.q_res(chips)',
 P_PATH='@s9s_mb_2u_lib.s9s_mb_2u(sch_1):page172_i35@pure_quanta.q_res(chips)',
 PATH='I35',
 DRAWING='@S9S_MB_2U_LIB.S9S_MB_2U(SCH_1):PAGE163',
 PHYS_PAGE='172',
 XY='(-275,-2575)',
 ROT='0',
 VER='1',
 PACK_TYPE='0402LF',
 CDS_LIB='pure_quanta',
 CDS_PART_NAME='Q_RES_0402LF-10,1%,1/16W,CHIP,A',
 WATTAGE='1/16W',
 TOLERANCE='1%',
 MATERIAL='CHIP',
 VALUE='10',
 PRIM_FILE='./archive_libs/logical/q_res/chips/chips.prt';

PART_NAME
 R3575 'Q_RES_0402LF-10,1%,1/16W,CHIP,A':;

SECTION_NUMBER 1
 '@S9S_MB_2U_LIB.S9S_MB_2U(SCH_1):PAGE163_I33@PURE_QUANTA.Q_RES(CHIPS)':
 C_PATH='@s9s_mb_2u_lib.s9s_mb_2u(sch_1):page163_i33@pure_quanta.q_res(chips)',
 P_PATH='@s9s_mb_2u_lib.s9s_mb_2u(sch_1):page172_i33@pure_quanta.q_res(chips)',
 PATH='I33',
 DRAWING='@S9S_MB_2U_LIB.S9S_MB_2U(SCH_1):PAGE163',
 PHYS_PAGE='172',
 XY='(-275,-2850)',
 ROT='0',
 VER='1',
 PACK_TYPE='0402LF',
 CDS_LIB='pure_quanta',
 CDS_PART_NAME='Q_RES_0402LF-10,1%,1/16W,CHIP,A',
 WATTAGE='1/16W',
 TOLERANCE='1%',
 MATERIAL='CHIP',
 VALUE='10',
 PRIM_FILE='./archive_libs/logical/q_res/chips/chips.prt';

PART_NAME
 R3576 'Q_RES_0402LF-33.2,1%,1/16W,CHIA':;

SECTION_NUMBER 1
 '@S9S_MB_2U_LIB.S9S_MB_2U(SCH_1):PAGE163_I61@PURE_QUANTA.Q_RES(CHIPS)':
 C_PATH='@s9s_mb_2u_lib.s9s_mb_2u(sch_1):page163_i61@pure_quanta.q_res(chips)',
 P_PATH='@s9s_mb_2u_lib.s9s_mb_2u(sch_1):page172_i61@pure_quanta.q_res(chips)',
 PATH='I61',
 DRAWING='@S9S_MB_2U_LIB.S9S_MB_2U(SCH_1):PAGE163',
 PHYS_PAGE='172',
 XY='(-175,-4125)',
 ROT='0',
 VER='1',
 PACK_TYPE='0402LF',
 CDS_LIB='pure_quanta',
 CDS_PART_NAME='Q_RES_0402LF-33.2,1%,1/16W,CHIA',
 WATTAGE='1/16W',
 TOLERANCE='1%',
 MATERIAL='CHIP',
 VALUE='33.2',
 PRIM_FILE='./archive_libs/logical/q_res/chips/chips.prt';

PART_NAME
 R3577 'Q_RES_0402LF-33.2,1%,1/16W,CHIA':;

SECTION_NUMBER 1
 '@S9S_MB_2U_LIB.S9S_MB_2U(SCH_1):PAGE163_I60@PURE_QUANTA.Q_RES(CHIPS)':
 C_PATH='@s9s_mb_2u_lib.s9s_mb_2u(sch_1):page163_i60@pure_quanta.q_res(chips)',
 P_PATH='@s9s_mb_2u_lib.s9s_mb_2u(sch_1):page172_i60@pure_quanta.q_res(chips)',
 PATH='I60',
 DRAWING='@S9S_MB_2U_LIB.S9S_MB_2U(SCH_1):PAGE163',
 PHYS_PAGE='172',
 XY='(-175,-4175)',
 ROT='0',
 VER='1',
 PACK_TYPE='0402LF',
 CDS_LIB='pure_quanta',
 CDS_PART_NAME='Q_RES_0402LF-33.2,1%,1/16W,CHIA',
 WATTAGE='1/16W',
 TOLERANCE='1%',
 MATERIAL='CHIP',
 VALUE='33.2',
 PRIM_FILE='./archive_libs/logical/q_res/chips/chips.prt';

PART_NAME
 R3578 'Q_RES_0402LF-10,1%,1/16W,CHIP,A':;

SECTION_NUMBER 1
 '@S9S_MB_2U_LIB.S9S_MB_2U(SCH_1):PAGE163_I58@PURE_QUANTA.Q_RES(CHIPS)':
 C_PATH='@s9s_mb_2u_lib.s9s_mb_2u(sch_1):page163_i58@pure_quanta.q_res(chips)',
 P_PATH='@s9s_mb_2u_lib.s9s_mb_2u(sch_1):page172_i58@pure_quanta.q_res(chips)',
 PATH='I58',
 DRAWING='@S9S_MB_2U_LIB.S9S_MB_2U(SCH_1):PAGE163',
 PHYS_PAGE='172',
 XY='(-150,-4725)',
 ROT='0',
 VER='1',
 PACK_TYPE='0402LF',
 CDS_LIB='pure_quanta',
 CDS_PART_NAME='Q_RES_0402LF-10,1%,1/16W,CHIP,A',
 WATTAGE='1/16W',
 TOLERANCE='1%',
 MATERIAL='CHIP',
 VALUE='10',
 PRIM_FILE='./archive_libs/logical/q_res/chips/chips.prt';

PART_NAME
 R3579 'Q_RES_0402LF-10,1%,1/16W,CHIP,A':;

SECTION_NUMBER 1
 '@S9S_MB_2U_LIB.S9S_MB_2U(SCH_1):PAGE163_I56@PURE_QUANTA.Q_RES(CHIPS)':
 C_PATH='@s9s_mb_2u_lib.s9s_mb_2u(sch_1):page163_i56@pure_quanta.q_res(chips)',
 P_PATH='@s9s_mb_2u_lib.s9s_mb_2u(sch_1):page172_i56@pure_quanta.q_res(chips)',
 PATH='I56',
 DRAWING='@S9S_MB_2U_LIB.S9S_MB_2U(SCH_1):PAGE163',
 PHYS_PAGE='172',
 XY='(-150,-5000)',
 ROT='0',
 VER='1',
 PACK_TYPE='0402LF',
 CDS_LIB='pure_quanta',
 CDS_PART_NAME='Q_RES_0402LF-10,1%,1/16W,CHIP,A',
 WATTAGE='1/16W',
 TOLERANCE='1%',
 MATERIAL='CHIP',
 VALUE='10',
 PRIM_FILE='./archive_libs/logical/q_res/chips/chips.prt';

PART_NAME
 R3580 'Q_RES_0402LF-0,5%,1/16W,CHIP,CA':;

SECTION_NUMBER 1
 '@S9S_MB_2U_LIB.S9S_MB_2U(SCH_1):PAGE219_I59@PURE_QUANTA.Q_RES(CHIPS)':
 C_PATH='@s9s_mb_2u_lib.s9s_mb_2u(sch_1):page219_i59@pure_quanta.q_res(chips)',
 P_PATH='@s9s_mb_2u_lib.s9s_mb_2u(sch_1):page231_i59@pure_quanta.q_res(chips)',
 PATH='I59',
 DRAWING='@S9S_MB_2U_LIB.S9S_MB_2U(SCH_1):PAGE219',
 PHYS_PAGE='231',
 XY='(3400,2525)',
 ROT='0',
 VER='1',
 PACK_TYPE='0402LF',
 CDS_LIB='pure_quanta',
 CDS_PART_NAME='Q_RES_0402LF-0,5%,1/16W,CHIP,CA',
 WATTAGE='1/16W',
 TOLERANCE='5%',
 MATERIAL='CHIP',
 VALUE='0',
 PRIM_FILE='./archive_libs/logical/q_res/chips/chips.prt';

PART_NAME
 R3581 'Q_RES_0402LF-0,5%,1/16W,CHIP,CA':;

SECTION_NUMBER 1
 '@S9S_MB_2U_LIB.S9S_MB_2U(SCH_1):PAGE219_I60@PURE_QUANTA.Q_RES(CHIPS)':
 C_PATH='@s9s_mb_2u_lib.s9s_mb_2u(sch_1):page219_i60@pure_quanta.q_res(chips)',
 P_PATH='@s9s_mb_2u_lib.s9s_mb_2u(sch_1):page231_i60@pure_quanta.q_res(chips)',
 PATH='I60',
 DRAWING='@S9S_MB_2U_LIB.S9S_MB_2U(SCH_1):PAGE219',
 PHYS_PAGE='231',
 XY='(3400,2575)',
 ROT='0',
 VER='1',
 PACK_TYPE='0402LF',
 CDS_LIB='pure_quanta',
 CDS_PART_NAME='Q_RES_0402LF-0,5%,1/16W,CHIP,CA',
 WATTAGE='1/16W',
 TOLERANCE='5%',
 MATERIAL='CHIP',
 VALUE='0',
 PRIM_FILE='./archive_libs/logical/q_res/chips/chips.prt';

PART_NAME
 R3582 'Q_RES_0402LF-2.2K,5%,1/16W,CHIA':;

SECTION_NUMBER 1
 '@S9S_MB_2U_LIB.S9S_MB_2U(SCH_1):PAGE219_I52@PURE_QUANTA.Q_RES(CHIPS)':
 C_PATH='@s9s_mb_2u_lib.s9s_mb_2u(sch_1):page219_i52@pure_quanta.q_res(chips)',
 P_PATH='@s9s_mb_2u_lib.s9s_mb_2u(sch_1):page231_i52@pure_quanta.q_res(chips)',
 PATH='I52',
 DRAWING='@S9S_MB_2U_LIB.S9S_MB_2U(SCH_1):PAGE219',
 PHYS_PAGE='231',
 XY='(3850,375)',
 ROT='0',
 VER='1',
 PACK_TYPE='0402LF',
 CDS_LIB='pure_quanta',
 CDS_PART_NAME='Q_RES_0402LF-2.2K,5%,1/16W,CHIA',
 WATTAGE='1/16W',
 TOLERANCE='5%',
 MATERIAL='CHIP',
 VALUE='2.2K',
 PRIM_FILE='./archive_libs/logical/q_res/chips/chips.prt';

PART_NAME
 R3583 'Q_RES_0402LF-2.2K,5%,1/16W,CHIA':;

SECTION_NUMBER 1
 '@S9S_MB_2U_LIB.S9S_MB_2U(SCH_1):PAGE219_I51@PURE_QUANTA.Q_RES(CHIPS)':
 C_PATH='@s9s_mb_2u_lib.s9s_mb_2u(sch_1):page219_i51@pure_quanta.q_res(chips)',
 P_PATH='@s9s_mb_2u_lib.s9s_mb_2u(sch_1):page231_i51@pure_quanta.q_res(chips)',
 PATH='I51',
 DRAWING='@S9S_MB_2U_LIB.S9S_MB_2U(SCH_1):PAGE219',
 PHYS_PAGE='231',
 XY='(3850,325)',
 ROT='0',
 VER='1',
 PACK_TYPE='0402LF',
 CDS_LIB='pure_quanta',
 CDS_PART_NAME='Q_RES_0402LF-2.2K,5%,1/16W,CHIA',
 WATTAGE='1/16W',
 TOLERANCE='5%',
 MATERIAL='CHIP',
 VALUE='2.2K',
 PRIM_FILE='./archive_libs/logical/q_res/chips/chips.prt';

PART_NAME
 R3586 'Q_RES_0402LF-33.2,1%,1/16W,CHIA':;

SECTION_NUMBER 1
 '@S9S_MB_2U_LIB.S9S_MB_2U(SCH_1):PAGE220_I4@PURE_QUANTA.Q_RES(CHIPS)':
 C_PATH='@s9s_mb_2u_lib.s9s_mb_2u(sch_1):page220_i4@pure_quanta.q_res(chips)',
 P_PATH='@s9s_mb_2u_lib.s9s_mb_2u(sch_1):page232_i4@pure_quanta.q_res(chips)',
 PATH='I4',
 DRAWING='@S9S_MB_2U_LIB.S9S_MB_2U(SCH_1):PAGE220',
 PHYS_PAGE='232',
 XY='(825,3625)',
 ROT='0',
 VER='1',
 PACK_TYPE='0402LF',
 CDS_LIB='pure_quanta',
 CDS_PART_NAME='Q_RES_0402LF-33.2,1%,1/16W,CHIA',
 WATTAGE='1/16W',
 TOLERANCE='1%',
 MATERIAL='CHIP',
 VALUE='33.2',
 PRIM_FILE='./archive_libs/logical/q_res/chips/chips.prt';

PART_NAME
 R3587 'Q_RES_0402LF-33.2,1%,1/16W,CHIA':;

SECTION_NUMBER 1
 '@S9S_MB_2U_LIB.S9S_MB_2U(SCH_1):PAGE220_I3@PURE_QUANTA.Q_RES(CHIPS)':
 C_PATH='@s9s_mb_2u_lib.s9s_mb_2u(sch_1):page220_i3@pure_quanta.q_res(chips)',
 P_PATH='@s9s_mb_2u_lib.s9s_mb_2u(sch_1):page232_i3@pure_quanta.q_res(chips)',
 PATH='I3',
 DRAWING='@S9S_MB_2U_LIB.S9S_MB_2U(SCH_1):PAGE220',
 PHYS_PAGE='232',
 XY='(825,3575)',
 ROT='0',
 VER='1',
 PACK_TYPE='0402LF',
 CDS_LIB='pure_quanta',
 CDS_PART_NAME='Q_RES_0402LF-33.2,1%,1/16W,CHIA',
 WATTAGE='1/16W',
 TOLERANCE='1%',
 MATERIAL='CHIP',
 VALUE='33.2',
 PRIM_FILE='./archive_libs/logical/q_res/chips/chips.prt';

PART_NAME
 R3588 'Q_RES_0402LF-33.2,1%,1/16W,CHIA':;

SECTION_NUMBER 1
 '@S9S_MB_2U_LIB.S9S_MB_2U(SCH_1):PAGE220_I16@PURE_QUANTA.Q_RES(CHIPS)':
 C_PATH='@s9s_mb_2u_lib.s9s_mb_2u(sch_1):page220_i16@pure_quanta.q_res(chips)',
 P_PATH='@s9s_mb_2u_lib.s9s_mb_2u(sch_1):page232_i16@pure_quanta.q_res(chips)',
 PATH='I16',
 DRAWING='@S9S_MB_2U_LIB.S9S_MB_2U(SCH_1):PAGE220',
 PHYS_PAGE='232',
 XY='(825,3275)',
 ROT='0',
 VER='1',
 PACK_TYPE='0402LF',
 CDS_LIB='pure_quanta',
 CDS_PART_NAME='Q_RES_0402LF-33.2,1%,1/16W,CHIA',
 WATTAGE='1/16W',
 TOLERANCE='1%',
 MATERIAL='CHIP',
 VALUE='33.2',
 PRIM_FILE='./archive_libs/logical/q_res/chips/chips.prt';

PART_NAME
 R3589 'Q_RES_0402LF-33.2,1%,1/16W,CHIA':;

SECTION_NUMBER 1
 '@S9S_MB_2U_LIB.S9S_MB_2U(SCH_1):PAGE220_I11@PURE_QUANTA.Q_RES(CHIPS)':
 C_PATH='@s9s_mb_2u_lib.s9s_mb_2u(sch_1):page220_i11@pure_quanta.q_res(chips)',
 P_PATH='@s9s_mb_2u_lib.s9s_mb_2u(sch_1):page232_i11@pure_quanta.q_res(chips)',
 PATH='I11',
 DRAWING='@S9S_MB_2U_LIB.S9S_MB_2U(SCH_1):PAGE220',
 PHYS_PAGE='232',
 XY='(825,3225)',
 ROT='0',
 VER='1',
 PACK_TYPE='0402LF',
 CDS_LIB='pure_quanta',
 CDS_PART_NAME='Q_RES_0402LF-33.2,1%,1/16W,CHIA',
 WATTAGE='1/16W',
 TOLERANCE='1%',
 MATERIAL='CHIP',
 VALUE='33.2',
 PRIM_FILE='./archive_libs/logical/q_res/chips/chips.prt';

PART_NAME
 R3590 'Q_RES_0402LF-33.2,1%,1/16W,CHIA':;

SECTION_NUMBER 1
 '@S9S_MB_2U_LIB.S9S_MB_2U(SCH_1):PAGE220_I17@PURE_QUANTA.Q_RES(CHIPS)':
 C_PATH='@s9s_mb_2u_lib.s9s_mb_2u(sch_1):page220_i17@pure_quanta.q_res(chips)',
 P_PATH='@s9s_mb_2u_lib.s9s_mb_2u(sch_1):page232_i17@pure_quanta.q_res(chips)',
 PATH='I17',
 DRAWING='@S9S_MB_2U_LIB.S9S_MB_2U(SCH_1):PAGE220',
 PHYS_PAGE='232',
 XY='(825,3000)',
 ROT='0',
 VER='1',
 PACK_TYPE='0402LF',
 CDS_LIB='pure_quanta',
 CDS_PART_NAME='Q_RES_0402LF-33.2,1%,1/16W,CHIA',
 WATTAGE='1/16W',
 TOLERANCE='1%',
 MATERIAL='CHIP',
 VALUE='33.2',
 PRIM_FILE='./archive_libs/logical/q_res/chips/chips.prt';

PART_NAME
 R3591 'Q_RES_0402LF-33.2,1%,1/16W,CHIA':;

SECTION_NUMBER 1
 '@S9S_MB_2U_LIB.S9S_MB_2U(SCH_1):PAGE220_I18@PURE_QUANTA.Q_RES(CHIPS)':
 C_PATH='@s9s_mb_2u_lib.s9s_mb_2u(sch_1):page220_i18@pure_quanta.q_res(chips)',
 P_PATH='@s9s_mb_2u_lib.s9s_mb_2u(sch_1):page232_i18@pure_quanta.q_res(chips)',
 PATH='I18',
 DRAWING='@S9S_MB_2U_LIB.S9S_MB_2U(SCH_1):PAGE220',
 PHYS_PAGE='232',
 XY='(825,2950)',
 ROT='0',
 VER='1',
 PACK_TYPE='0402LF',
 CDS_LIB='pure_quanta',
 CDS_PART_NAME='Q_RES_0402LF-33.2,1%,1/16W,CHIA',
 WATTAGE='1/16W',
 TOLERANCE='1%',
 MATERIAL='CHIP',
 VALUE='33.2',
 PRIM_FILE='./archive_libs/logical/q_res/chips/chips.prt';

PART_NAME
 R3592 'Q_RES_0402LF-33.2,1%,1/16W,CHIA':;

SECTION_NUMBER 1
 '@S9S_MB_2U_LIB.S9S_MB_2U(SCH_1):PAGE220_I20@PURE_QUANTA.Q_RES(CHIPS)':
 C_PATH='@s9s_mb_2u_lib.s9s_mb_2u(sch_1):page220_i20@pure_quanta.q_res(chips)',
 P_PATH='@s9s_mb_2u_lib.s9s_mb_2u(sch_1):page232_i20@pure_quanta.q_res(chips)',
 PATH='I20',
 DRAWING='@S9S_MB_2U_LIB.S9S_MB_2U(SCH_1):PAGE220',
 PHYS_PAGE='232',
 XY='(825,2425)',
 ROT='0',
 VER='1',
 PACK_TYPE='0402LF',
 CDS_LIB='pure_quanta',
 CDS_PART_NAME='Q_RES_0402LF-33.2,1%,1/16W,CHIA',
 WATTAGE='1/16W',
 TOLERANCE='1%',
 MATERIAL='CHIP',
 VALUE='33.2',
 PRIM_FILE='./archive_libs/logical/q_res/chips/chips.prt';

PART_NAME
 R3593 'Q_RES_0402LF-33.2,1%,1/16W,CHIA':;

SECTION_NUMBER 1
 '@S9S_MB_2U_LIB.S9S_MB_2U(SCH_1):PAGE220_I19@PURE_QUANTA.Q_RES(CHIPS)':
 C_PATH='@s9s_mb_2u_lib.s9s_mb_2u(sch_1):page220_i19@pure_quanta.q_res(chips)',
 P_PATH='@s9s_mb_2u_lib.s9s_mb_2u(sch_1):page232_i19@pure_quanta.q_res(chips)',
 PATH='I19',
 DRAWING='@S9S_MB_2U_LIB.S9S_MB_2U(SCH_1):PAGE220',
 PHYS_PAGE='232',
 XY='(825,2375)',
 ROT='0',
 VER='1',
 PACK_TYPE='0402LF',
 CDS_LIB='pure_quanta',
 CDS_PART_NAME='Q_RES_0402LF-33.2,1%,1/16W,CHIA',
 WATTAGE='1/16W',
 TOLERANCE='1%',
 MATERIAL='CHIP',
 VALUE='33.2',
 PRIM_FILE='./archive_libs/logical/q_res/chips/chips.prt';

PART_NAME
 R3594 'Q_RES_0402LF-33.2,1%,1/16W,CHIA':;

SECTION_NUMBER 1
 '@S9S_MB_2U_LIB.S9S_MB_2U(SCH_1):PAGE220_I21@PURE_QUANTA.Q_RES(CHIPS)':
 C_PATH='@s9s_mb_2u_lib.s9s_mb_2u(sch_1):page220_i21@pure_quanta.q_res(chips)',
 P_PATH='@s9s_mb_2u_lib.s9s_mb_2u(sch_1):page232_i21@pure_quanta.q_res(chips)',
 PATH='I21',
 DRAWING='@S9S_MB_2U_LIB.S9S_MB_2U(SCH_1):PAGE220',
 PHYS_PAGE='232',
 XY='(850,2700)',
 ROT='0',
 VER='1',
 PACK_TYPE='0402LF',
 CDS_LIB='pure_quanta',
 CDS_PART_NAME='Q_RES_0402LF-33.2,1%,1/16W,CHIA',
 WATTAGE='1/16W',
 TOLERANCE='1%',
 MATERIAL='CHIP',
 VALUE='33.2',
 PRIM_FILE='./archive_libs/logical/q_res/chips/chips.prt';

PART_NAME
 R3595 'Q_RES_0402LF-33.2,1%,1/16W,CHIA':;

SECTION_NUMBER 1
 '@S9S_MB_2U_LIB.S9S_MB_2U(SCH_1):PAGE220_I26@PURE_QUANTA.Q_RES(CHIPS)':
 C_PATH='@s9s_mb_2u_lib.s9s_mb_2u(sch_1):page220_i26@pure_quanta.q_res(chips)',
 P_PATH='@s9s_mb_2u_lib.s9s_mb_2u(sch_1):page232_i26@pure_quanta.q_res(chips)',
 PATH='I26',
 DRAWING='@S9S_MB_2U_LIB.S9S_MB_2U(SCH_1):PAGE220',
 PHYS_PAGE='232',
 XY='(850,2650)',
 ROT='0',
 VER='1',
 PACK_TYPE='0402LF',
 CDS_LIB='pure_quanta',
 CDS_PART_NAME='Q_RES_0402LF-33.2,1%,1/16W,CHIA',
 WATTAGE='1/16W',
 TOLERANCE='1%',
 MATERIAL='CHIP',
 VALUE='33.2',
 PRIM_FILE='./archive_libs/logical/q_res/chips/chips.prt';

PART_NAME
 R3600 'Q_RES_0402LF-33.2,1%,1/16W,CHIA':;

SECTION_NUMBER 1
 '@S9S_MB_2U_LIB.S9S_MB_2U(SCH_1):PAGE295_I38@PURE_QUANTA.Q_RES(CHIPS)':
 C_PATH='@s9s_mb_2u_lib.s9s_mb_2u(sch_1):page295_i38@pure_quanta.q_res(chips)',
 P_PATH='@s9s_mb_2u_lib.s9s_mb_2u(sch_1):page171_i38@pure_quanta.q_res(chips)',
 PATH='I38',
 DRAWING='@S9S_MB_2U_LIB.S9S_MB_2U(SCH_1):PAGE295',
 PHYS_PAGE='171',
 XY='(1275,3075)',
 ROT='0',
 VER='1',
 PACK_TYPE='0402LF',
 CDS_LIB='pure_quanta',
 CDS_PART_NAME='Q_RES_0402LF-33.2,1%,1/16W,CHIA',
 WATTAGE='1/16W',
 TOLERANCE='1%',
 MATERIAL='CHIP',
 VALUE='33.2',
 PRIM_FILE='./archive_libs/logical/q_res/chips/chips.prt';

PART_NAME
 R3601 'Q_RES_0402LF-33.2,1%,1/16W,CHIA':;

SECTION_NUMBER 1
 '@S9S_MB_2U_LIB.S9S_MB_2U(SCH_1):PAGE295_I39@PURE_QUANTA.Q_RES(CHIPS)':
 C_PATH='@s9s_mb_2u_lib.s9s_mb_2u(sch_1):page295_i39@pure_quanta.q_res(chips)',
 P_PATH='@s9s_mb_2u_lib.s9s_mb_2u(sch_1):page171_i39@pure_quanta.q_res(chips)',
 PATH='I39',
 DRAWING='@S9S_MB_2U_LIB.S9S_MB_2U(SCH_1):PAGE295',
 PHYS_PAGE='171',
 XY='(1275,3025)',
 ROT='0',
 VER='1',
 PACK_TYPE='0402LF',
 CDS_LIB='pure_quanta',
 CDS_PART_NAME='Q_RES_0402LF-33.2,1%,1/16W,CHIA',
 WATTAGE='1/16W',
 TOLERANCE='1%',
 MATERIAL='CHIP',
 VALUE='33.2',
 PRIM_FILE='./archive_libs/logical/q_res/chips/chips.prt';

PART_NAME
 R3602 'Q_RES_0402LF-10,1%,1/16W,CHIP,A':;

SECTION_NUMBER 1
 '@S9S_MB_2U_LIB.S9S_MB_2U(SCH_1):PAGE295_I41@PURE_QUANTA.Q_RES(CHIPS)':
 C_PATH='@s9s_mb_2u_lib.s9s_mb_2u(sch_1):page295_i41@pure_quanta.q_res(chips)',
 P_PATH='@s9s_mb_2u_lib.s9s_mb_2u(sch_1):page171_i41@pure_quanta.q_res(chips)',
 PATH='I41',
 DRAWING='@S9S_MB_2U_LIB.S9S_MB_2U(SCH_1):PAGE295',
 PHYS_PAGE='171',
 XY='(1300,2475)',
 ROT='0',
 VER='1',
 PACK_TYPE='0402LF',
 CDS_LIB='pure_quanta',
 CDS_PART_NAME='Q_RES_0402LF-10,1%,1/16W,CHIP,A',
 WATTAGE='1/16W',
 TOLERANCE='1%',
 MATERIAL='CHIP',
 VALUE='10',
 PRIM_FILE='./archive_libs/logical/q_res/chips/chips.prt';

PART_NAME
 R3603 'Q_RES_0402LF-10,1%,1/16W,CHIP,A':;

SECTION_NUMBER 1
 '@S9S_MB_2U_LIB.S9S_MB_2U(SCH_1):PAGE295_I43@PURE_QUANTA.Q_RES(CHIPS)':
 C_PATH='@s9s_mb_2u_lib.s9s_mb_2u(sch_1):page295_i43@pure_quanta.q_res(chips)',
 P_PATH='@s9s_mb_2u_lib.s9s_mb_2u(sch_1):page171_i43@pure_quanta.q_res(chips)',
 PATH='I43',
 DRAWING='@S9S_MB_2U_LIB.S9S_MB_2U(SCH_1):PAGE295',
 PHYS_PAGE='171',
 XY='(1300,2200)',
 ROT='0',
 VER='1',
 PACK_TYPE='0402LF',
 CDS_LIB='pure_quanta',
 CDS_PART_NAME='Q_RES_0402LF-10,1%,1/16W,CHIP,A',
 WATTAGE='1/16W',
 TOLERANCE='1%',
 MATERIAL='CHIP',
 VALUE='10',
 PRIM_FILE='./archive_libs/logical/q_res/chips/chips.prt';

PART_NAME
 R3608 'Q_RES_0402LF-4.7K,1%,1/16W,CHIA':;

SECTION_NUMBER 1
 '@S9S_MB_2U_LIB.S9S_MB_2U(SCH_1):PAGE163_I103@PURE_QUANTA.Q_RES(CHIPS)':
 C_PATH='@s9s_mb_2u_lib.s9s_mb_2u(sch_1):page163_i103@pure_quanta.q_res(chips)',
 P_PATH='@s9s_mb_2u_lib.s9s_mb_2u(sch_1):page172_i103@pure_quanta.q_res(chips)',
 PATH='I103',
 DRAWING='@S9S_MB_2U_LIB.S9S_MB_2U(SCH_1):PAGE163',
 PHYS_PAGE='172',
 XY='(-525,600)',
 ROT='0',
 VER='1',
 PACK_TYPE='0402LF',
 CDS_LIB='pure_quanta',
 CDS_PART_NAME='Q_RES_0402LF-4.7K,1%,1/16W,CHIA',
 WATTAGE='1/16W',
 TOLERANCE='1%',
 MATERIAL='CHIP',
 VALUE='4.7K',
 PRIM_FILE='./archive_libs/logical/q_res/chips/chips.prt';

PART_NAME
 R3609 'Q_RES_0402LF-4.7K,1%,1/16W,EMPA':;

SECTION_NUMBER 1
 '@S9S_MB_2U_LIB.S9S_MB_2U(SCH_1):PAGE163_I104@PURE_QUANTA.Q_RES(CHIPS)':
 C_PATH='@s9s_mb_2u_lib.s9s_mb_2u(sch_1):page163_i104@pure_quanta.q_res(chips)',
 P_PATH='@s9s_mb_2u_lib.s9s_mb_2u(sch_1):page172_i104@pure_quanta.q_res(chips)',
 PATH='I104',
 DRAWING='@S9S_MB_2U_LIB.S9S_MB_2U(SCH_1):PAGE163',
 PHYS_PAGE='172',
 XY='(-525,525)',
 ROT='0',
 VER='1',
 PACK_TYPE='0402LF',
 CDS_LIB='pure_quanta',
 CDS_PART_NAME='Q_RES_0402LF-4.7K,1%,1/16W,EMPA',
 WATTAGE='1/16W',
 TOLERANCE='1%',
 MATERIAL='EMPTY',
 VALUE='4.7K',
 PRIM_FILE='./archive_libs/logical/q_res/chips/chips.prt';

PART_NAME
 R3610 'Q_RES_0402LF-4.7K,1%,1/16W,EMPA':;

SECTION_NUMBER 1
 '@S9S_MB_2U_LIB.S9S_MB_2U(SCH_1):PAGE163_I45@PURE_QUANTA.Q_RES(CHIPS)':
 C_PATH='@s9s_mb_2u_lib.s9s_mb_2u(sch_1):page163_i45@pure_quanta.q_res(chips)',
 P_PATH='@s9s_mb_2u_lib.s9s_mb_2u(sch_1):page172_i45@pure_quanta.q_res(chips)',
 PATH='I45',
 DRAWING='@S9S_MB_2U_LIB.S9S_MB_2U(SCH_1):PAGE163',
 PHYS_PAGE='172',
 XY='(-1050,-1675)',
 ROT='0',
 VER='1',
 PACK_TYPE='0402LF',
 CDS_LIB='pure_quanta',
 CDS_PART_NAME='Q_RES_0402LF-4.7K,1%,1/16W,EMPA',
 WATTAGE='1/16W',
 TOLERANCE='1%',
 MATERIAL='EMPTY',
 VALUE='4.7K',
 PRIM_FILE='./archive_libs/logical/q_res/chips/chips.prt';

PART_NAME
 R3611 'Q_RES_0402LF-4.7K,1%,1/16W,CHIA':;

SECTION_NUMBER 1
 '@S9S_MB_2U_LIB.S9S_MB_2U(SCH_1):PAGE163_I36@PURE_QUANTA.Q_RES(CHIPS)':
 C_PATH='@s9s_mb_2u_lib.s9s_mb_2u(sch_1):page163_i36@pure_quanta.q_res(chips)',
 P_PATH='@s9s_mb_2u_lib.s9s_mb_2u(sch_1):page172_i36@pure_quanta.q_res(chips)',
 PATH='I36',
 DRAWING='@S9S_MB_2U_LIB.S9S_MB_2U(SCH_1):PAGE163',
 PHYS_PAGE='172',
 XY='(-1050,-1750)',
 ROT='0',
 VER='1',
 PACK_TYPE='0402LF',
 CDS_LIB='pure_quanta',
 CDS_PART_NAME='Q_RES_0402LF-4.7K,1%,1/16W,CHIA',
 WATTAGE='1/16W',
 TOLERANCE='1%',
 MATERIAL='CHIP',
 VALUE='4.7K',
 PRIM_FILE='./archive_libs/logical/q_res/chips/chips.prt';

PART_NAME
 R3612 'Q_RES_0402LF-4.7K,1%,1/16W,EMPA':;

SECTION_NUMBER 1
 '@S9S_MB_2U_LIB.S9S_MB_2U(SCH_1):PAGE163_I68@PURE_QUANTA.Q_RES(CHIPS)':
 C_PATH='@s9s_mb_2u_lib.s9s_mb_2u(sch_1):page163_i68@pure_quanta.q_res(chips)',
 P_PATH='@s9s_mb_2u_lib.s9s_mb_2u(sch_1):page172_i68@pure_quanta.q_res(chips)',
 PATH='I68',
 DRAWING='@S9S_MB_2U_LIB.S9S_MB_2U(SCH_1):PAGE163',
 PHYS_PAGE='172',
 XY='(-975,-3850)',
 ROT='0',
 VER='1',
 PACK_TYPE='0402LF',
 CDS_LIB='pure_quanta',
 CDS_PART_NAME='Q_RES_0402LF-4.7K,1%,1/16W,EMPA',
 WATTAGE='1/16W',
 TOLERANCE='1%',
 MATERIAL='EMPTY',
 VALUE='4.7K',
 PRIM_FILE='./archive_libs/logical/q_res/chips/chips.prt';

PART_NAME
 R3613 'Q_RES_0402LF-4.7K,1%,1/16W,EMPA':;

SECTION_NUMBER 1
 '@S9S_MB_2U_LIB.S9S_MB_2U(SCH_1):PAGE163_I59@PURE_QUANTA.Q_RES(CHIPS)':
 C_PATH='@s9s_mb_2u_lib.s9s_mb_2u(sch_1):page163_i59@pure_quanta.q_res(chips)',
 P_PATH='@s9s_mb_2u_lib.s9s_mb_2u(sch_1):page172_i59@pure_quanta.q_res(chips)',
 PATH='I59',
 DRAWING='@S9S_MB_2U_LIB.S9S_MB_2U(SCH_1):PAGE163',
 PHYS_PAGE='172',
 XY='(-975,-3925)',
 ROT='0',
 VER='1',
 PACK_TYPE='0402LF',
 CDS_LIB='pure_quanta',
 CDS_PART_NAME='Q_RES_0402LF-4.7K,1%,1/16W,EMPA',
 WATTAGE='1/16W',
 TOLERANCE='1%',
 MATERIAL='EMPTY',
 VALUE='4.7K',
 PRIM_FILE='./archive_libs/logical/q_res/chips/chips.prt';

PART_NAME
 R3616 'Q_RES_0402LF-4.7K,1%,1/16W,CHIA':;

SECTION_NUMBER 1
 '@S9S_MB_2U_LIB.S9S_MB_2U(SCH_1):PAGE295_I31@PURE_QUANTA.Q_RES(CHIPS)':
 C_PATH='@s9s_mb_2u_lib.s9s_mb_2u(sch_1):page295_i31@pure_quanta.q_res(chips)',
 P_PATH='@s9s_mb_2u_lib.s9s_mb_2u(sch_1):page171_i31@pure_quanta.q_res(chips)',
 PATH='I31',
 DRAWING='@S9S_MB_2U_LIB.S9S_MB_2U(SCH_1):PAGE295',
 PHYS_PAGE='171',
 XY='(625,3350)',
 ROT='0',
 VER='1',
 PACK_TYPE='0402LF',
 CDS_LIB='pure_quanta',
 CDS_PART_NAME='Q_RES_0402LF-4.7K,1%,1/16W,CHIA',
 WATTAGE='1/16W',
 TOLERANCE='1%',
 MATERIAL='CHIP',
 VALUE='4.7K',
 PRIM_FILE='./archive_libs/logical/q_res/chips/chips.prt';

PART_NAME
 R3617 'Q_RES_0402LF-4.7K,1%,1/16W,EMPA':;

SECTION_NUMBER 1
 '@S9S_MB_2U_LIB.S9S_MB_2U(SCH_1):PAGE295_I40@PURE_QUANTA.Q_RES(CHIPS)':
 C_PATH='@s9s_mb_2u_lib.s9s_mb_2u(sch_1):page295_i40@pure_quanta.q_res(chips)',
 P_PATH='@s9s_mb_2u_lib.s9s_mb_2u(sch_1):page171_i40@pure_quanta.q_res(chips)',
 PATH='I40',
 DRAWING='@S9S_MB_2U_LIB.S9S_MB_2U(SCH_1):PAGE295',
 PHYS_PAGE='171',
 XY='(625,3275)',
 ROT='0',
 VER='1',
 PACK_TYPE='0402LF',
 CDS_LIB='pure_quanta',
 CDS_PART_NAME='Q_RES_0402LF-4.7K,1%,1/16W,EMPA',
 WATTAGE='1/16W',
 TOLERANCE='1%',
 MATERIAL='EMPTY',
 VALUE='4.7K',
 PRIM_FILE='./archive_libs/logical/q_res/chips/chips.prt';

PART_NAME
 R3620 'Q_RES_0402LF-0,5%,1/16W,CHIP,CA':;

SECTION_NUMBER 1
 '@S9S_MB_2U_LIB.S9S_MB_2U(SCH_1):PAGE163_I100@PURE_QUANTA.Q_RES(CHIPS)':
 C_PATH='@s9s_mb_2u_lib.s9s_mb_2u(sch_1):page163_i100@pure_quanta.q_res(chips)',
 P_PATH='@s9s_mb_2u_lib.s9s_mb_2u(sch_1):page172_i100@pure_quanta.q_res(chips)',
 PATH='I100',
 DRAWING='@S9S_MB_2U_LIB.S9S_MB_2U(SCH_1):PAGE163',
 PHYS_PAGE='172',
 XY='(525,350)',
 ROT='0',
 VER='2',
 PACK_TYPE='0402LF',
 CDS_LIB='pure_quanta',
 CDS_PART_NAME='Q_RES_0402LF-0,5%,1/16W,CHIP,CA',
 WATTAGE='1/16W',
 TOLERANCE='5%',
 MATERIAL='CHIP',
 VALUE='0',
 PRIM_FILE='./archive_libs/logical/q_res/chips/chips.prt';

PART_NAME
 R3621 'Q_RES_0402LF-4.7K,1%,1/16W,EMPA':;

SECTION_NUMBER 1
 '@S9S_MB_2U_LIB.S9S_MB_2U(SCH_1):PAGE163_I87@PURE_QUANTA.Q_RES(CHIPS)':
 C_PATH='@s9s_mb_2u_lib.s9s_mb_2u(sch_1):page163_i87@pure_quanta.q_res(chips)',
 P_PATH='@s9s_mb_2u_lib.s9s_mb_2u(sch_1):page172_i87@pure_quanta.q_res(chips)',
 PATH='I87',
 DRAWING='@S9S_MB_2U_LIB.S9S_MB_2U(SCH_1):PAGE163',
 PHYS_PAGE='172',
 XY='(-225,-1325)',
 ROT='0',
 VER='2',
 PACK_TYPE='0402LF',
 CDS_LIB='pure_quanta',
 CDS_PART_NAME='Q_RES_0402LF-4.7K,1%,1/16W,EMPA',
 WATTAGE='1/16W',
 TOLERANCE='1%',
 MATERIAL='EMPTY',
 VALUE='4.7K',
 PRIM_FILE='./archive_libs/logical/q_res/chips/chips.prt';

PART_NAME
 R3622 'Q_RES_0402LF-4.7K,1%,1/16W,CHIA':;

SECTION_NUMBER 1
 '@S9S_MB_2U_LIB.S9S_MB_2U(SCH_1):PAGE163_I90@PURE_QUANTA.Q_RES(CHIPS)':
 C_PATH='@s9s_mb_2u_lib.s9s_mb_2u(sch_1):page163_i90@pure_quanta.q_res(chips)',
 P_PATH='@s9s_mb_2u_lib.s9s_mb_2u(sch_1):page172_i90@pure_quanta.q_res(chips)',
 PATH='I90',
 DRAWING='@S9S_MB_2U_LIB.S9S_MB_2U(SCH_1):PAGE163',
 PHYS_PAGE='172',
 XY='(-175,-3525)',
 ROT='0',
 VER='2',
 PACK_TYPE='0402LF',
 CDS_LIB='pure_quanta',
 CDS_PART_NAME='Q_RES_0402LF-4.7K,1%,1/16W,CHIA',
 WATTAGE='1/16W',
 TOLERANCE='1%',
 MATERIAL='CHIP',
 VALUE='4.7K',
 PRIM_FILE='./archive_libs/logical/q_res/chips/chips.prt';

PART_NAME
 R3623 'Q_RES_0402LF-4.7K,1%,1/16W,CHIA':;

SECTION_NUMBER 1
 '@S9S_MB_2U_LIB.S9S_MB_2U(SCH_1):PAGE163_I86@PURE_QUANTA.Q_RES(CHIPS)':
 C_PATH='@s9s_mb_2u_lib.s9s_mb_2u(sch_1):page163_i86@pure_quanta.q_res(chips)',
 P_PATH='@s9s_mb_2u_lib.s9s_mb_2u(sch_1):page172_i86@pure_quanta.q_res(chips)',
 PATH='I86',
 DRAWING='@S9S_MB_2U_LIB.S9S_MB_2U(SCH_1):PAGE163',
 PHYS_PAGE='172',
 XY='(75,-1325)',
 ROT='0',
 VER='2',
 PACK_TYPE='0402LF',
 CDS_LIB='pure_quanta',
 CDS_PART_NAME='Q_RES_0402LF-4.7K,1%,1/16W,CHIA',
 WATTAGE='1/16W',
 TOLERANCE='1%',
 MATERIAL='CHIP',
 VALUE='4.7K',
 PRIM_FILE='./archive_libs/logical/q_res/chips/chips.prt';

PART_NAME
 R3624 'Q_RES_0402LF-4.7K,1%,1/16W,CHIA':;

SECTION_NUMBER 1
 '@S9S_MB_2U_LIB.S9S_MB_2U(SCH_1):PAGE163_I89@PURE_QUANTA.Q_RES(CHIPS)':
 C_PATH='@s9s_mb_2u_lib.s9s_mb_2u(sch_1):page163_i89@pure_quanta.q_res(chips)',
 P_PATH='@s9s_mb_2u_lib.s9s_mb_2u(sch_1):page172_i89@pure_quanta.q_res(chips)',
 PATH='I89',
 DRAWING='@S9S_MB_2U_LIB.S9S_MB_2U(SCH_1):PAGE163',
 PHYS_PAGE='172',
 XY='(125,-3525)',
 ROT='0',
 VER='2',
 PACK_TYPE='0402LF',
 CDS_LIB='pure_quanta',
 CDS_PART_NAME='Q_RES_0402LF-4.7K,1%,1/16W,CHIA',
 WATTAGE='1/16W',
 TOLERANCE='1%',
 MATERIAL='CHIP',
 VALUE='4.7K',
 PRIM_FILE='./archive_libs/logical/q_res/chips/chips.prt';

PART_NAME
 R3627 'Q_RES_0402LF-4.7K,1%,1/16W,CHIA':;

SECTION_NUMBER 1
 '@S9S_MB_2U_LIB.S9S_MB_2U(SCH_1):PAGE295_I89@PURE_QUANTA.Q_RES(CHIPS)':
 C_PATH='@s9s_mb_2u_lib.s9s_mb_2u(sch_1):page295_i89@pure_quanta.q_res(chips)',
 P_PATH='@s9s_mb_2u_lib.s9s_mb_2u(sch_1):page171_i89@pure_quanta.q_res(chips)',
 PATH='I89',
 DRAWING='@S9S_MB_2U_LIB.S9S_MB_2U(SCH_1):PAGE295',
 PHYS_PAGE='171',
 XY='(1525,3700)',
 ROT='0',
 VER='2',
 PACK_TYPE='0402LF',
 CDS_LIB='pure_quanta',
 CDS_PART_NAME='Q_RES_0402LF-4.7K,1%,1/16W,CHIA',
 WATTAGE='1/16W',
 TOLERANCE='1%',
 MATERIAL='CHIP',
 VALUE='4.7K',
 PRIM_FILE='./archive_libs/logical/q_res/chips/chips.prt';

PART_NAME
 R3628 'Q_RES_0402LF-4.7K,1%,1/16W,EMPA':;

SECTION_NUMBER 1
 '@S9S_MB_2U_LIB.S9S_MB_2U(SCH_1):PAGE295_I88@PURE_QUANTA.Q_RES(CHIPS)':
 C_PATH='@s9s_mb_2u_lib.s9s_mb_2u(sch_1):page295_i88@pure_quanta.q_res(chips)',
 P_PATH='@s9s_mb_2u_lib.s9s_mb_2u(sch_1):page171_i88@pure_quanta.q_res(chips)',
 PATH='I88',
 DRAWING='@S9S_MB_2U_LIB.S9S_MB_2U(SCH_1):PAGE295',
 PHYS_PAGE='171',
 XY='(1825,3700)',
 ROT='0',
 VER='2',
 PACK_TYPE='0402LF',
 CDS_LIB='pure_quanta',
 CDS_PART_NAME='Q_RES_0402LF-4.7K,1%,1/16W,EMPA',
 WATTAGE='1/16W',
 TOLERANCE='1%',
 MATERIAL='EMPTY',
 VALUE='4.7K',
 PRIM_FILE='./archive_libs/logical/q_res/chips/chips.prt';

PART_NAME
 R3630 'Q_RES_0402LF-0,5%,1/16W,CHIP,CA':
 ROOM='NIC1_P12V_MPS_MAM_BOM3';

SECTION_NUMBER 1
 '@S9S_MB_2U_LIB.S9S_MB_2U(SCH_1):PAGE237_I66@PURE_QUANTA.Q_RES(CHIPS)':
 C_PATH='@s9s_mb_2u_lib.s9s_mb_2u(sch_1):page237_i66@pure_quanta.q_res(chips)',
 P_PATH='@s9s_mb_2u_lib.s9s_mb_2u(sch_1):page163_i66@pure_quanta.q_res(chips)',
 PATH='I66',
 DRAWING='@S9S_MB_2U_LIB.S9S_MB_2U(SCH_1):PAGE237',
 ROOM1='NIC1_P12V_MPS_TIC_BOM4',
 PHYS_PAGE='163',
 XY='(-4075,3175)',
 ROT='0',
 VER='1',
 PACK_TYPE='0402LF',
 CDS_LIB='pure_quanta',
 CDS_PART_NAME='Q_RES_0402LF-0,5%,1/16W,CHIP,CA',
 WATTAGE='1/16W',
 TOLERANCE='5%',
 MATERIAL='CHIP',
 ROOM='NIC1_P12V_MPS_MAM_BOM3',
 VALUE='0',
 PRIM_FILE='./archive_libs/logical/q_res/chips/chips.prt';

PART_NAME
 R3631 'Q_RES_0402LF-0,5%,1/16W,EMPTY,A':
 ROOM='NIC1_P3V3_BOM2';

SECTION_NUMBER 1
 '@S9S_MB_2U_LIB.S9S_MB_2U(SCH_1):PAGE237_I44@PURE_QUANTA.Q_RES(CHIPS)':
 C_PATH='@s9s_mb_2u_lib.s9s_mb_2u(sch_1):page237_i44@pure_quanta.q_res(chips)',
 P_PATH='@s9s_mb_2u_lib.s9s_mb_2u(sch_1):page163_i44@pure_quanta.q_res(chips)',
 PATH='I44',
 DRAWING='@S9S_MB_2U_LIB.S9S_MB_2U(SCH_1):PAGE237',
 PHYS_PAGE='163',
 XY='(225,6475)',
 ROT='0',
 VER='1',
 PACK_TYPE='0402LF',
 CDS_LIB='pure_quanta',
 CDS_PART_NAME='Q_RES_0402LF-0,5%,1/16W,EMPTY,A',
 WATTAGE='1/16W',
 TOLERANCE='5%',
 MATERIAL='EMPTY',
 ROOM='NIC1_P3V3_BOM2',
 VALUE='0',
 PRIM_FILE='./archive_libs/logical/q_res/chips/chips.prt';

PART_NAME
 R3633 'Q_RES_2512LF-0.01,1%,1W,CHIP,CA':;

SECTION_NUMBER 1
 '@S9S_MB_2U_LIB.S9S_MB_2U(SCH_1):PAGE163_I127@PURE_QUANTA.Q_RES(CHIPS)':
 C_PATH='@s9s_mb_2u_lib.s9s_mb_2u(sch_1):page163_i127@pure_quanta.q_res(chips)',
 P_PATH='@s9s_mb_2u_lib.s9s_mb_2u(sch_1):page172_i127@pure_quanta.q_res(chips)',
 PATH='I127',
 DRAWING='@S9S_MB_2U_LIB.S9S_MB_2U(SCH_1):PAGE163',
 PHYS_PAGE='172',
 XY='(-1750,-275)',
 ROT='0',
 VER='1',
 PACK_TYPE='2512LF',
 LOCATION='R3633',
 CDS_LIB='pure_quanta',
 CDS_PART_NAME='Q_RES_2512LF-0.01,1%,1W,CHIP,CA',
 WATTAGE='1W',
 TOLERANCE='1%',
 MATERIAL='CHIP',
 VALUE='0.01',
 PRIM_FILE='./archive_libs/logical/q_res/chips/chips.prt';

PART_NAME
 R3634 'Q_RES_2512LF-0.01,1%,1W,CHIP,CA':;

SECTION_NUMBER 1
 '@S9S_MB_2U_LIB.S9S_MB_2U(SCH_1):PAGE163_I128@PURE_QUANTA.Q_RES(CHIPS)':
 C_PATH='@s9s_mb_2u_lib.s9s_mb_2u(sch_1):page163_i128@pure_quanta.q_res(chips)',
 P_PATH='@s9s_mb_2u_lib.s9s_mb_2u(sch_1):page172_i128@pure_quanta.q_res(chips)',
 PATH='I128',
 DRAWING='@S9S_MB_2U_LIB.S9S_MB_2U(SCH_1):PAGE163',
 PHYS_PAGE='172',
 XY='(-2150,-2375)',
 ROT='0',
 VER='1',
 PACK_TYPE='2512LF',
 LOCATION='R3634',
 CDS_LIB='pure_quanta',
 CDS_PART_NAME='Q_RES_2512LF-0.01,1%,1W,CHIP,CA',
 WATTAGE='1W',
 TOLERANCE='1%',
 MATERIAL='CHIP',
 VALUE='0.01',
 PRIM_FILE='./archive_libs/logical/q_res/chips/chips.prt';

PART_NAME
 R3635 'Q_RES_2512LF-0.01,1%,1W,CHIP,CA':;

SECTION_NUMBER 1
 '@S9S_MB_2U_LIB.S9S_MB_2U(SCH_1):PAGE163_I129@PURE_QUANTA.Q_RES(CHIPS)':
 C_PATH='@s9s_mb_2u_lib.s9s_mb_2u(sch_1):page163_i129@pure_quanta.q_res(chips)',
 P_PATH='@s9s_mb_2u_lib.s9s_mb_2u(sch_1):page172_i129@pure_quanta.q_res(chips)',
 PATH='I129',
 DRAWING='@S9S_MB_2U_LIB.S9S_MB_2U(SCH_1):PAGE163',
 PHYS_PAGE='172',
 XY='(-2050,-4525)',
 ROT='0',
 VER='1',
 PACK_TYPE='2512LF',
 LOCATION='R3635',
 CDS_LIB='pure_quanta',
 CDS_PART_NAME='Q_RES_2512LF-0.01,1%,1W,CHIP,CA',
 WATTAGE='1W',
 TOLERANCE='1%',
 MATERIAL='CHIP',
 VALUE='0.01',
 PRIM_FILE='./archive_libs/logical/q_res/chips/chips.prt';

PART_NAME
 R3636 'Q_RES_0402LF-0,5%,1/16W,CHIP,CA':;

SECTION_NUMBER 1
 '@S9S_MB_2U_LIB.S9S_MB_2U(SCH_1):PAGE195_I536@PURE_QUANTA.Q_RES(CHIPS)':
 C_PATH='@s9s_mb_2u_lib.s9s_mb_2u(sch_1):page195_i536@pure_quanta.q_res(chips)',
 P_PATH='@s9s_mb_2u_lib.s9s_mb_2u(sch_1):page206_i536@pure_quanta.q_res(chips)',
 PATH='I536',
 DRAWING='@S9S_MB_2U_LIB.S9S_MB_2U(SCH_1):PAGE195',
 PHYS_PAGE='206',
 XY='(-5300,1950)',
 ROT='0',
 VER='1',
 PACK_TYPE='0402LF',
 LOCATION='R3636',
 CDS_LIB='pure_quanta',
 CDS_PART_NAME='Q_RES_0402LF-0,5%,1/16W,CHIP,CA',
 WATTAGE='1/16W',
 TOLERANCE='5%',
 MATERIAL='CHIP',
 VALUE='0',
 PRIM_FILE='./archive_libs/logical/q_res/chips/chips.prt';

PART_NAME
 R3637 'Q_RES_0402LF-0,5%,1/16W,CHIP,CA':;

SECTION_NUMBER 1
 '@S9S_MB_2U_LIB.S9S_MB_2U(SCH_1):PAGE195_I537@PURE_QUANTA.Q_RES(CHIPS)':
 C_PATH='@s9s_mb_2u_lib.s9s_mb_2u(sch_1):page195_i537@pure_quanta.q_res(chips)',
 P_PATH='@s9s_mb_2u_lib.s9s_mb_2u(sch_1):page206_i537@pure_quanta.q_res(chips)',
 PATH='I537',
 DRAWING='@S9S_MB_2U_LIB.S9S_MB_2U(SCH_1):PAGE195',
 PHYS_PAGE='206',
 XY='(-5300,1900)',
 ROT='0',
 VER='1',
 PACK_TYPE='0402LF',
 LOCATION='R3637',
 CDS_LIB='pure_quanta',
 CDS_PART_NAME='Q_RES_0402LF-0,5%,1/16W,CHIP,CA',
 WATTAGE='1/16W',
 TOLERANCE='5%',
 MATERIAL='CHIP',
 VALUE='0',
 PRIM_FILE='./archive_libs/logical/q_res/chips/chips.prt';

PART_NAME
 R3638 'Q_RES_0402LF-10K,1%,1/16W,CHIPA':;

SECTION_NUMBER 1
 '@S9S_MB_2U_LIB.S9S_MB_2U(SCH_1):PAGE197_I378@PURE_QUANTA.Q_RES(CHIPS)':
 C_PATH='@s9s_mb_2u_lib.s9s_mb_2u(sch_1):page197_i378@pure_quanta.q_res(chips)',
 P_PATH='@s9s_mb_2u_lib.s9s_mb_2u(sch_1):page208_i378@pure_quanta.q_res(chips)',
 PATH='I378',
 DRAWING='@S9S_MB_2U_LIB.S9S_MB_2U(SCH_1):PAGE197',
 PHYS_PAGE='208',
 XY='(-2650,6925)',
 ROT='0',
 VER='1',
 PACK_TYPE='0402LF',
 CDS_LIB='pure_quanta',
 CDS_PART_NAME='Q_RES_0402LF-10K,1%,1/16W,CHIPA',
 WATTAGE='1/16W',
 TOLERANCE='1%',
 MATERIAL='CHIP',
 VALUE='10K',
 PRIM_FILE='./archive_libs/logical/q_res/chips/chips.prt';

PART_NAME
 R3639 'Q_RES_0402LF-10K,1%,1/16W,CHIPA':;

SECTION_NUMBER 1
 '@S9S_MB_2U_LIB.S9S_MB_2U(SCH_1):PAGE197_I379@PURE_QUANTA.Q_RES(CHIPS)':
 C_PATH='@s9s_mb_2u_lib.s9s_mb_2u(sch_1):page197_i379@pure_quanta.q_res(chips)',
 P_PATH='@s9s_mb_2u_lib.s9s_mb_2u(sch_1):page208_i379@pure_quanta.q_res(chips)',
 PATH='I379',
 DRAWING='@S9S_MB_2U_LIB.S9S_MB_2U(SCH_1):PAGE197',
 PHYS_PAGE='208',
 XY='(-2650,6875)',
 ROT='0',
 VER='1',
 PACK_TYPE='0402LF',
 CDS_LIB='pure_quanta',
 CDS_PART_NAME='Q_RES_0402LF-10K,1%,1/16W,CHIPA',
 WATTAGE='1/16W',
 TOLERANCE='1%',
 MATERIAL='CHIP',
 VALUE='10K',
 PRIM_FILE='./archive_libs/logical/q_res/chips/chips.prt';

PART_NAME
 R3640 'Q_RES_0402LF-10K,1%,1/16W,CHIPA':;

SECTION_NUMBER 1
 '@S9S_MB_2U_LIB.S9S_MB_2U(SCH_1):PAGE197_I380@PURE_QUANTA.Q_RES(CHIPS)':
 C_PATH='@s9s_mb_2u_lib.s9s_mb_2u(sch_1):page197_i380@pure_quanta.q_res(chips)',
 P_PATH='@s9s_mb_2u_lib.s9s_mb_2u(sch_1):page208_i380@pure_quanta.q_res(chips)',
 PATH='I380',
 DRAWING='@S9S_MB_2U_LIB.S9S_MB_2U(SCH_1):PAGE197',
 PHYS_PAGE='208',
 XY='(-2650,6825)',
 ROT='0',
 VER='1',
 PACK_TYPE='0402LF',
 CDS_LIB='pure_quanta',
 CDS_PART_NAME='Q_RES_0402LF-10K,1%,1/16W,CHIPA',
 WATTAGE='1/16W',
 TOLERANCE='1%',
 MATERIAL='CHIP',
 VALUE='10K',
 PRIM_FILE='./archive_libs/logical/q_res/chips/chips.prt';

PART_NAME
 R3641 'Q_RES_0402LF-10K,1%,1/16W,CHIPA':;

SECTION_NUMBER 1
 '@S9S_MB_2U_LIB.S9S_MB_2U(SCH_1):PAGE197_I381@PURE_QUANTA.Q_RES(CHIPS)':
 C_PATH='@s9s_mb_2u_lib.s9s_mb_2u(sch_1):page197_i381@pure_quanta.q_res(chips)',
 P_PATH='@s9s_mb_2u_lib.s9s_mb_2u(sch_1):page208_i381@pure_quanta.q_res(chips)',
 PATH='I381',
 DRAWING='@S9S_MB_2U_LIB.S9S_MB_2U(SCH_1):PAGE197',
 PHYS_PAGE='208',
 XY='(-2650,6775)',
 ROT='0',
 VER='1',
 PACK_TYPE='0402LF',
 CDS_LIB='pure_quanta',
 CDS_PART_NAME='Q_RES_0402LF-10K,1%,1/16W,CHIPA',
 WATTAGE='1/16W',
 TOLERANCE='1%',
 MATERIAL='CHIP',
 VALUE='10K',
 PRIM_FILE='./archive_libs/logical/q_res/chips/chips.prt';

PART_NAME
 R3642 'Q_RES_0402LF-10K,1%,1/16W,CHIPA':;

SECTION_NUMBER 1
 '@S9S_MB_2U_LIB.S9S_MB_2U(SCH_1):PAGE197_I382@PURE_QUANTA.Q_RES(CHIPS)':
 C_PATH='@s9s_mb_2u_lib.s9s_mb_2u(sch_1):page197_i382@pure_quanta.q_res(chips)',
 P_PATH='@s9s_mb_2u_lib.s9s_mb_2u(sch_1):page208_i382@pure_quanta.q_res(chips)',
 PATH='I382',
 DRAWING='@S9S_MB_2U_LIB.S9S_MB_2U(SCH_1):PAGE197',
 PHYS_PAGE='208',
 XY='(-2650,6725)',
 ROT='0',
 VER='1',
 PACK_TYPE='0402LF',
 CDS_LIB='pure_quanta',
 CDS_PART_NAME='Q_RES_0402LF-10K,1%,1/16W,CHIPA',
 WATTAGE='1/16W',
 TOLERANCE='1%',
 MATERIAL='CHIP',
 VALUE='10K',
 PRIM_FILE='./archive_libs/logical/q_res/chips/chips.prt';

PART_NAME
 R3643 'Q_RES_0402LF-10K,1%,1/16W,CHIPA':;

SECTION_NUMBER 1
 '@S9S_MB_2U_LIB.S9S_MB_2U(SCH_1):PAGE197_I383@PURE_QUANTA.Q_RES(CHIPS)':
 C_PATH='@s9s_mb_2u_lib.s9s_mb_2u(sch_1):page197_i383@pure_quanta.q_res(chips)',
 P_PATH='@s9s_mb_2u_lib.s9s_mb_2u(sch_1):page208_i383@pure_quanta.q_res(chips)',
 PATH='I383',
 DRAWING='@S9S_MB_2U_LIB.S9S_MB_2U(SCH_1):PAGE197',
 PHYS_PAGE='208',
 XY='(-2650,6675)',
 ROT='0',
 VER='1',
 PACK_TYPE='0402LF',
 CDS_LIB='pure_quanta',
 CDS_PART_NAME='Q_RES_0402LF-10K,1%,1/16W,CHIPA',
 WATTAGE='1/16W',
 TOLERANCE='1%',
 MATERIAL='CHIP',
 VALUE='10K',
 PRIM_FILE='./archive_libs/logical/q_res/chips/chips.prt';

PART_NAME
 R3645 'Q_RES_2512LF-0.01,1%,1W,CHIP,CA':;

SECTION_NUMBER 1
 '@S9S_MB_2U_LIB.S9S_MB_2U(SCH_1):PAGE295_I152@PURE_QUANTA.Q_RES(CHIPS)':
 C_PATH='@s9s_mb_2u_lib.s9s_mb_2u(sch_1):page295_i152@pure_quanta.q_res(chips)',
 P_PATH='@s9s_mb_2u_lib.s9s_mb_2u(sch_1):page171_i152@pure_quanta.q_res(chips)',
 PATH='I152',
 DRAWING='@S9S_MB_2U_LIB.S9S_MB_2U(SCH_1):PAGE295',
 PHYS_PAGE='171',
 XY='(-600,2675)',
 ROT='0',
 VER='1',
 PACK_TYPE='2512LF',
 LOCATION='R3645',
 CDS_LIB='pure_quanta',
 CDS_PART_NAME='Q_RES_2512LF-0.01,1%,1W,CHIP,CA',
 WATTAGE='1W',
 TOLERANCE='1%',
 MATERIAL='CHIP',
 VALUE='0.01',
 PRIM_FILE='./archive_libs/logical/q_res/chips/chips.prt';

PART_NAME
 R3651 'Q_RES_0402LF-0,5%,1/16W,CHIP,CA':
 ROOM='USB1_BOM1';

SECTION_NUMBER 1
 '@S9S_MB_2U_LIB.S9S_MB_2U(SCH_1):PAGE155_I138@PURE_QUANTA.Q_RES(CHIPS)':
 C_PATH='@s9s_mb_2u_lib.s9s_mb_2u(sch_1):page155_i138@pure_quanta.q_res(chips)',
 P_PATH='@s9s_mb_2u_lib.s9s_mb_2u(sch_1):page152_i138@pure_quanta.q_res(chips)',
 PATH='I138',
 DRAWING='@S9S_MB_2U_LIB.S9S_MB_2U(SCH_1):PAGE155',
 PHYS_PAGE='152',
 XY='(2550,3925)',
 ROT='0',
 VER='1',
 PACK_TYPE='0402LF',
 CDS_LIB='pure_quanta',
 CDS_PART_NAME='Q_RES_0402LF-0,5%,1/16W,CHIP,CA',
 WATTAGE='1/16W',
 TOLERANCE='5%',
 MATERIAL='CHIP',
 ROOM='USB1_BOM1',
 VALUE='0',
 PRIM_FILE='./archive_libs/logical/q_res/chips/chips.prt';

PART_NAME
 R3652 'Q_RES_0402LF-0,5%,1/16W,CHIP,CA':
 ROOM='USB1_BOM1';

SECTION_NUMBER 1
 '@S9S_MB_2U_LIB.S9S_MB_2U(SCH_1):PAGE155_I137@PURE_QUANTA.Q_RES(CHIPS)':
 C_PATH='@s9s_mb_2u_lib.s9s_mb_2u(sch_1):page155_i137@pure_quanta.q_res(chips)',
 P_PATH='@s9s_mb_2u_lib.s9s_mb_2u(sch_1):page152_i137@pure_quanta.q_res(chips)',
 PATH='I137',
 DRAWING='@S9S_MB_2U_LIB.S9S_MB_2U(SCH_1):PAGE155',
 PHYS_PAGE='152',
 XY='(2550,3875)',
 ROT='0',
 VER='1',
 PACK_TYPE='0402LF',
 CDS_LIB='pure_quanta',
 CDS_PART_NAME='Q_RES_0402LF-0,5%,1/16W,CHIP,CA',
 WATTAGE='1/16W',
 TOLERANCE='5%',
 MATERIAL='CHIP',
 ROOM='USB1_BOM1',
 VALUE='0',
 PRIM_FILE='./archive_libs/logical/q_res/chips/chips.prt';

PART_NAME
 R3653 'Q_RES_0402LF-680,1%,1/16W,CHIPA':
 ROOM='USB1_BOM1';

SECTION_NUMBER 1
 '@S9S_MB_2U_LIB.S9S_MB_2U(SCH_1):PAGE155_I139@PURE_QUANTA.Q_RES(CHIPS)':
 C_PATH='@s9s_mb_2u_lib.s9s_mb_2u(sch_1):page155_i139@pure_quanta.q_res(chips)',
 P_PATH='@s9s_mb_2u_lib.s9s_mb_2u(sch_1):page152_i139@pure_quanta.q_res(chips)',
 PATH='I139',
 DRAWING='@S9S_MB_2U_LIB.S9S_MB_2U(SCH_1):PAGE155',
 PHYS_PAGE='152',
 XY='(-1075,3100)',
 ROT='0',
 VER='2',
 PACK_TYPE='0402LF',
 CDS_LIB='pure_quanta',
 CDS_PART_NAME='Q_RES_0402LF-680,1%,1/16W,CHIPA',
 WATTAGE='1/16W',
 TOLERANCE='1%',
 MATERIAL='CHIP',
 ROOM='USB1_BOM1',
 VALUE='680',
 PRIM_FILE='./archive_libs/logical/q_res/chips/chips.prt';

PART_NAME
 R3654 'Q_RES_0402LF-33.2,1%,1/16W,CHIA':
 ROOM='USB1_BOM1';

SECTION_NUMBER 1
 '@S9S_MB_2U_LIB.S9S_MB_2U(SCH_1):PAGE155_I155@PURE_QUANTA.Q_RES(CHIPS)':
 C_PATH='@s9s_mb_2u_lib.s9s_mb_2u(sch_1):page155_i155@pure_quanta.q_res(chips)',
 P_PATH='@s9s_mb_2u_lib.s9s_mb_2u(sch_1):page152_i155@pure_quanta.q_res(chips)',
 PATH='I155',
 DRAWING='@S9S_MB_2U_LIB.S9S_MB_2U(SCH_1):PAGE155',
 PHYS_PAGE='152',
 XY='(-2725,3425)',
 ROT='0',
 VER='1',
 PACK_TYPE='0402LF',
 CDS_LIB='pure_quanta',
 CDS_PART_NAME='Q_RES_0402LF-33.2,1%,1/16W,CHIA',
 WATTAGE='1/16W',
 TOLERANCE='1%',
 MATERIAL='CHIP',
 ROOM='USB1_BOM1',
 VALUE='33.2',
 PRIM_FILE='./archive_libs/logical/q_res/chips/chips.prt';

PART_NAME
 R3655 'Q_RES_0402LF-0,5%,1/16W,CHIP,CA':
 ROOM='USB1_BOM1';

SECTION_NUMBER 1
 '@S9S_MB_2U_LIB.S9S_MB_2U(SCH_1):PAGE155_I161@PURE_QUANTA.Q_RES(CHIPS)':
 C_PATH='@s9s_mb_2u_lib.s9s_mb_2u(sch_1):page155_i161@pure_quanta.q_res(chips)',
 P_PATH='@s9s_mb_2u_lib.s9s_mb_2u(sch_1):page152_i161@pure_quanta.q_res(chips)',
 PATH='I161',
 DRAWING='@S9S_MB_2U_LIB.S9S_MB_2U(SCH_1):PAGE155',
 PHYS_PAGE='152',
 XY='(-3750,4800)',
 ROT='0',
 VER='1',
 PACK_TYPE='0402LF',
 CDS_LIB='pure_quanta',
 CDS_PART_NAME='Q_RES_0402LF-0,5%,1/16W,CHIP,CA',
 WATTAGE='1/16W',
 TOLERANCE='5%',
 MATERIAL='CHIP',
 ROOM='USB1_BOM1',
 VALUE='0',
 PRIM_FILE='./archive_libs/logical/q_res/chips/chips.prt';

PART_NAME
 R3656 'Q_RES_0402LF-10K,1%,1/16W,EMPTA':;

SECTION_NUMBER 1
 '@S9S_MB_2U_LIB.S9S_MB_2U(SCH_1):PAGE155_I194@PURE_QUANTA.Q_RES(CHIPS)':
 C_PATH='@s9s_mb_2u_lib.s9s_mb_2u(sch_1):page155_i194@pure_quanta.q_res(chips)',
 P_PATH='@s9s_mb_2u_lib.s9s_mb_2u(sch_1):page152_i194@pure_quanta.q_res(chips)',
 PATH='I194',
 DRAWING='@S9S_MB_2U_LIB.S9S_MB_2U(SCH_1):PAGE155',
 PHYS_PAGE='152',
 XY='(-1550,2275)',
 ROT='0',
 VER='1',
 PACK_TYPE='0402LF',
 CDS_LIB='pure_quanta',
 CDS_PART_NAME='Q_RES_0402LF-10K,1%,1/16W,EMPTA',
 WATTAGE='1/16W',
 TOLERANCE='1%',
 MATERIAL='EMPTY',
 VALUE='10K',
 PRIM_FILE='./archive_libs/logical/q_res/chips/chips.prt';

PART_NAME
 R3657 'Q_RES_0402LF-10K,1%,1/16W,EMPTA':;

SECTION_NUMBER 1
 '@S9S_MB_2U_LIB.S9S_MB_2U(SCH_1):PAGE155_I195@PURE_QUANTA.Q_RES(CHIPS)':
 C_PATH='@s9s_mb_2u_lib.s9s_mb_2u(sch_1):page155_i195@pure_quanta.q_res(chips)',
 P_PATH='@s9s_mb_2u_lib.s9s_mb_2u(sch_1):page152_i195@pure_quanta.q_res(chips)',
 PATH='I195',
 DRAWING='@S9S_MB_2U_LIB.S9S_MB_2U(SCH_1):PAGE155',
 PHYS_PAGE='152',
 XY='(-1550,2125)',
 ROT='0',
 VER='1',
 PACK_TYPE='0402LF',
 CDS_LIB='pure_quanta',
 CDS_PART_NAME='Q_RES_0402LF-10K,1%,1/16W,EMPTA',
 WATTAGE='1/16W',
 TOLERANCE='1%',
 MATERIAL='EMPTY',
 VALUE='10K',
 PRIM_FILE='./archive_libs/logical/q_res/chips/chips.prt';

PART_NAME
 R3658 'Q_RES_0402LF-10K,1%,1/16W,EMPTA':;

SECTION_NUMBER 1
 '@S9S_MB_2U_LIB.S9S_MB_2U(SCH_1):PAGE155_I196@PURE_QUANTA.Q_RES(CHIPS)':
 C_PATH='@s9s_mb_2u_lib.s9s_mb_2u(sch_1):page155_i196@pure_quanta.q_res(chips)',
 P_PATH='@s9s_mb_2u_lib.s9s_mb_2u(sch_1):page152_i196@pure_quanta.q_res(chips)',
 PATH='I196',
 DRAWING='@S9S_MB_2U_LIB.S9S_MB_2U(SCH_1):PAGE155',
 PHYS_PAGE='152',
 XY='(-1550,2000)',
 ROT='0',
 VER='1',
 PACK_TYPE='0402LF',
 CDS_LIB='pure_quanta',
 CDS_PART_NAME='Q_RES_0402LF-10K,1%,1/16W,EMPTA',
 WATTAGE='1/16W',
 TOLERANCE='1%',
 MATERIAL='EMPTY',
 VALUE='10K',
 PRIM_FILE='./archive_libs/logical/q_res/chips/chips.prt';

PART_NAME
 R3659 'Q_RES_0402LF-10K,1%,1/16W,EMPTA':;

SECTION_NUMBER 1
 '@S9S_MB_2U_LIB.S9S_MB_2U(SCH_1):PAGE155_I198@PURE_QUANTA.Q_RES(CHIPS)':
 C_PATH='@s9s_mb_2u_lib.s9s_mb_2u(sch_1):page155_i198@pure_quanta.q_res(chips)',
 P_PATH='@s9s_mb_2u_lib.s9s_mb_2u(sch_1):page152_i198@pure_quanta.q_res(chips)',
 PATH='I198',
 DRAWING='@S9S_MB_2U_LIB.S9S_MB_2U(SCH_1):PAGE155',
 PHYS_PAGE='152',
 XY='(-1550,1875)',
 ROT='0',
 VER='1',
 PACK_TYPE='0402LF',
 CDS_LIB='pure_quanta',
 CDS_PART_NAME='Q_RES_0402LF-10K,1%,1/16W,EMPTA',
 WATTAGE='1/16W',
 TOLERANCE='1%',
 MATERIAL='EMPTY',
 VALUE='10K',
 PRIM_FILE='./archive_libs/logical/q_res/chips/chips.prt';

PART_NAME
 R3660 'Q_RES_0402LF-10K,1%,1/16W,CHIPA':
 ROOM='USB1_BOM1';

SECTION_NUMBER 1
 '@S9S_MB_2U_LIB.S9S_MB_2U(SCH_1):PAGE155_I159@PURE_QUANTA.Q_RES(CHIPS)':
 C_PATH='@s9s_mb_2u_lib.s9s_mb_2u(sch_1):page155_i159@pure_quanta.q_res(chips)',
 P_PATH='@s9s_mb_2u_lib.s9s_mb_2u(sch_1):page152_i159@pure_quanta.q_res(chips)',
 PATH='I159',
 DRAWING='@S9S_MB_2U_LIB.S9S_MB_2U(SCH_1):PAGE155',
 PHYS_PAGE='152',
 XY='(-1900,3775)',
 ROT='0',
 VER='2',
 PACK_TYPE='0402LF',
 CDS_LIB='pure_quanta',
 CDS_PART_NAME='Q_RES_0402LF-10K,1%,1/16W,CHIPA',
 WATTAGE='1/16W',
 TOLERANCE='1%',
 MATERIAL='CHIP',
 ROOM='USB1_BOM1',
 VALUE='10K',
 PRIM_FILE='./archive_libs/logical/q_res/chips/chips.prt';

PART_NAME
 R3661 'Q_RES_0402LF-47K,0.1%,1/16W,EMA':;

SECTION_NUMBER 1
 '@S9S_MB_2U_LIB.S9S_MB_2U(SCH_1):PAGE155_I201@PURE_QUANTA.Q_RES(CHIPS)':
 C_PATH='@s9s_mb_2u_lib.s9s_mb_2u(sch_1):page155_i201@pure_quanta.q_res(chips)',
 P_PATH='@s9s_mb_2u_lib.s9s_mb_2u(sch_1):page152_i201@pure_quanta.q_res(chips)',
 PATH='I201',
 DRAWING='@S9S_MB_2U_LIB.S9S_MB_2U(SCH_1):PAGE155',
 PHYS_PAGE='152',
 XY='(-1900,3100)',
 ROT='1',
 VER='1',
 PACK_TYPE='0402LF',
 LOCATION='R3661',
 CDS_LIB='pure_quanta',
 CDS_PART_NAME='Q_RES_0402LF-47K,0.1%,1/16W,EMA',
 WATTAGE='1/16W',
 TOLERANCE='0.1%',
 MATERIAL='EMPTY',
 VALUE='47K',
 PRIM_FILE='./archive_libs/logical/q_res/chips/chips.prt';

PART_NAME
 R3662 'Q_RES_0402LF-0,5%,1/16W,CHIP,CA':
 ROOM='USB1_BOM1';

SECTION_NUMBER 1
 '@S9S_MB_2U_LIB.S9S_MB_2U(SCH_1):PAGE155_I167@PURE_QUANTA.Q_RES(CHIPS)':
 C_PATH='@s9s_mb_2u_lib.s9s_mb_2u(sch_1):page155_i167@pure_quanta.q_res(chips)',
 P_PATH='@s9s_mb_2u_lib.s9s_mb_2u(sch_1):page152_i167@pure_quanta.q_res(chips)',
 PATH='I167',
 DRAWING='@S9S_MB_2U_LIB.S9S_MB_2U(SCH_1):PAGE155',
 PHYS_PAGE='152',
 XY='(-1025,3925)',
 ROT='0',
 VER='1',
 PACK_TYPE='0402LF',
 CDS_LIB='pure_quanta',
 CDS_PART_NAME='Q_RES_0402LF-0,5%,1/16W,CHIP,CA',
 WATTAGE='1/16W',
 TOLERANCE='5%',
 MATERIAL='CHIP',
 ROOM='USB1_BOM1',
 VALUE='0',
 PRIM_FILE='./archive_libs/logical/q_res/chips/chips.prt';

PART_NAME
 R3663 'Q_RES_0402LF-10K,1%,1/16W,CHIPA':
 ROOM='USB1_BOM1';

SECTION_NUMBER 1
 '@S9S_MB_2U_LIB.S9S_MB_2U(SCH_1):PAGE155_I186@PURE_QUANTA.Q_RES(CHIPS)':
 C_PATH='@s9s_mb_2u_lib.s9s_mb_2u(sch_1):page155_i186@pure_quanta.q_res(chips)',
 P_PATH='@s9s_mb_2u_lib.s9s_mb_2u(sch_1):page152_i186@pure_quanta.q_res(chips)',
 PATH='I186',
 DRAWING='@S9S_MB_2U_LIB.S9S_MB_2U(SCH_1):PAGE155',
 PHYS_PAGE='152',
 XY='(-4150,2950)',
 ROT='0',
 VER='2',
 PACK_TYPE='0402LF',
 CDS_LIB='pure_quanta',
 CDS_PART_NAME='Q_RES_0402LF-10K,1%,1/16W,CHIPA',
 WATTAGE='1/16W',
 TOLERANCE='1%',
 MATERIAL='CHIP',
 ROOM='USB1_BOM1',
 VALUE='10K',
 PRIM_FILE='./archive_libs/logical/q_res/chips/chips.prt';

PART_NAME
 R3664 'Q_RES_0402LF-10K,1%,1/16W,EMPTA':;

SECTION_NUMBER 1
 '@S9S_MB_2U_LIB.S9S_MB_2U(SCH_1):PAGE155_I187@PURE_QUANTA.Q_RES(CHIPS)':
 C_PATH='@s9s_mb_2u_lib.s9s_mb_2u(sch_1):page155_i187@pure_quanta.q_res(chips)',
 P_PATH='@s9s_mb_2u_lib.s9s_mb_2u(sch_1):page152_i187@pure_quanta.q_res(chips)',
 PATH='I187',
 DRAWING='@S9S_MB_2U_LIB.S9S_MB_2U(SCH_1):PAGE155',
 PHYS_PAGE='152',
 XY='(-4150,2350)',
 ROT='0',
 VER='2',
 PACK_TYPE='0402LF',
 CDS_LIB='pure_quanta',
 CDS_PART_NAME='Q_RES_0402LF-10K,1%,1/16W,EMPTA',
 WATTAGE='1/16W',
 TOLERANCE='1%',
 MATERIAL='EMPTY',
 VALUE='10K',
 PRIM_FILE='./archive_libs/logical/q_res/chips/chips.prt';

PART_NAME
 R3665 'Q_RES_0402LF-100K,1%,1/16W,CHIA':
 ROOM='USB1_BOM1';

SECTION_NUMBER 1
 '@S9S_MB_2U_LIB.S9S_MB_2U(SCH_1):PAGE155_I182@PURE_QUANTA.Q_RES(CHIPS)':
 C_PATH='@s9s_mb_2u_lib.s9s_mb_2u(sch_1):page155_i182@pure_quanta.q_res(chips)',
 P_PATH='@s9s_mb_2u_lib.s9s_mb_2u(sch_1):page152_i182@pure_quanta.q_res(chips)',
 PATH='I182',
 DRAWING='@S9S_MB_2U_LIB.S9S_MB_2U(SCH_1):PAGE155',
 PHYS_PAGE='152',
 XY='(-750,3075)',
 ROT='0',
 VER='2',
 PACK_TYPE='0402LF',
 CDS_LIB='pure_quanta',
 CDS_PART_NAME='Q_RES_0402LF-100K,1%,1/16W,CHIA',
 WATTAGE='1/16W',
 TOLERANCE='1%',
 MATERIAL='CHIP',
 ROOM='USB1_BOM1',
 VALUE='100K',
 PRIM_FILE='./archive_libs/logical/q_res/chips/chips.prt';

PART_NAME
 R3666 'Q_RES_0402LF-0,5%,1/16W,CHIP,CA':
 ROOM='USB1_BOM1';

SECTION_NUMBER 1
 '@S9S_MB_2U_LIB.S9S_MB_2U(SCH_1):PAGE155_I199@PURE_QUANTA.Q_RES(CHIPS)':
 C_PATH='@s9s_mb_2u_lib.s9s_mb_2u(sch_1):page155_i199@pure_quanta.q_res(chips)',
 P_PATH='@s9s_mb_2u_lib.s9s_mb_2u(sch_1):page152_i199@pure_quanta.q_res(chips)',
 PATH='I199',
 DRAWING='@S9S_MB_2U_LIB.S9S_MB_2U(SCH_1):PAGE155',
 PHYS_PAGE='152',
 XY='(1375,4275)',
 ROT='0',
 VER='1',
 PACK_TYPE='0402LF',
 CDS_LIB='pure_quanta',
 CDS_PART_NAME='Q_RES_0402LF-0,5%,1/16W,CHIP,CA',
 WATTAGE='1/16W',
 TOLERANCE='5%',
 MATERIAL='CHIP',
 ROOM='USB1_BOM1',
 VALUE='0',
 PRIM_FILE='./archive_libs/logical/q_res/chips/chips.prt';

PART_NAME
 R3667 'Q_RES_0402LF-1K,1%,1/16W,EMPTYA':;

SECTION_NUMBER 1
 '@S9S_MB_2U_LIB.S9S_MB_2U(SCH_1):PAGE239_I224@PURE_QUANTA.Q_RES(CHIPS)':
 C_PATH='@s9s_mb_2u_lib.s9s_mb_2u(sch_1):page239_i224@pure_quanta.q_res(chips)',
 P_PATH='@s9s_mb_2u_lib.s9s_mb_2u(sch_1):page250_i224@pure_quanta.q_res(chips)',
 PATH='I224',
 DRAWING='@S9S_MB_2U_LIB.S9S_MB_2U(SCH_1):PAGE239',
 PHYS_PAGE='250',
 XY='(3350,525)',
 ROT='0',
 VER='2',
 PACK_TYPE='0402LF',
 CDS_LIB='pure_quanta',
 CDS_PART_NAME='Q_RES_0402LF-1K,1%,1/16W,EMPTYA',
 WATTAGE='1/16W',
 TOLERANCE='1%',
 MATERIAL='EMPTY',
 VALUE='1K',
 PRIM_FILE='./archive_libs/logical/q_res/chips/chips.prt';

PART_NAME
 R3668 'Q_RES_0402LF-1K,1%,1/16W,CHIP,A':
 ROOM='ADC1_BOM2';

SECTION_NUMBER 1
 '@S9S_MB_2U_LIB.S9S_MB_2U(SCH_1):PAGE239_I223@PURE_QUANTA.Q_RES(CHIPS)':
 C_PATH='@s9s_mb_2u_lib.s9s_mb_2u(sch_1):page239_i223@pure_quanta.q_res(chips)',
 P_PATH='@s9s_mb_2u_lib.s9s_mb_2u(sch_1):page250_i223@pure_quanta.q_res(chips)',
 PATH='I223',
 DRAWING='@S9S_MB_2U_LIB.S9S_MB_2U(SCH_1):PAGE239',
 PHYS_PAGE='250',
 XY='(3350,-75)',
 ROT='0',
 VER='2',
 PACK_TYPE='0402LF',
 CDS_LIB='pure_quanta',
 CDS_PART_NAME='Q_RES_0402LF-1K,1%,1/16W,CHIP,A',
 WATTAGE='1/16W',
 TOLERANCE='1%',
 MATERIAL='CHIP',
 ROOM='ADC1_BOM2',
 VALUE='1K',
 PRIM_FILE='./archive_libs/logical/q_res/chips/chips.prt';

PART_NAME
 R3669 'Q_RES_0402LF-1K,1%,1/16W,EMPTYA':;

SECTION_NUMBER 1
 '@S9S_MB_2U_LIB.S9S_MB_2U(SCH_1):PAGE239_I228@PURE_QUANTA.Q_RES(CHIPS)':
 C_PATH='@s9s_mb_2u_lib.s9s_mb_2u(sch_1):page239_i228@pure_quanta.q_res(chips)',
 P_PATH='@s9s_mb_2u_lib.s9s_mb_2u(sch_1):page250_i228@pure_quanta.q_res(chips)',
 PATH='I228',
 DRAWING='@S9S_MB_2U_LIB.S9S_MB_2U(SCH_1):PAGE239',
 PHYS_PAGE='250',
 XY='(3600,525)',
 ROT='0',
 VER='2',
 PACK_TYPE='0402LF',
 CDS_LIB='pure_quanta',
 CDS_PART_NAME='Q_RES_0402LF-1K,1%,1/16W,EMPTYA',
 WATTAGE='1/16W',
 TOLERANCE='1%',
 MATERIAL='EMPTY',
 VALUE='1K',
 PRIM_FILE='./archive_libs/logical/q_res/chips/chips.prt';

PART_NAME
 R3670 'Q_RES_0402LF-1K,1%,1/16W,CHIP,A':
 ROOM='ADC1_BOM2';

SECTION_NUMBER 1
 '@S9S_MB_2U_LIB.S9S_MB_2U(SCH_1):PAGE239_I227@PURE_QUANTA.Q_RES(CHIPS)':
 C_PATH='@s9s_mb_2u_lib.s9s_mb_2u(sch_1):page239_i227@pure_quanta.q_res(chips)',
 P_PATH='@s9s_mb_2u_lib.s9s_mb_2u(sch_1):page250_i227@pure_quanta.q_res(chips)',
 PATH='I227',
 DRAWING='@S9S_MB_2U_LIB.S9S_MB_2U(SCH_1):PAGE239',
 PHYS_PAGE='250',
 XY='(3600,-75)',
 ROT='0',
 VER='2',
 PACK_TYPE='0402LF',
 CDS_LIB='pure_quanta',
 CDS_PART_NAME='Q_RES_0402LF-1K,1%,1/16W,CHIP,A',
 WATTAGE='1/16W',
 TOLERANCE='1%',
 MATERIAL='CHIP',
 ROOM='ADC1_BOM2',
 VALUE='1K',
 PRIM_FILE='./archive_libs/logical/q_res/chips/chips.prt';

PART_NAME
 R3671 'Q_RES_0402LF-0,5%,1/16W,CHIP,CA':
 ROOM='ADC1_BOM2';

SECTION_NUMBER 1
 '@S9S_MB_2U_LIB.S9S_MB_2U(SCH_1):PAGE239_I110@PURE_QUANTA.Q_RES(CHIPS)':
 C_PATH='@s9s_mb_2u_lib.s9s_mb_2u(sch_1):page239_i110@pure_quanta.q_res(chips)',
 P_PATH='@s9s_mb_2u_lib.s9s_mb_2u(sch_1):page250_i110@pure_quanta.q_res(chips)',
 PATH='I110',
 DRAWING='@S9S_MB_2U_LIB.S9S_MB_2U(SCH_1):PAGE239',
 PHYS_PAGE='250',
 XY='(6350,250)',
 ROT='0',
 VER='1',
 PACK_TYPE='0402LF',
 CDS_LIB='pure_quanta',
 CDS_PART_NAME='Q_RES_0402LF-0,5%,1/16W,CHIP,CA',
 WATTAGE='1/16W',
 TOLERANCE='5%',
 MATERIAL='CHIP',
 ROOM='ADC1_BOM2',
 VALUE='0',
 PRIM_FILE='./archive_libs/logical/q_res/chips/chips.prt';

PART_NAME
 R3672 'Q_RES_0402LF-0,5%,1/16W,CHIP,CA':
 ROOM='ADC1_BOM2';

SECTION_NUMBER 1
 '@S9S_MB_2U_LIB.S9S_MB_2U(SCH_1):PAGE239_I111@PURE_QUANTA.Q_RES(CHIPS)':
 C_PATH='@s9s_mb_2u_lib.s9s_mb_2u(sch_1):page239_i111@pure_quanta.q_res(chips)',
 P_PATH='@s9s_mb_2u_lib.s9s_mb_2u(sch_1):page250_i111@pure_quanta.q_res(chips)',
 PATH='I111',
 DRAWING='@S9S_MB_2U_LIB.S9S_MB_2U(SCH_1):PAGE239',
 PHYS_PAGE='250',
 XY='(6350,200)',
 ROT='0',
 VER='1',
 PACK_TYPE='0402LF',
 CDS_LIB='pure_quanta',
 CDS_PART_NAME='Q_RES_0402LF-0,5%,1/16W,CHIP,CA',
 WATTAGE='1/16W',
 TOLERANCE='5%',
 MATERIAL='CHIP',
 ROOM='ADC1_BOM2',
 VALUE='0',
 PRIM_FILE='./archive_libs/logical/q_res/chips/chips.prt';

PART_NAME
 R3679 'Q_RES_0402LF-0,5%,1/16W,EMPTY,A':
 ROOM='ADC1_BOM1';

SECTION_NUMBER 1
 '@S9S_MB_2U_LIB.S9S_MB_2U(SCH_1):PAGE239_I209@PURE_QUANTA.Q_RES(CHIPS)':
 C_PATH='@s9s_mb_2u_lib.s9s_mb_2u(sch_1):page239_i209@pure_quanta.q_res(chips)',
 P_PATH='@s9s_mb_2u_lib.s9s_mb_2u(sch_1):page250_i209@pure_quanta.q_res(chips)',
 PATH='I209',
 DRAWING='@S9S_MB_2U_LIB.S9S_MB_2U(SCH_1):PAGE239',
 PHYS_PAGE='250',
 XY='(-200,1400)',
 ROT='0',
 VER='1',
 PACK_TYPE='0402LF',
 CDS_LIB='pure_quanta',
 CDS_PART_NAME='Q_RES_0402LF-0,5%,1/16W,EMPTY,A',
 WATTAGE='1/16W',
 TOLERANCE='5%',
 MATERIAL='EMPTY',
 ROOM='ADC1_BOM1',
 VALUE='0',
 PRIM_FILE='./archive_libs/logical/q_res/chips/chips.prt';

PART_NAME
 R3680 'Q_RES_0402LF-0,5%,1/16W,CHIP,CA':
 ROOM='ADC1_BOM2';

SECTION_NUMBER 1
 '@S9S_MB_2U_LIB.S9S_MB_2U(SCH_1):PAGE239_I210@PURE_QUANTA.Q_RES(CHIPS)':
 C_PATH='@s9s_mb_2u_lib.s9s_mb_2u(sch_1):page239_i210@pure_quanta.q_res(chips)',
 P_PATH='@s9s_mb_2u_lib.s9s_mb_2u(sch_1):page250_i210@pure_quanta.q_res(chips)',
 PATH='I210',
 DRAWING='@S9S_MB_2U_LIB.S9S_MB_2U(SCH_1):PAGE239',
 PHYS_PAGE='250',
 XY='(-200,1250)',
 ROT='0',
 VER='1',
 PACK_TYPE='0402LF',
 CDS_LIB='pure_quanta',
 CDS_PART_NAME='Q_RES_0402LF-0,5%,1/16W,CHIP,CA',
 WATTAGE='1/16W',
 TOLERANCE='5%',
 MATERIAL='CHIP',
 ROOM='ADC1_BOM2',
 VALUE='0',
 PRIM_FILE='./archive_libs/logical/q_res/chips/chips.prt';

PART_NAME
 R3681 'Q_RES_0402LF-0,5%,1/16W,EMPTY,A':
 ROOM='ADC1_BOM1';

SECTION_NUMBER 1
 '@S9S_MB_2U_LIB.S9S_MB_2U(SCH_1):PAGE239_I176@PURE_QUANTA.Q_RES(CHIPS)':
 C_PATH='@s9s_mb_2u_lib.s9s_mb_2u(sch_1):page239_i176@pure_quanta.q_res(chips)',
 P_PATH='@s9s_mb_2u_lib.s9s_mb_2u(sch_1):page250_i176@pure_quanta.q_res(chips)',
 PATH='I176',
 DRAWING='@S9S_MB_2U_LIB.S9S_MB_2U(SCH_1):PAGE239',
 PHYS_PAGE='250',
 XY='(-300,5175)',
 ROT='0',
 VER='1',
 PACK_TYPE='0402LF',
 CDS_LIB='pure_quanta',
 CDS_PART_NAME='Q_RES_0402LF-0,5%,1/16W,EMPTY,A',
 WATTAGE='1/16W',
 TOLERANCE='5%',
 MATERIAL='EMPTY',
 ROOM='ADC1_BOM1',
 VALUE='0',
 PRIM_FILE='./archive_libs/logical/q_res/chips/chips.prt';

PART_NAME
 R3682 'Q_RES_0402LF-0,5%,1/16W,CHIP,CA':
 ROOM='ADC1_BOM2';

SECTION_NUMBER 1
 '@S9S_MB_2U_LIB.S9S_MB_2U(SCH_1):PAGE239_I179@PURE_QUANTA.Q_RES(CHIPS)':
 C_PATH='@s9s_mb_2u_lib.s9s_mb_2u(sch_1):page239_i179@pure_quanta.q_res(chips)',
 P_PATH='@s9s_mb_2u_lib.s9s_mb_2u(sch_1):page250_i179@pure_quanta.q_res(chips)',
 PATH='I179',
 DRAWING='@S9S_MB_2U_LIB.S9S_MB_2U(SCH_1):PAGE239',
 PHYS_PAGE='250',
 XY='(-300,5025)',
 ROT='0',
 VER='1',
 PACK_TYPE='0402LF',
 CDS_LIB='pure_quanta',
 CDS_PART_NAME='Q_RES_0402LF-0,5%,1/16W,CHIP,CA',
 WATTAGE='1/16W',
 TOLERANCE='5%',
 MATERIAL='CHIP',
 ROOM='ADC1_BOM2',
 VALUE='0',
 PRIM_FILE='./archive_libs/logical/q_res/chips/chips.prt';

PART_NAME
 R3683 'Q_RES_0402LF-0,5%,1/16W,EMPTY,A':
 ROOM='ADC1_BOM1';

SECTION_NUMBER 1
 '@S9S_MB_2U_LIB.S9S_MB_2U(SCH_1):PAGE239_I199@PURE_QUANTA.Q_RES(CHIPS)':
 C_PATH='@s9s_mb_2u_lib.s9s_mb_2u(sch_1):page239_i199@pure_quanta.q_res(chips)',
 P_PATH='@s9s_mb_2u_lib.s9s_mb_2u(sch_1):page250_i199@pure_quanta.q_res(chips)',
 PATH='I199',
 DRAWING='@S9S_MB_2U_LIB.S9S_MB_2U(SCH_1):PAGE239',
 PHYS_PAGE='250',
 XY='(-375,3850)',
 ROT='0',
 VER='1',
 PACK_TYPE='0402LF',
 CDS_LIB='pure_quanta',
 CDS_PART_NAME='Q_RES_0402LF-0,5%,1/16W,EMPTY,A',
 WATTAGE='1/16W',
 TOLERANCE='5%',
 MATERIAL='EMPTY',
 ROOM='ADC1_BOM1',
 VALUE='0',
 PRIM_FILE='./archive_libs/logical/q_res/chips/chips.prt';

PART_NAME
 R3684 'Q_RES_0402LF-0,5%,1/16W,CHIP,CA':
 ROOM='ADC1_BOM2';

SECTION_NUMBER 1
 '@S9S_MB_2U_LIB.S9S_MB_2U(SCH_1):PAGE239_I200@PURE_QUANTA.Q_RES(CHIPS)':
 C_PATH='@s9s_mb_2u_lib.s9s_mb_2u(sch_1):page239_i200@pure_quanta.q_res(chips)',
 P_PATH='@s9s_mb_2u_lib.s9s_mb_2u(sch_1):page250_i200@pure_quanta.q_res(chips)',
 PATH='I200',
 DRAWING='@S9S_MB_2U_LIB.S9S_MB_2U(SCH_1):PAGE239',
 PHYS_PAGE='250',
 XY='(-375,3700)',
 ROT='0',
 VER='1',
 PACK_TYPE='0402LF',
 CDS_LIB='pure_quanta',
 CDS_PART_NAME='Q_RES_0402LF-0,5%,1/16W,CHIP,CA',
 WATTAGE='1/16W',
 TOLERANCE='5%',
 MATERIAL='CHIP',
 ROOM='ADC1_BOM2',
 VALUE='0',
 PRIM_FILE='./archive_libs/logical/q_res/chips/chips.prt';

PART_NAME
 R3685 'Q_RES_0402LF-0,5%,1/16W,EMPTY,A':
 ROOM='ADC1_BOM1';

SECTION_NUMBER 1
 '@S9S_MB_2U_LIB.S9S_MB_2U(SCH_1):PAGE239_I190@PURE_QUANTA.Q_RES(CHIPS)':
 C_PATH='@s9s_mb_2u_lib.s9s_mb_2u(sch_1):page239_i190@pure_quanta.q_res(chips)',
 P_PATH='@s9s_mb_2u_lib.s9s_mb_2u(sch_1):page250_i190@pure_quanta.q_res(chips)',
 PATH='I190',
 DRAWING='@S9S_MB_2U_LIB.S9S_MB_2U(SCH_1):PAGE239',
 PHYS_PAGE='250',
 XY='(-375,2700)',
 ROT='0',
 VER='1',
 PACK_TYPE='0402LF',
 CDS_LIB='pure_quanta',
 CDS_PART_NAME='Q_RES_0402LF-0,5%,1/16W,EMPTY,A',
 WATTAGE='1/16W',
 TOLERANCE='5%',
 MATERIAL='EMPTY',
 ROOM='ADC1_BOM1',
 VALUE='0',
 PRIM_FILE='./archive_libs/logical/q_res/chips/chips.prt';

PART_NAME
 R3686 'Q_RES_0402LF-0,5%,1/16W,CHIP,CA':
 ROOM='ADC1_BOM2';

SECTION_NUMBER 1
 '@S9S_MB_2U_LIB.S9S_MB_2U(SCH_1):PAGE239_I191@PURE_QUANTA.Q_RES(CHIPS)':
 C_PATH='@s9s_mb_2u_lib.s9s_mb_2u(sch_1):page239_i191@pure_quanta.q_res(chips)',
 P_PATH='@s9s_mb_2u_lib.s9s_mb_2u(sch_1):page250_i191@pure_quanta.q_res(chips)',
 PATH='I191',
 DRAWING='@S9S_MB_2U_LIB.S9S_MB_2U(SCH_1):PAGE239',
 PHYS_PAGE='250',
 XY='(-375,2550)',
 ROT='0',
 VER='1',
 PACK_TYPE='0402LF',
 CDS_LIB='pure_quanta',
 CDS_PART_NAME='Q_RES_0402LF-0,5%,1/16W,CHIP,CA',
 WATTAGE='1/16W',
 TOLERANCE='5%',
 MATERIAL='CHIP',
 ROOM='ADC1_BOM2',
 VALUE='0',
 PRIM_FILE='./archive_libs/logical/q_res/chips/chips.prt';

PART_NAME
 R3687 'Q_RES_0402LF-0,5%,1/16W,EMPTY,A':
 ROOM='ADC1_BOM1';

SECTION_NUMBER 1
 '@S9S_MB_2U_LIB.S9S_MB_2U(SCH_1):PAGE239_I240@PURE_QUANTA.Q_RES(CHIPS)':
 C_PATH='@s9s_mb_2u_lib.s9s_mb_2u(sch_1):page239_i240@pure_quanta.q_res(chips)',
 P_PATH='@s9s_mb_2u_lib.s9s_mb_2u(sch_1):page250_i240@pure_quanta.q_res(chips)',
 PATH='I240',
 DRAWING='@S9S_MB_2U_LIB.S9S_MB_2U(SCH_1):PAGE239',
 PHYS_PAGE='250',
 XY='(475,500)',
 ROT='0',
 VER='1',
 PACK_TYPE='0402LF',
 CDS_LIB='pure_quanta',
 CDS_PART_NAME='Q_RES_0402LF-0,5%,1/16W,EMPTY,A',
 WATTAGE='1/16W',
 TOLERANCE='5%',
 MATERIAL='EMPTY',
 ROOM='ADC1_BOM1',
 VALUE='0',
 PRIM_FILE='./archive_libs/logical/q_res/chips/chips.prt';

PART_NAME
 R3688 'Q_RES_0402LF-0,5%,1/16W,CHIP,CA':
 ROOM='ADC1_BOM2';

SECTION_NUMBER 1
 '@S9S_MB_2U_LIB.S9S_MB_2U(SCH_1):PAGE239_I241@PURE_QUANTA.Q_RES(CHIPS)':
 C_PATH='@s9s_mb_2u_lib.s9s_mb_2u(sch_1):page239_i241@pure_quanta.q_res(chips)',
 P_PATH='@s9s_mb_2u_lib.s9s_mb_2u(sch_1):page250_i241@pure_quanta.q_res(chips)',
 PATH='I241',
 DRAWING='@S9S_MB_2U_LIB.S9S_MB_2U(SCH_1):PAGE239',
 PHYS_PAGE='250',
 XY='(475,350)',
 ROT='0',
 VER='1',
 PACK_TYPE='0402LF',
 CDS_LIB='pure_quanta',
 CDS_PART_NAME='Q_RES_0402LF-0,5%,1/16W,CHIP,CA',
 WATTAGE='1/16W',
 TOLERANCE='5%',
 MATERIAL='CHIP',
 ROOM='ADC1_BOM2',
 VALUE='0',
 PRIM_FILE='./archive_libs/logical/q_res/chips/chips.prt';

PART_NAME
 R3689 'Q_RES_0402LF-4.7K,1%,1/16W,EMPA':;

SECTION_NUMBER 1
 '@S9S_MB_2U_LIB.S9S_MB_2U(SCH_1):PAGE239_I129@PURE_QUANTA.Q_RES(CHIPS)':
 C_PATH='@s9s_mb_2u_lib.s9s_mb_2u(sch_1):page239_i129@pure_quanta.q_res(chips)',
 P_PATH='@s9s_mb_2u_lib.s9s_mb_2u(sch_1):page250_i129@pure_quanta.q_res(chips)',
 PATH='I129',
 DRAWING='@S9S_MB_2U_LIB.S9S_MB_2U(SCH_1):PAGE239',
 PHYS_PAGE='250',
 XY='(4425,1700)',
 ROT='0',
 VER='2',
 PACK_TYPE='0402LF',
 CDS_LIB='pure_quanta',
 CDS_PART_NAME='Q_RES_0402LF-4.7K,1%,1/16W,EMPA',
 WATTAGE='1/16W',
 TOLERANCE='1%',
 MATERIAL='EMPTY',
 VALUE='4.7K',
 PRIM_FILE='./archive_libs/logical/q_res/chips/chips.prt';

PART_NAME
 R3690 'Q_RES_0402LF-4.7K,1%,1/16W,EMPA':;

SECTION_NUMBER 1
 '@S9S_MB_2U_LIB.S9S_MB_2U(SCH_1):PAGE239_I131@PURE_QUANTA.Q_RES(CHIPS)':
 C_PATH='@s9s_mb_2u_lib.s9s_mb_2u(sch_1):page239_i131@pure_quanta.q_res(chips)',
 P_PATH='@s9s_mb_2u_lib.s9s_mb_2u(sch_1):page250_i131@pure_quanta.q_res(chips)',
 PATH='I131',
 DRAWING='@S9S_MB_2U_LIB.S9S_MB_2U(SCH_1):PAGE239',
 PHYS_PAGE='250',
 XY='(4425,1200)',
 ROT='0',
 VER='2',
 PACK_TYPE='0402LF',
 CDS_LIB='pure_quanta',
 CDS_PART_NAME='Q_RES_0402LF-4.7K,1%,1/16W,EMPA',
 WATTAGE='1/16W',
 TOLERANCE='1%',
 MATERIAL='EMPTY',
 VALUE='4.7K',
 PRIM_FILE='./archive_libs/logical/q_res/chips/chips.prt';

PART_NAME
 R3703 'Q_RES_0402LF-10K,1%,1/16W,EMPTA':;

SECTION_NUMBER 1
 '@S9S_MB_2U_LIB.S9S_MB_2U(SCH_1):PAGE221_I3@PURE_QUANTA.Q_RES(CHIPS)':
 C_PATH='@s9s_mb_2u_lib.s9s_mb_2u(sch_1):page221_i3@pure_quanta.q_res(chips)',
 P_PATH='@s9s_mb_2u_lib.s9s_mb_2u(sch_1):page233_i3@pure_quanta.q_res(chips)',
 PATH='I3',
 DRAWING='@S9S_MB_2U_LIB.S9S_MB_2U(SCH_1):PAGE221',
 PHYS_PAGE='233',
 XY='(-3150,725)',
 ROT='0',
 VER='2',
 PACK_TYPE='0402LF',
 CDS_LIB='pure_quanta',
 CDS_PART_NAME='Q_RES_0402LF-10K,1%,1/16W,EMPTA',
 WATTAGE='1/16W',
 TOLERANCE='1%',
 MATERIAL='EMPTY',
 VALUE='10K',
 PRIM_FILE='./archive_libs/logical/q_res/chips/chips.prt';

PART_NAME
 R3704 'Q_RES_0402LF-1K,1%,1/16W,CHIP,A':;

SECTION_NUMBER 1
 '@S9S_MB_2U_LIB.S9S_MB_2U(SCH_1):PAGE221_I2@PURE_QUANTA.Q_RES(CHIPS)':
 C_PATH='@s9s_mb_2u_lib.s9s_mb_2u(sch_1):page221_i2@pure_quanta.q_res(chips)',
 P_PATH='@s9s_mb_2u_lib.s9s_mb_2u(sch_1):page233_i2@pure_quanta.q_res(chips)',
 PATH='I2',
 DRAWING='@S9S_MB_2U_LIB.S9S_MB_2U(SCH_1):PAGE221',
 PHYS_PAGE='233',
 XY='(-3150,75)',
 ROT='0',
 VER='2',
 PACK_TYPE='0402LF',
 CDS_LIB='pure_quanta',
 CDS_PART_NAME='Q_RES_0402LF-1K,1%,1/16W,CHIP,A',
 WATTAGE='1/16W',
 TOLERANCE='1%',
 MATERIAL='CHIP',
 VALUE='1K',
 PRIM_FILE='./archive_libs/logical/q_res/chips/chips.prt';

PART_NAME
 R3705 'Q_RES_0402LF-10K,1%,1/16W,EMPTA':;

SECTION_NUMBER 1
 '@S9S_MB_2U_LIB.S9S_MB_2U(SCH_1):PAGE221_I147@PURE_QUANTA.Q_RES(CHIPS)':
 C_PATH='@s9s_mb_2u_lib.s9s_mb_2u(sch_1):page221_i147@pure_quanta.q_res(chips)',
 P_PATH='@s9s_mb_2u_lib.s9s_mb_2u(sch_1):page233_i147@pure_quanta.q_res(chips)',
 PATH='I147',
 DRAWING='@S9S_MB_2U_LIB.S9S_MB_2U(SCH_1):PAGE221',
 PHYS_PAGE='233',
 XY='(-2425,3000)',
 ROT='2',
 VER='2',
 PACK_TYPE='0402LF',
 CDS_LIB='pure_quanta',
 CDS_PART_NAME='Q_RES_0402LF-10K,1%,1/16W,EMPTA',
 WATTAGE='1/16W',
 TOLERANCE='1%',
 MATERIAL='EMPTY',
 VALUE='10K',
 PRIM_FILE='./archive_libs/logical/q_res/chips/chips.prt';

PART_NAME
 R3706 'Q_RES_0402LF-10K,1%,1/16W,EMPTA':;

SECTION_NUMBER 1
 '@S9S_MB_2U_LIB.S9S_MB_2U(SCH_1):PAGE221_I9@PURE_QUANTA.Q_RES(CHIPS)':
 C_PATH='@s9s_mb_2u_lib.s9s_mb_2u(sch_1):page221_i9@pure_quanta.q_res(chips)',
 P_PATH='@s9s_mb_2u_lib.s9s_mb_2u(sch_1):page233_i9@pure_quanta.q_res(chips)',
 PATH='I9',
 DRAWING='@S9S_MB_2U_LIB.S9S_MB_2U(SCH_1):PAGE221',
 PHYS_PAGE='233',
 XY='(-2875,725)',
 ROT='0',
 VER='2',
 PACK_TYPE='0402LF',
 CDS_LIB='pure_quanta',
 CDS_PART_NAME='Q_RES_0402LF-10K,1%,1/16W,EMPTA',
 WATTAGE='1/16W',
 TOLERANCE='1%',
 MATERIAL='EMPTY',
 VALUE='10K',
 PRIM_FILE='./archive_libs/logical/q_res/chips/chips.prt';

PART_NAME
 R3707 'Q_RES_0402LF-1K,1%,1/16W,CHIP,A':;

SECTION_NUMBER 1
 '@S9S_MB_2U_LIB.S9S_MB_2U(SCH_1):PAGE221_I6@PURE_QUANTA.Q_RES(CHIPS)':
 C_PATH='@s9s_mb_2u_lib.s9s_mb_2u(sch_1):page221_i6@pure_quanta.q_res(chips)',
 P_PATH='@s9s_mb_2u_lib.s9s_mb_2u(sch_1):page233_i6@pure_quanta.q_res(chips)',
 PATH='I6',
 DRAWING='@S9S_MB_2U_LIB.S9S_MB_2U(SCH_1):PAGE221',
 PHYS_PAGE='233',
 XY='(-2875,75)',
 ROT='0',
 VER='2',
 PACK_TYPE='0402LF',
 CDS_LIB='pure_quanta',
 CDS_PART_NAME='Q_RES_0402LF-1K,1%,1/16W,CHIP,A',
 WATTAGE='1/16W',
 TOLERANCE='1%',
 MATERIAL='CHIP',
 VALUE='1K',
 PRIM_FILE='./archive_libs/logical/q_res/chips/chips.prt';

PART_NAME
 R3708 'Q_RES_0402LF-10K,1%,1/16W,EMPTA':;

SECTION_NUMBER 1
 '@S9S_MB_2U_LIB.S9S_MB_2U(SCH_1):PAGE221_I10@PURE_QUANTA.Q_RES(CHIPS)':
 C_PATH='@s9s_mb_2u_lib.s9s_mb_2u(sch_1):page221_i10@pure_quanta.q_res(chips)',
 P_PATH='@s9s_mb_2u_lib.s9s_mb_2u(sch_1):page233_i10@pure_quanta.q_res(chips)',
 PATH='I10',
 DRAWING='@S9S_MB_2U_LIB.S9S_MB_2U(SCH_1):PAGE221',
 PHYS_PAGE='233',
 XY='(-2600,725)',
 ROT='0',
 VER='2',
 PACK_TYPE='0402LF',
 CDS_LIB='pure_quanta',
 CDS_PART_NAME='Q_RES_0402LF-10K,1%,1/16W,EMPTA',
 WATTAGE='1/16W',
 TOLERANCE='1%',
 MATERIAL='EMPTY',
 VALUE='10K',
 PRIM_FILE='./archive_libs/logical/q_res/chips/chips.prt';

PART_NAME
 R3709 'Q_RES_0402LF-1K,1%,1/16W,CHIP,A':;

SECTION_NUMBER 1
 '@S9S_MB_2U_LIB.S9S_MB_2U(SCH_1):PAGE221_I8@PURE_QUANTA.Q_RES(CHIPS)':
 C_PATH='@s9s_mb_2u_lib.s9s_mb_2u(sch_1):page221_i8@pure_quanta.q_res(chips)',
 P_PATH='@s9s_mb_2u_lib.s9s_mb_2u(sch_1):page233_i8@pure_quanta.q_res(chips)',
 PATH='I8',
 DRAWING='@S9S_MB_2U_LIB.S9S_MB_2U(SCH_1):PAGE221',
 PHYS_PAGE='233',
 XY='(-2600,75)',
 ROT='0',
 VER='2',
 PACK_TYPE='0402LF',
 CDS_LIB='pure_quanta',
 CDS_PART_NAME='Q_RES_0402LF-1K,1%,1/16W,CHIP,A',
 WATTAGE='1/16W',
 TOLERANCE='1%',
 MATERIAL='CHIP',
 VALUE='1K',
 PRIM_FILE='./archive_libs/logical/q_res/chips/chips.prt';

PART_NAME
 R3710 'Q_RES_0402LF-0,5%,1/16W,CHIP,CA':;

SECTION_NUMBER 1
 '@S9S_MB_2U_LIB.S9S_MB_2U(SCH_1):PAGE221_I145@PURE_QUANTA.Q_RES(CHIPS)':
 C_PATH='@s9s_mb_2u_lib.s9s_mb_2u(sch_1):page221_i145@pure_quanta.q_res(chips)',
 P_PATH='@s9s_mb_2u_lib.s9s_mb_2u(sch_1):page233_i145@pure_quanta.q_res(chips)',
 PATH='I145',
 DRAWING='@S9S_MB_2U_LIB.S9S_MB_2U(SCH_1):PAGE221',
 PHYS_PAGE='233',
 XY='(-1325,2650)',
 ROT='0',
 VER='1',
 PACK_TYPE='0402LF',
 CDS_LIB='pure_quanta',
 CDS_PART_NAME='Q_RES_0402LF-0,5%,1/16W,CHIP,CA',
 WATTAGE='1/16W',
 TOLERANCE='5%',
 MATERIAL='CHIP',
 VALUE='0',
 PRIM_FILE='./archive_libs/logical/q_res/chips/chips.prt';

PART_NAME
 R3711 'Q_RES_0402LF-33.2,1%,1/16W,CHIA':;

SECTION_NUMBER 1
 '@S9S_MB_2U_LIB.S9S_MB_2U(SCH_1):PAGE221_I116@PURE_QUANTA.Q_RES(CHIPS)':
 C_PATH='@s9s_mb_2u_lib.s9s_mb_2u(sch_1):page221_i116@pure_quanta.q_res(chips)',
 P_PATH='@s9s_mb_2u_lib.s9s_mb_2u(sch_1):page233_i116@pure_quanta.q_res(chips)',
 PATH='I116',
 DRAWING='@S9S_MB_2U_LIB.S9S_MB_2U(SCH_1):PAGE221',
 PHYS_PAGE='233',
 XY='(1700,2750)',
 ROT='2',
 VER='1',
 PACK_TYPE='0402LF',
 CDS_LIB='pure_quanta',
 CDS_PART_NAME='Q_RES_0402LF-33.2,1%,1/16W,CHIA',
 WATTAGE='1/16W',
 TOLERANCE='1%',
 MATERIAL='CHIP',
 VALUE='33.2',
 PRIM_FILE='./archive_libs/logical/q_res/chips/chips.prt';

PART_NAME
 R3712 'Q_RES_0402LF-33.2,1%,1/16W,CHIA':;

SECTION_NUMBER 1
 '@S9S_MB_2U_LIB.S9S_MB_2U(SCH_1):PAGE221_I115@PURE_QUANTA.Q_RES(CHIPS)':
 C_PATH='@s9s_mb_2u_lib.s9s_mb_2u(sch_1):page221_i115@pure_quanta.q_res(chips)',
 P_PATH='@s9s_mb_2u_lib.s9s_mb_2u(sch_1):page233_i115@pure_quanta.q_res(chips)',
 PATH='I115',
 DRAWING='@S9S_MB_2U_LIB.S9S_MB_2U(SCH_1):PAGE221',
 PHYS_PAGE='233',
 XY='(1700,2800)',
 ROT='2',
 VER='1',
 PACK_TYPE='0402LF',
 CDS_LIB='pure_quanta',
 CDS_PART_NAME='Q_RES_0402LF-33.2,1%,1/16W,CHIA',
 WATTAGE='1/16W',
 TOLERANCE='1%',
 MATERIAL='CHIP',
 VALUE='33.2',
 PRIM_FILE='./archive_libs/logical/q_res/chips/chips.prt';

PART_NAME
 R3713 'Q_RES_0402LF-0,5%,1/16W,CHIP,CA':;

SECTION_NUMBER 1
 '@S9S_MB_2U_LIB.S9S_MB_2U(SCH_1):PAGE221_I137@PURE_QUANTA.Q_RES(CHIPS)':
 C_PATH='@s9s_mb_2u_lib.s9s_mb_2u(sch_1):page221_i137@pure_quanta.q_res(chips)',
 P_PATH='@s9s_mb_2u_lib.s9s_mb_2u(sch_1):page233_i137@pure_quanta.q_res(chips)',
 PATH='I137',
 DRAWING='@S9S_MB_2U_LIB.S9S_MB_2U(SCH_1):PAGE221',
 PHYS_PAGE='233',
 XY='(-1075,2500)',
 ROT='2',
 VER='1',
 PACK_TYPE='0402LF',
 CDS_LIB='pure_quanta',
 CDS_PART_NAME='Q_RES_0402LF-0,5%,1/16W,CHIP,CA',
 WATTAGE='1/16W',
 TOLERANCE='5%',
 MATERIAL='CHIP',
 VALUE='0',
 PRIM_FILE='./archive_libs/logical/q_res/chips/chips.prt';

PART_NAME
 R3714 'Q_RES_0402LF-0,5%,1/16W,CHIP,CA':;

SECTION_NUMBER 1
 '@S9S_MB_2U_LIB.S9S_MB_2U(SCH_1):PAGE221_I138@PURE_QUANTA.Q_RES(CHIPS)':
 C_PATH='@s9s_mb_2u_lib.s9s_mb_2u(sch_1):page221_i138@pure_quanta.q_res(chips)',
 P_PATH='@s9s_mb_2u_lib.s9s_mb_2u(sch_1):page233_i138@pure_quanta.q_res(chips)',
 PATH='I138',
 DRAWING='@S9S_MB_2U_LIB.S9S_MB_2U(SCH_1):PAGE221',
 PHYS_PAGE='233',
 XY='(-1075,2550)',
 ROT='2',
 VER='1',
 PACK_TYPE='0402LF',
 CDS_LIB='pure_quanta',
 CDS_PART_NAME='Q_RES_0402LF-0,5%,1/16W,CHIP,CA',
 WATTAGE='1/16W',
 TOLERANCE='5%',
 MATERIAL='CHIP',
 VALUE='0',
 PRIM_FILE='./archive_libs/logical/q_res/chips/chips.prt';

PART_NAME
 R3715 'Q_RES_0402LF-0,5%,1/16W,CHIP,CA':;

SECTION_NUMBER 1
 '@S9S_MB_2U_LIB.S9S_MB_2U(SCH_1):PAGE221_I139@PURE_QUANTA.Q_RES(CHIPS)':
 C_PATH='@s9s_mb_2u_lib.s9s_mb_2u(sch_1):page221_i139@pure_quanta.q_res(chips)',
 P_PATH='@s9s_mb_2u_lib.s9s_mb_2u(sch_1):page233_i139@pure_quanta.q_res(chips)',
 PATH='I139',
 DRAWING='@S9S_MB_2U_LIB.S9S_MB_2U(SCH_1):PAGE221',
 PHYS_PAGE='233',
 XY='(-1075,2400)',
 ROT='2',
 VER='1',
 PACK_TYPE='0402LF',
 CDS_LIB='pure_quanta',
 CDS_PART_NAME='Q_RES_0402LF-0,5%,1/16W,CHIP,CA',
 WATTAGE='1/16W',
 TOLERANCE='5%',
 MATERIAL='CHIP',
 VALUE='0',
 PRIM_FILE='./archive_libs/logical/q_res/chips/chips.prt';

PART_NAME
 R3716 'Q_RES_0402LF-0,5%,1/16W,CHIP,CA':;

SECTION_NUMBER 1
 '@S9S_MB_2U_LIB.S9S_MB_2U(SCH_1):PAGE221_I140@PURE_QUANTA.Q_RES(CHIPS)':
 C_PATH='@s9s_mb_2u_lib.s9s_mb_2u(sch_1):page221_i140@pure_quanta.q_res(chips)',
 P_PATH='@s9s_mb_2u_lib.s9s_mb_2u(sch_1):page233_i140@pure_quanta.q_res(chips)',
 PATH='I140',
 DRAWING='@S9S_MB_2U_LIB.S9S_MB_2U(SCH_1):PAGE221',
 PHYS_PAGE='233',
 XY='(-1075,2450)',
 ROT='2',
 VER='1',
 PACK_TYPE='0402LF',
 CDS_LIB='pure_quanta',
 CDS_PART_NAME='Q_RES_0402LF-0,5%,1/16W,CHIP,CA',
 WATTAGE='1/16W',
 TOLERANCE='5%',
 MATERIAL='CHIP',
 VALUE='0',
 PRIM_FILE='./archive_libs/logical/q_res/chips/chips.prt';

PART_NAME
 R3717 'Q_RES_0402LF-0,5%,1/16W,CHIP,CA':;

SECTION_NUMBER 1
 '@S9S_MB_2U_LIB.S9S_MB_2U(SCH_1):PAGE221_I141@PURE_QUANTA.Q_RES(CHIPS)':
 C_PATH='@s9s_mb_2u_lib.s9s_mb_2u(sch_1):page221_i141@pure_quanta.q_res(chips)',
 P_PATH='@s9s_mb_2u_lib.s9s_mb_2u(sch_1):page233_i141@pure_quanta.q_res(chips)',
 PATH='I141',
 DRAWING='@S9S_MB_2U_LIB.S9S_MB_2U(SCH_1):PAGE221',
 PHYS_PAGE='233',
 XY='(-1075,2300)',
 ROT='2',
 VER='1',
 PACK_TYPE='0402LF',
 CDS_LIB='pure_quanta',
 CDS_PART_NAME='Q_RES_0402LF-0,5%,1/16W,CHIP,CA',
 WATTAGE='1/16W',
 TOLERANCE='5%',
 MATERIAL='CHIP',
 VALUE='0',
 PRIM_FILE='./archive_libs/logical/q_res/chips/chips.prt';

PART_NAME
 R3718 'Q_RES_0402LF-0,5%,1/16W,CHIP,CA':;

SECTION_NUMBER 1
 '@S9S_MB_2U_LIB.S9S_MB_2U(SCH_1):PAGE221_I142@PURE_QUANTA.Q_RES(CHIPS)':
 C_PATH='@s9s_mb_2u_lib.s9s_mb_2u(sch_1):page221_i142@pure_quanta.q_res(chips)',
 P_PATH='@s9s_mb_2u_lib.s9s_mb_2u(sch_1):page233_i142@pure_quanta.q_res(chips)',
 PATH='I142',
 DRAWING='@S9S_MB_2U_LIB.S9S_MB_2U(SCH_1):PAGE221',
 PHYS_PAGE='233',
 XY='(-1075,2350)',
 ROT='2',
 VER='1',
 PACK_TYPE='0402LF',
 CDS_LIB='pure_quanta',
 CDS_PART_NAME='Q_RES_0402LF-0,5%,1/16W,CHIP,CA',
 WATTAGE='1/16W',
 TOLERANCE='5%',
 MATERIAL='CHIP',
 VALUE='0',
 PRIM_FILE='./archive_libs/logical/q_res/chips/chips.prt';

PART_NAME
 R3719 'Q_RES_0402LF-0,5%,1/16W,CHIP,CA':;

SECTION_NUMBER 1
 '@S9S_MB_2U_LIB.S9S_MB_2U(SCH_1):PAGE221_I143@PURE_QUANTA.Q_RES(CHIPS)':
 C_PATH='@s9s_mb_2u_lib.s9s_mb_2u(sch_1):page221_i143@pure_quanta.q_res(chips)',
 P_PATH='@s9s_mb_2u_lib.s9s_mb_2u(sch_1):page233_i143@pure_quanta.q_res(chips)',
 PATH='I143',
 DRAWING='@S9S_MB_2U_LIB.S9S_MB_2U(SCH_1):PAGE221',
 PHYS_PAGE='233',
 XY='(-1075,2200)',
 ROT='2',
 VER='1',
 PACK_TYPE='0402LF',
 CDS_LIB='pure_quanta',
 CDS_PART_NAME='Q_RES_0402LF-0,5%,1/16W,CHIP,CA',
 WATTAGE='1/16W',
 TOLERANCE='5%',
 MATERIAL='CHIP',
 VALUE='0',
 PRIM_FILE='./archive_libs/logical/q_res/chips/chips.prt';

PART_NAME
 R3720 'Q_RES_0402LF-0,5%,1/16W,CHIP,CA':;

SECTION_NUMBER 1
 '@S9S_MB_2U_LIB.S9S_MB_2U(SCH_1):PAGE221_I144@PURE_QUANTA.Q_RES(CHIPS)':
 C_PATH='@s9s_mb_2u_lib.s9s_mb_2u(sch_1):page221_i144@pure_quanta.q_res(chips)',
 P_PATH='@s9s_mb_2u_lib.s9s_mb_2u(sch_1):page233_i144@pure_quanta.q_res(chips)',
 PATH='I144',
 DRAWING='@S9S_MB_2U_LIB.S9S_MB_2U(SCH_1):PAGE221',
 PHYS_PAGE='233',
 XY='(-1075,2250)',
 ROT='2',
 VER='1',
 PACK_TYPE='0402LF',
 CDS_LIB='pure_quanta',
 CDS_PART_NAME='Q_RES_0402LF-0,5%,1/16W,CHIP,CA',
 WATTAGE='1/16W',
 TOLERANCE='5%',
 MATERIAL='CHIP',
 VALUE='0',
 PRIM_FILE='./archive_libs/logical/q_res/chips/chips.prt';

PART_NAME
 R3721 'Q_RES_0402LF-0,5%,1/16W,CHIP,CA':;

SECTION_NUMBER 1
 '@S9S_MB_2U_LIB.S9S_MB_2U(SCH_1):PAGE221_I120@PURE_QUANTA.Q_RES(CHIPS)':
 C_PATH='@s9s_mb_2u_lib.s9s_mb_2u(sch_1):page221_i120@pure_quanta.q_res(chips)',
 P_PATH='@s9s_mb_2u_lib.s9s_mb_2u(sch_1):page233_i120@pure_quanta.q_res(chips)',
 PATH='I120',
 DRAWING='@S9S_MB_2U_LIB.S9S_MB_2U(SCH_1):PAGE221',
 PHYS_PAGE='233',
 XY='(1575,2500)',
 ROT='0',
 VER='1',
 PACK_TYPE='0402LF',
 CDS_LIB='pure_quanta',
 CDS_PART_NAME='Q_RES_0402LF-0,5%,1/16W,CHIP,CA',
 WATTAGE='1/16W',
 TOLERANCE='5%',
 MATERIAL='CHIP',
 VALUE='0',
 PRIM_FILE='./archive_libs/logical/q_res/chips/chips.prt';

PART_NAME
 R3722 'Q_RES_0402LF-0,5%,1/16W,CHIP,CA':;

SECTION_NUMBER 1
 '@S9S_MB_2U_LIB.S9S_MB_2U(SCH_1):PAGE221_I119@PURE_QUANTA.Q_RES(CHIPS)':
 C_PATH='@s9s_mb_2u_lib.s9s_mb_2u(sch_1):page221_i119@pure_quanta.q_res(chips)',
 P_PATH='@s9s_mb_2u_lib.s9s_mb_2u(sch_1):page233_i119@pure_quanta.q_res(chips)',
 PATH='I119',
 DRAWING='@S9S_MB_2U_LIB.S9S_MB_2U(SCH_1):PAGE221',
 PHYS_PAGE='233',
 XY='(1575,2550)',
 ROT='0',
 VER='1',
 PACK_TYPE='0402LF',
 CDS_LIB='pure_quanta',
 CDS_PART_NAME='Q_RES_0402LF-0,5%,1/16W,CHIP,CA',
 WATTAGE='1/16W',
 TOLERANCE='5%',
 MATERIAL='CHIP',
 VALUE='0',
 PRIM_FILE='./archive_libs/logical/q_res/chips/chips.prt';

PART_NAME
 R3723 'Q_RES_0402LF-2.2K,5%,1/16W,CHIA':;

SECTION_NUMBER 1
 '@S9S_MB_2U_LIB.S9S_MB_2U(SCH_1):PAGE221_I55@PURE_QUANTA.Q_RES(CHIPS)':
 C_PATH='@s9s_mb_2u_lib.s9s_mb_2u(sch_1):page221_i55@pure_quanta.q_res(chips)',
 P_PATH='@s9s_mb_2u_lib.s9s_mb_2u(sch_1):page233_i55@pure_quanta.q_res(chips)',
 PATH='I55',
 DRAWING='@S9S_MB_2U_LIB.S9S_MB_2U(SCH_1):PAGE221',
 PHYS_PAGE='233',
 XY='(1950,1075)',
 ROT='0',
 VER='1',
 PACK_TYPE='0402LF',
 CDS_LIB='pure_quanta',
 CDS_PART_NAME='Q_RES_0402LF-2.2K,5%,1/16W,CHIA',
 WATTAGE='1/16W',
 TOLERANCE='5%',
 MATERIAL='CHIP',
 VALUE='2.2K',
 PRIM_FILE='./archive_libs/logical/q_res/chips/chips.prt';

PART_NAME
 R3724 'Q_RES_0402LF-2.2K,5%,1/16W,CHIA':;

SECTION_NUMBER 1
 '@S9S_MB_2U_LIB.S9S_MB_2U(SCH_1):PAGE221_I56@PURE_QUANTA.Q_RES(CHIPS)':
 C_PATH='@s9s_mb_2u_lib.s9s_mb_2u(sch_1):page221_i56@pure_quanta.q_res(chips)',
 P_PATH='@s9s_mb_2u_lib.s9s_mb_2u(sch_1):page233_i56@pure_quanta.q_res(chips)',
 PATH='I56',
 DRAWING='@S9S_MB_2U_LIB.S9S_MB_2U(SCH_1):PAGE221',
 PHYS_PAGE='233',
 XY='(1950,1025)',
 ROT='0',
 VER='1',
 PACK_TYPE='0402LF',
 CDS_LIB='pure_quanta',
 CDS_PART_NAME='Q_RES_0402LF-2.2K,5%,1/16W,CHIA',
 WATTAGE='1/16W',
 TOLERANCE='5%',
 MATERIAL='CHIP',
 VALUE='2.2K',
 PRIM_FILE='./archive_libs/logical/q_res/chips/chips.prt';

PART_NAME
 R3725 'Q_RES_0402LF-2.2K,5%,1/16W,CHIA':;

SECTION_NUMBER 1
 '@S9S_MB_2U_LIB.S9S_MB_2U(SCH_1):PAGE221_I53@PURE_QUANTA.Q_RES(CHIPS)':
 C_PATH='@s9s_mb_2u_lib.s9s_mb_2u(sch_1):page221_i53@pure_quanta.q_res(chips)',
 P_PATH='@s9s_mb_2u_lib.s9s_mb_2u(sch_1):page233_i53@pure_quanta.q_res(chips)',
 PATH='I53',
 DRAWING='@S9S_MB_2U_LIB.S9S_MB_2U(SCH_1):PAGE221',
 PHYS_PAGE='233',
 XY='(1950,700)',
 ROT='0',
 VER='1',
 PACK_TYPE='0402LF',
 CDS_LIB='pure_quanta',
 CDS_PART_NAME='Q_RES_0402LF-2.2K,5%,1/16W,CHIA',
 WATTAGE='1/16W',
 TOLERANCE='5%',
 MATERIAL='CHIP',
 VALUE='2.2K',
 PRIM_FILE='./archive_libs/logical/q_res/chips/chips.prt';

PART_NAME
 R3726 'Q_RES_0402LF-2.2K,5%,1/16W,CHIA':;

SECTION_NUMBER 1
 '@S9S_MB_2U_LIB.S9S_MB_2U(SCH_1):PAGE221_I52@PURE_QUANTA.Q_RES(CHIPS)':
 C_PATH='@s9s_mb_2u_lib.s9s_mb_2u(sch_1):page221_i52@pure_quanta.q_res(chips)',
 P_PATH='@s9s_mb_2u_lib.s9s_mb_2u(sch_1):page233_i52@pure_quanta.q_res(chips)',
 PATH='I52',
 DRAWING='@S9S_MB_2U_LIB.S9S_MB_2U(SCH_1):PAGE221',
 PHYS_PAGE='233',
 XY='(1950,650)',
 ROT='0',
 VER='1',
 PACK_TYPE='0402LF',
 CDS_LIB='pure_quanta',
 CDS_PART_NAME='Q_RES_0402LF-2.2K,5%,1/16W,CHIA',
 WATTAGE='1/16W',
 TOLERANCE='5%',
 MATERIAL='CHIP',
 VALUE='2.2K',
 PRIM_FILE='./archive_libs/logical/q_res/chips/chips.prt';

PART_NAME
 R3727 'Q_RES_0402LF-2.2K,5%,1/16W,CHIA':;

SECTION_NUMBER 1
 '@S9S_MB_2U_LIB.S9S_MB_2U(SCH_1):PAGE221_I51@PURE_QUANTA.Q_RES(CHIPS)':
 C_PATH='@s9s_mb_2u_lib.s9s_mb_2u(sch_1):page221_i51@pure_quanta.q_res(chips)',
 P_PATH='@s9s_mb_2u_lib.s9s_mb_2u(sch_1):page233_i51@pure_quanta.q_res(chips)',
 PATH='I51',
 DRAWING='@S9S_MB_2U_LIB.S9S_MB_2U(SCH_1):PAGE221',
 PHYS_PAGE='233',
 XY='(1950,425)',
 ROT='0',
 VER='1',
 PACK_TYPE='0402LF',
 CDS_LIB='pure_quanta',
 CDS_PART_NAME='Q_RES_0402LF-2.2K,5%,1/16W,CHIA',
 WATTAGE='1/16W',
 TOLERANCE='5%',
 MATERIAL='CHIP',
 VALUE='2.2K',
 PRIM_FILE='./archive_libs/logical/q_res/chips/chips.prt';

PART_NAME
 R3728 'Q_RES_0402LF-2.2K,5%,1/16W,CHIA':;

SECTION_NUMBER 1
 '@S9S_MB_2U_LIB.S9S_MB_2U(SCH_1):PAGE221_I50@PURE_QUANTA.Q_RES(CHIPS)':
 C_PATH='@s9s_mb_2u_lib.s9s_mb_2u(sch_1):page221_i50@pure_quanta.q_res(chips)',
 P_PATH='@s9s_mb_2u_lib.s9s_mb_2u(sch_1):page233_i50@pure_quanta.q_res(chips)',
 PATH='I50',
 DRAWING='@S9S_MB_2U_LIB.S9S_MB_2U(SCH_1):PAGE221',
 PHYS_PAGE='233',
 XY='(1950,375)',
 ROT='0',
 VER='1',
 PACK_TYPE='0402LF',
 CDS_LIB='pure_quanta',
 CDS_PART_NAME='Q_RES_0402LF-2.2K,5%,1/16W,CHIA',
 WATTAGE='1/16W',
 TOLERANCE='5%',
 MATERIAL='CHIP',
 VALUE='2.2K',
 PRIM_FILE='./archive_libs/logical/q_res/chips/chips.prt';

PART_NAME
 R3729 'Q_RES_0402LF-2.2K,5%,1/16W,CHIA':;

SECTION_NUMBER 1
 '@S9S_MB_2U_LIB.S9S_MB_2U(SCH_1):PAGE221_I48@PURE_QUANTA.Q_RES(CHIPS)':
 C_PATH='@s9s_mb_2u_lib.s9s_mb_2u(sch_1):page221_i48@pure_quanta.q_res(chips)',
 P_PATH='@s9s_mb_2u_lib.s9s_mb_2u(sch_1):page233_i48@pure_quanta.q_res(chips)',
 PATH='I48',
 DRAWING='@S9S_MB_2U_LIB.S9S_MB_2U(SCH_1):PAGE221',
 PHYS_PAGE='233',
 XY='(1975,125)',
 ROT='0',
 VER='1',
 PACK_TYPE='0402LF',
 CDS_LIB='pure_quanta',
 CDS_PART_NAME='Q_RES_0402LF-2.2K,5%,1/16W,CHIA',
 WATTAGE='1/16W',
 TOLERANCE='5%',
 MATERIAL='CHIP',
 VALUE='2.2K',
 PRIM_FILE='./archive_libs/logical/q_res/chips/chips.prt';

PART_NAME
 R3730 'Q_RES_0402LF-2.2K,5%,1/16W,CHIA':;

SECTION_NUMBER 1
 '@S9S_MB_2U_LIB.S9S_MB_2U(SCH_1):PAGE221_I49@PURE_QUANTA.Q_RES(CHIPS)':
 C_PATH='@s9s_mb_2u_lib.s9s_mb_2u(sch_1):page221_i49@pure_quanta.q_res(chips)',
 P_PATH='@s9s_mb_2u_lib.s9s_mb_2u(sch_1):page233_i49@pure_quanta.q_res(chips)',
 PATH='I49',
 DRAWING='@S9S_MB_2U_LIB.S9S_MB_2U(SCH_1):PAGE221',
 PHYS_PAGE='233',
 XY='(1975,75)',
 ROT='0',
 VER='1',
 PACK_TYPE='0402LF',
 CDS_LIB='pure_quanta',
 CDS_PART_NAME='Q_RES_0402LF-2.2K,5%,1/16W,CHIA',
 WATTAGE='1/16W',
 TOLERANCE='5%',
 MATERIAL='CHIP',
 VALUE='2.2K',
 PRIM_FILE='./archive_libs/logical/q_res/chips/chips.prt';

PART_NAME
 R3731 'Q_RES_0402LF-2.2K,5%,1/16W,CHIA':;

SECTION_NUMBER 1
 '@S9S_MB_2U_LIB.S9S_MB_2U(SCH_1):PAGE221_I98@PURE_QUANTA.Q_RES(CHIPS)':
 C_PATH='@s9s_mb_2u_lib.s9s_mb_2u(sch_1):page221_i98@pure_quanta.q_res(chips)',
 P_PATH='@s9s_mb_2u_lib.s9s_mb_2u(sch_1):page233_i98@pure_quanta.q_res(chips)',
 PATH='I98',
 DRAWING='@S9S_MB_2U_LIB.S9S_MB_2U(SCH_1):PAGE221',
 PHYS_PAGE='233',
 XY='(1975,-175)',
 ROT='0',
 VER='1',
 PACK_TYPE='0402LF',
 CDS_LIB='pure_quanta',
 CDS_PART_NAME='Q_RES_0402LF-2.2K,5%,1/16W,CHIA',
 WATTAGE='1/16W',
 TOLERANCE='5%',
 MATERIAL='CHIP',
 VALUE='2.2K',
 PRIM_FILE='./archive_libs/logical/q_res/chips/chips.prt';

PART_NAME
 R3732 'Q_RES_0402LF-2.2K,5%,1/16W,CHIA':;

SECTION_NUMBER 1
 '@S9S_MB_2U_LIB.S9S_MB_2U(SCH_1):PAGE221_I34@PURE_QUANTA.Q_RES(CHIPS)':
 C_PATH='@s9s_mb_2u_lib.s9s_mb_2u(sch_1):page221_i34@pure_quanta.q_res(chips)',
 P_PATH='@s9s_mb_2u_lib.s9s_mb_2u(sch_1):page233_i34@pure_quanta.q_res(chips)',
 PATH='I34',
 DRAWING='@S9S_MB_2U_LIB.S9S_MB_2U(SCH_1):PAGE221',
 PHYS_PAGE='233',
 XY='(1975,-225)',
 ROT='0',
 VER='1',
 PACK_TYPE='0402LF',
 CDS_LIB='pure_quanta',
 CDS_PART_NAME='Q_RES_0402LF-2.2K,5%,1/16W,CHIA',
 WATTAGE='1/16W',
 TOLERANCE='5%',
 MATERIAL='CHIP',
 VALUE='2.2K',
 PRIM_FILE='./archive_libs/logical/q_res/chips/chips.prt';

PART_NAME
 R3751 'Q_RES_0402LF-0,5%,1/16W,CHIP,CA':;

SECTION_NUMBER 1
 '@S9S_MB_2U_LIB.S9S_MB_2U(SCH_1):PAGE295_I146@PURE_QUANTA.Q_RES(CHIPS)':
 C_PATH='@s9s_mb_2u_lib.s9s_mb_2u(sch_1):page295_i146@pure_quanta.q_res(chips)',
 P_PATH='@s9s_mb_2u_lib.s9s_mb_2u(sch_1):page171_i146@pure_quanta.q_res(chips)',
 PATH='I146',
 DRAWING='@S9S_MB_2U_LIB.S9S_MB_2U(SCH_1):PAGE295',
 PHYS_PAGE='171',
 XY='(1550,825)',
 ROT='0',
 VER='2',
 PACK_TYPE='0402LF',
 CDS_LIB='pure_quanta',
 CDS_PART_NAME='Q_RES_0402LF-0,5%,1/16W,CHIP,CA',
 WATTAGE='1/16W',
 TOLERANCE='5%',
 MATERIAL='CHIP',
 VALUE='0',
 PRIM_FILE='./archive_libs/logical/q_res/chips/chips.prt';

PART_NAME
 R3752 'Q_RES_0402LF-0,5%,1/16W,CHIP,CA':;

SECTION_NUMBER 1
 '@S9S_MB_2U_LIB.S9S_MB_2U(SCH_1):PAGE295_I122@PURE_QUANTA.Q_RES(CHIPS)':
 C_PATH='@s9s_mb_2u_lib.s9s_mb_2u(sch_1):page295_i122@pure_quanta.q_res(chips)',
 P_PATH='@s9s_mb_2u_lib.s9s_mb_2u(sch_1):page171_i122@pure_quanta.q_res(chips)',
 PATH='I122',
 DRAWING='@S9S_MB_2U_LIB.S9S_MB_2U(SCH_1):PAGE295',
 PHYS_PAGE='171',
 XY='(4350,725)',
 ROT='0',
 VER='1',
 PACK_TYPE='0402LF',
 CDS_LIB='pure_quanta',
 CDS_PART_NAME='Q_RES_0402LF-0,5%,1/16W,CHIP,CA',
 WATTAGE='1/16W',
 TOLERANCE='5%',
 MATERIAL='CHIP',
 VALUE='0',
 PRIM_FILE='./archive_libs/logical/q_res/chips/chips.prt';

PART_NAME
 R3754 'Q_RES_0402LF-33.2,1%,1/16W,CHIA':;

SECTION_NUMBER 1
 '@S9S_MB_2U_LIB.S9S_MB_2U(SCH_1):PAGE295_I130@PURE_QUANTA.Q_RES(CHIPS)':
 C_PATH='@s9s_mb_2u_lib.s9s_mb_2u(sch_1):page295_i130@pure_quanta.q_res(chips)',
 P_PATH='@s9s_mb_2u_lib.s9s_mb_2u(sch_1):page171_i130@pure_quanta.q_res(chips)',
 PATH='I130',
 DRAWING='@S9S_MB_2U_LIB.S9S_MB_2U(SCH_1):PAGE295',
 PHYS_PAGE='171',
 XY='(1275,475)',
 ROT='0',
 VER='1',
 PACK_TYPE='0402LF',
 CDS_LIB='pure_quanta',
 CDS_PART_NAME='Q_RES_0402LF-33.2,1%,1/16W,CHIA',
 WATTAGE='1/16W',
 TOLERANCE='1%',
 MATERIAL='CHIP',
 VALUE='33.2',
 PRIM_FILE='./archive_libs/logical/q_res/chips/chips.prt';

PART_NAME
 R3756 'Q_RES_0402LF-33.2,1%,1/16W,CHIA':;

SECTION_NUMBER 1
 '@S9S_MB_2U_LIB.S9S_MB_2U(SCH_1):PAGE295_I131@PURE_QUANTA.Q_RES(CHIPS)':
 C_PATH='@s9s_mb_2u_lib.s9s_mb_2u(sch_1):page295_i131@pure_quanta.q_res(chips)',
 P_PATH='@s9s_mb_2u_lib.s9s_mb_2u(sch_1):page171_i131@pure_quanta.q_res(chips)',
 PATH='I131',
 DRAWING='@S9S_MB_2U_LIB.S9S_MB_2U(SCH_1):PAGE295',
 PHYS_PAGE='171',
 XY='(1275,425)',
 ROT='0',
 VER='1',
 PACK_TYPE='0402LF',
 CDS_LIB='pure_quanta',
 CDS_PART_NAME='Q_RES_0402LF-33.2,1%,1/16W,CHIA',
 WATTAGE='1/16W',
 TOLERANCE='1%',
 MATERIAL='CHIP',
 VALUE='33.2',
 PRIM_FILE='./archive_libs/logical/q_res/chips/chips.prt';

PART_NAME
 R3758 'Q_RES_0402LF-10,1%,1/16W,CHIP,A':;

SECTION_NUMBER 1
 '@S9S_MB_2U_LIB.S9S_MB_2U(SCH_1):PAGE295_I132@PURE_QUANTA.Q_RES(CHIPS)':
 C_PATH='@s9s_mb_2u_lib.s9s_mb_2u(sch_1):page295_i132@pure_quanta.q_res(chips)',
 P_PATH='@s9s_mb_2u_lib.s9s_mb_2u(sch_1):page171_i132@pure_quanta.q_res(chips)',
 PATH='I132',
 DRAWING='@S9S_MB_2U_LIB.S9S_MB_2U(SCH_1):PAGE295',
 PHYS_PAGE='171',
 XY='(1300,-125)',
 ROT='0',
 VER='1',
 PACK_TYPE='0402LF',
 CDS_LIB='pure_quanta',
 CDS_PART_NAME='Q_RES_0402LF-10,1%,1/16W,CHIP,A',
 WATTAGE='1/16W',
 TOLERANCE='1%',
 MATERIAL='CHIP',
 VALUE='10',
 PRIM_FILE='./archive_libs/logical/q_res/chips/chips.prt';

PART_NAME
 R3760 'Q_RES_0402LF-10,1%,1/16W,CHIP,A':;

SECTION_NUMBER 1
 '@S9S_MB_2U_LIB.S9S_MB_2U(SCH_1):PAGE295_I134@PURE_QUANTA.Q_RES(CHIPS)':
 C_PATH='@s9s_mb_2u_lib.s9s_mb_2u(sch_1):page295_i134@pure_quanta.q_res(chips)',
 P_PATH='@s9s_mb_2u_lib.s9s_mb_2u(sch_1):page171_i134@pure_quanta.q_res(chips)',
 PATH='I134',
 DRAWING='@S9S_MB_2U_LIB.S9S_MB_2U(SCH_1):PAGE295',
 PHYS_PAGE='171',
 XY='(1300,-400)',
 ROT='0',
 VER='1',
 PACK_TYPE='0402LF',
 CDS_LIB='pure_quanta',
 CDS_PART_NAME='Q_RES_0402LF-10,1%,1/16W,CHIP,A',
 WATTAGE='1/16W',
 TOLERANCE='1%',
 MATERIAL='CHIP',
 VALUE='10',
 PRIM_FILE='./archive_libs/logical/q_res/chips/chips.prt';

PART_NAME
 R3763 'Q_RES_0402LF-4.7K,1%,1/16W,CHIA':;

SECTION_NUMBER 1
 '@S9S_MB_2U_LIB.S9S_MB_2U(SCH_1):PAGE295_I136@PURE_QUANTA.Q_RES(CHIPS)':
 C_PATH='@s9s_mb_2u_lib.s9s_mb_2u(sch_1):page295_i136@pure_quanta.q_res(chips)',
 P_PATH='@s9s_mb_2u_lib.s9s_mb_2u(sch_1):page171_i136@pure_quanta.q_res(chips)',
 PATH='I136',
 DRAWING='@S9S_MB_2U_LIB.S9S_MB_2U(SCH_1):PAGE295',
 PHYS_PAGE='171',
 XY='(750,1075)',
 ROT='0',
 VER='1',
 PACK_TYPE='0402LF',
 CDS_LIB='pure_quanta',
 CDS_PART_NAME='Q_RES_0402LF-4.7K,1%,1/16W,CHIA',
 WATTAGE='1/16W',
 TOLERANCE='1%',
 MATERIAL='CHIP',
 VALUE='4.7K',
 PRIM_FILE='./archive_libs/logical/q_res/chips/chips.prt';

PART_NAME
 R3764 'Q_RES_0402LF-4.7K,1%,1/16W,EMPA':;

SECTION_NUMBER 1
 '@S9S_MB_2U_LIB.S9S_MB_2U(SCH_1):PAGE295_I135@PURE_QUANTA.Q_RES(CHIPS)':
 C_PATH='@s9s_mb_2u_lib.s9s_mb_2u(sch_1):page295_i135@pure_quanta.q_res(chips)',
 P_PATH='@s9s_mb_2u_lib.s9s_mb_2u(sch_1):page171_i135@pure_quanta.q_res(chips)',
 PATH='I135',
 DRAWING='@S9S_MB_2U_LIB.S9S_MB_2U(SCH_1):PAGE295',
 PHYS_PAGE='171',
 XY='(750,1000)',
 ROT='0',
 VER='1',
 PACK_TYPE='0402LF',
 CDS_LIB='pure_quanta',
 CDS_PART_NAME='Q_RES_0402LF-4.7K,1%,1/16W,EMPA',
 WATTAGE='1/16W',
 TOLERANCE='1%',
 MATERIAL='EMPTY',
 VALUE='4.7K',
 PRIM_FILE='./archive_libs/logical/q_res/chips/chips.prt';

PART_NAME
 R3767 'Q_RES_2512LF-0.01,1%,1W,CHIP,CA':;

SECTION_NUMBER 1
 '@S9S_MB_2U_LIB.S9S_MB_2U(SCH_1):PAGE295_I153@PURE_QUANTA.Q_RES(CHIPS)':
 C_PATH='@s9s_mb_2u_lib.s9s_mb_2u(sch_1):page295_i153@pure_quanta.q_res(chips)',
 P_PATH='@s9s_mb_2u_lib.s9s_mb_2u(sch_1):page171_i153@pure_quanta.q_res(chips)',
 PATH='I153',
 DRAWING='@S9S_MB_2U_LIB.S9S_MB_2U(SCH_1):PAGE295',
 PHYS_PAGE='171',
 XY='(-600,75)',
 ROT='0',
 VER='1',
 PACK_TYPE='2512LF',
 LOCATION='R3767',
 CDS_LIB='pure_quanta',
 CDS_PART_NAME='Q_RES_2512LF-0.01,1%,1W,CHIP,CA',
 WATTAGE='1W',
 TOLERANCE='1%',
 MATERIAL='CHIP',
 VALUE='0.01',
 PRIM_FILE='./archive_libs/logical/q_res/chips/chips.prt';

PART_NAME
 R3770 'Q_RES_0402LF-0,5%,1/16W,CHIP,CA':;

SECTION_NUMBER 1
 '@S9S_MB_2U_LIB.S9S_MB_2U(SCH_1):PAGE230_I34@PURE_QUANTA.Q_RES(CHIPS)':
 C_PATH='@s9s_mb_2u_lib.s9s_mb_2u(sch_1):page230_i34@pure_quanta.q_res(chips)',
 P_PATH='@s9s_mb_2u_lib.s9s_mb_2u(sch_1):page246_i34@pure_quanta.q_res(chips)',
 PATH='I34',
 DRAWING='@S9S_MB_2U_LIB.S9S_MB_2U(SCH_1):PAGE230',
 PHYS_PAGE='246',
 XY='(-1325,2125)',
 ROT='0',
 VER='1',
 PACK_TYPE='0402LF',
 CDS_LIB='pure_quanta',
 CDS_PART_NAME='Q_RES_0402LF-0,5%,1/16W,CHIP,CA',
 WATTAGE='1/16W',
 TOLERANCE='5%',
 MATERIAL='CHIP',
 VALUE='0',
 PRIM_FILE='./archive_libs/logical/q_res/chips/chips.prt';

PART_NAME
 R3771 'Q_RES_0402LF-10K,1%,1/16W,CHIPA':;

SECTION_NUMBER 1
 '@S9S_MB_2U_LIB.S9S_MB_2U(SCH_1):PAGE297_I291@PURE_QUANTA.Q_RES(CHIPS)':
 C_PATH='@s9s_mb_2u_lib.s9s_mb_2u(sch_1):page297_i291@pure_quanta.q_res(chips)',
 P_PATH='@s9s_mb_2u_lib.s9s_mb_2u(sch_1):page191_i291@pure_quanta.q_res(chips)',
 PATH='I291',
 DRAWING='@S9S_MB_2U_LIB.S9S_MB_2U(SCH_1):PAGE297',
 PHYS_PAGE='191',
 XY='(-3475,3450)',
 ROT='0',
 VER='2',
 PACK_TYPE='0402LF',
 CDS_LIB='pure_quanta',
 CDS_PART_NAME='Q_RES_0402LF-10K,1%,1/16W,CHIPA',
 WATTAGE='1/16W',
 TOLERANCE='1%',
 MATERIAL='CHIP',
 VALUE='10K',
 PRIM_FILE='./archive_libs/logical/q_res/chips/chips.prt';

PART_NAME
 R3772 'Q_RES_0402LF-0,5%,1/16W,CHIP,CA':;

SECTION_NUMBER 1
 '@S9S_MB_2U_LIB.S9S_MB_2U(SCH_1):PAGE297_I301@PURE_QUANTA.Q_RES(CHIPS)':
 C_PATH='@s9s_mb_2u_lib.s9s_mb_2u(sch_1):page297_i301@pure_quanta.q_res(chips)',
 P_PATH='@s9s_mb_2u_lib.s9s_mb_2u(sch_1):page191_i301@pure_quanta.q_res(chips)',
 PATH='I301',
 DRAWING='@S9S_MB_2U_LIB.S9S_MB_2U(SCH_1):PAGE297',
 PHYS_PAGE='191',
 XY='(1750,-550)',
 ROT='0',
 VER='1',
 PACK_TYPE='0402LF',
 CDS_LIB='pure_quanta',
 CDS_PART_NAME='Q_RES_0402LF-0,5%,1/16W,CHIP,CA',
 WATTAGE='1/16W',
 TOLERANCE='5%',
 MATERIAL='CHIP',
 VALUE='0',
 PRIM_FILE='./archive_libs/logical/q_res/chips/chips.prt';

PART_NAME
 R3773 'Q_RES_0402LF-4.7K,5%,1/16W,EMPA':;

SECTION_NUMBER 1
 '@S9S_MB_2U_LIB.S9S_MB_2U(SCH_1):PAGE297_I299@PURE_QUANTA.Q_RES(CHIPS)':
 C_PATH='@s9s_mb_2u_lib.s9s_mb_2u(sch_1):page297_i299@pure_quanta.q_res(chips)',
 P_PATH='@s9s_mb_2u_lib.s9s_mb_2u(sch_1):page191_i299@pure_quanta.q_res(chips)',
 PATH='I299',
 DRAWING='@S9S_MB_2U_LIB.S9S_MB_2U(SCH_1):PAGE297',
 PHYS_PAGE='191',
 XY='(2775,-200)',
 ROT='0',
 VER='2',
 PACK_TYPE='0402LF',
 CDS_LIB='pure_quanta',
 CDS_PART_NAME='Q_RES_0402LF-4.7K,5%,1/16W,EMPA',
 WATTAGE='1/16W',
 TOLERANCE='5%',
 MATERIAL='EMPTY',
 VALUE='4.7K',
 PRIM_FILE='./archive_libs/logical/q_res/chips/chips.prt';

PART_NAME
 R3775 'Q_RES_0402LF-0,5%,1/16W,CHIP,CA':;

SECTION_NUMBER 1
 '@S9S_MB_2U_LIB.S9S_MB_2U(SCH_1):PAGE297_I307@PURE_QUANTA.Q_RES(CHIPS)':
 C_PATH='@s9s_mb_2u_lib.s9s_mb_2u(sch_1):page297_i307@pure_quanta.q_res(chips)',
 P_PATH='@s9s_mb_2u_lib.s9s_mb_2u(sch_1):page191_i307@pure_quanta.q_res(chips)',
 PATH='I307',
 DRAWING='@S9S_MB_2U_LIB.S9S_MB_2U(SCH_1):PAGE297',
 PHYS_PAGE='191',
 XY='(-1000,-550)',
 ROT='0',
 VER='1',
 PACK_TYPE='0402LF',
 CDS_LIB='pure_quanta',
 CDS_PART_NAME='Q_RES_0402LF-0,5%,1/16W,CHIP,CA',
 WATTAGE='1/16W',
 TOLERANCE='5%',
 MATERIAL='CHIP',
 VALUE='0',
 PRIM_FILE='./archive_libs/logical/q_res/chips/chips.prt';

PART_NAME
 R3776 'Q_RES_0402LF-0,5%,1/16W,CHIP,CA':;

SECTION_NUMBER 1
 '@S9S_MB_2U_LIB.S9S_MB_2U(SCH_1):PAGE227_I21@PURE_QUANTA.Q_RES(CHIPS)':
 C_PATH='@s9s_mb_2u_lib.s9s_mb_2u(sch_1):page227_i21@pure_quanta.q_res(chips)',
 P_PATH='@s9s_mb_2u_lib.s9s_mb_2u(sch_1):page240_i21@pure_quanta.q_res(chips)',
 PATH='I21',
 DRAWING='@S9S_MB_2U_LIB.S9S_MB_2U(SCH_1):PAGE227',
 PHYS_PAGE='240',
 XY='(-13325,-1375)',
 ROT='0',
 VER='1',
 PACK_TYPE='0402LF',
 CDS_LIB='pure_quanta',
 CDS_PART_NAME='Q_RES_0402LF-0,5%,1/16W,CHIP,CA',
 WATTAGE='1/16W',
 TOLERANCE='5%',
 MATERIAL='CHIP',
 VALUE='0',
 PRIM_FILE='./archive_libs/logical/q_res/chips/chips.prt';

PART_NAME
 R3777 'Q_RES_0402LF-0,5%,1/16W,CHIP,CA':;

SECTION_NUMBER 1
 '@S9S_MB_2U_LIB.S9S_MB_2U(SCH_1):PAGE227_I19@PURE_QUANTA.Q_RES(CHIPS)':
 C_PATH='@s9s_mb_2u_lib.s9s_mb_2u(sch_1):page227_i19@pure_quanta.q_res(chips)',
 P_PATH='@s9s_mb_2u_lib.s9s_mb_2u(sch_1):page240_i19@pure_quanta.q_res(chips)',
 PATH='I19',
 DRAWING='@S9S_MB_2U_LIB.S9S_MB_2U(SCH_1):PAGE227',
 PHYS_PAGE='240',
 XY='(-13325,-1525)',
 ROT='0',
 VER='1',
 PACK_TYPE='0402LF',
 CDS_LIB='pure_quanta',
 CDS_PART_NAME='Q_RES_0402LF-0,5%,1/16W,CHIP,CA',
 WATTAGE='1/16W',
 TOLERANCE='5%',
 MATERIAL='CHIP',
 VALUE='0',
 PRIM_FILE='./archive_libs/logical/q_res/chips/chips.prt';

PART_NAME
 R3778 'Q_RES_0402LF-0,5%,1/16W,CHIP,CA':;

SECTION_NUMBER 1
 '@S9S_MB_2U_LIB.S9S_MB_2U(SCH_1):PAGE227_I159@PURE_QUANTA.Q_RES(CHIPS)':
 C_PATH='@s9s_mb_2u_lib.s9s_mb_2u(sch_1):page227_i159@pure_quanta.q_res(chips)',
 P_PATH='@s9s_mb_2u_lib.s9s_mb_2u(sch_1):page240_i159@pure_quanta.q_res(chips)',
 PATH='I159',
 DRAWING='@S9S_MB_2U_LIB.S9S_MB_2U(SCH_1):PAGE227',
 PHYS_PAGE='240',
 XY='(-7800,1525)',
 ROT='0',
 VER='1',
 PACK_TYPE='0402LF',
 CDS_LIB='pure_quanta',
 CDS_PART_NAME='Q_RES_0402LF-0,5%,1/16W,CHIP,CA',
 WATTAGE='1/16W',
 TOLERANCE='5%',
 MATERIAL='CHIP',
 VALUE='0',
 PRIM_FILE='./archive_libs/logical/q_res/chips/chips.prt';

PART_NAME
 R3779 'Q_RES_0402LF-0,5%,1/16W,CHIP,CA':;

SECTION_NUMBER 1
 '@S9S_MB_2U_LIB.S9S_MB_2U(SCH_1):PAGE297_I309@PURE_QUANTA.Q_RES(CHIPS)':
 C_PATH='@s9s_mb_2u_lib.s9s_mb_2u(sch_1):page297_i309@pure_quanta.q_res(chips)',
 P_PATH='@s9s_mb_2u_lib.s9s_mb_2u(sch_1):page191_i309@pure_quanta.q_res(chips)',
 PATH='I309',
 DRAWING='@S9S_MB_2U_LIB.S9S_MB_2U(SCH_1):PAGE297',
 PHYS_PAGE='191',
 XY='(-2000,4200)',
 ROT='0',
 VER='1',
 PACK_TYPE='0402LF',
 CDS_LIB='pure_quanta',
 CDS_PART_NAME='Q_RES_0402LF-0,5%,1/16W,CHIP,CA',
 WATTAGE='1/16W',
 TOLERANCE='5%',
 MATERIAL='CHIP',
 VALUE='0',
 PRIM_FILE='./archive_libs/logical/q_res/chips/chips.prt';

PART_NAME
 R3783 'Q_RES_0402LF-100K,1%,1/16W,CHIA':
 ROOM='NIC1_P3V3_BOM1';

SECTION_NUMBER 1
 '@S9S_MB_2U_LIB.S9S_MB_2U(SCH_1):PAGE153_I110@PURE_QUANTA.Q_RES(CHIPS)':
 C_PATH='@s9s_mb_2u_lib.s9s_mb_2u(sch_1):page153_i110@pure_quanta.q_res(chips)',
 P_PATH='@s9s_mb_2u_lib.s9s_mb_2u(sch_1):page156_i110@pure_quanta.q_res(chips)',
 PATH='I110',
 DRAWING='@S9S_MB_2U_LIB.S9S_MB_2U(SCH_1):PAGE153',
 PHYS_PAGE='156',
 XY='(9950,13075)',
 ROT='0',
 VER='2',
 PACK_TYPE='0402LF',
 LOCATION='R3783',
 CDS_LIB='pure_quanta',
 CDS_PART_NAME='Q_RES_0402LF-100K,1%,1/16W,CHIA',
 WATTAGE='1/16W',
 TOLERANCE='1%',
 MATERIAL='CHIP',
 ROOM='NIC1_P3V3_BOM1',
 VALUE='100K',
 PRIM_FILE='./archive_libs/logical/q_res/chips/chips.prt';

PART_NAME
 R3784 'Q_RES_0402LF-0,5%,1/16W,EMPTY,A':
 ROOM='NIC1_P12V_MAM_MAM_BOM1';

SECTION_NUMBER 1
 '@S9S_MB_2U_LIB.S9S_MB_2U(SCH_1):PAGE153_I39@PURE_QUANTA.Q_RES(CHIPS)':
 C_PATH='@s9s_mb_2u_lib.s9s_mb_2u(sch_1):page153_i39@pure_quanta.q_res(chips)',
 P_PATH='@s9s_mb_2u_lib.s9s_mb_2u(sch_1):page156_i39@pure_quanta.q_res(chips)',
 PATH='I39',
 DRAWING='@S9S_MB_2U_LIB.S9S_MB_2U(SCH_1):PAGE153',
 ROOM1='NIC1_P12V_MAM_TIC_BOM2',
 PHYS_PAGE='156',
 XY='(5400,10875)',
 ROT='0',
 VER='1',
 PACK_TYPE='0402LF',
 CDS_LIB='pure_quanta',
 CDS_PART_NAME='Q_RES_0402LF-0,5%,1/16W,EMPTY,A',
 WATTAGE='1/16W',
 TOLERANCE='5%',
 MATERIAL='EMPTY',
 ROOM='NIC1_P12V_MAM_MAM_BOM1',
 VALUE='0',
 PRIM_FILE='./archive_libs/logical/q_res/chips/chips.prt';

PART_NAME
 R3785 'Q_RES_0402LF-0,5%,1/16W,CHIP,CA':
 ROOM='NIC1_P3V3_BOM1';

SECTION_NUMBER 1
 '@S9S_MB_2U_LIB.S9S_MB_2U(SCH_1):PAGE153_I64@PURE_QUANTA.Q_RES(CHIPS)':
 C_PATH='@s9s_mb_2u_lib.s9s_mb_2u(sch_1):page153_i64@pure_quanta.q_res(chips)',
 P_PATH='@s9s_mb_2u_lib.s9s_mb_2u(sch_1):page156_i64@pure_quanta.q_res(chips)',
 PATH='I64',
 DRAWING='@S9S_MB_2U_LIB.S9S_MB_2U(SCH_1):PAGE153',
 PHYS_PAGE='156',
 XY='(5550,12900)',
 ROT='0',
 VER='1',
 PACK_TYPE='0402LF',
 CDS_LIB='pure_quanta',
 CDS_PART_NAME='Q_RES_0402LF-0,5%,1/16W,CHIP,CA',
 WATTAGE='1/16W',
 TOLERANCE='5%',
 MATERIAL='CHIP',
 ROOM='NIC1_P3V3_BOM1',
 VALUE='0',
 PRIM_FILE='./archive_libs/logical/q_res/chips/chips.prt';

PART_NAME
 R3794 'Q_RES_0402LF-0,5%,1/16W,CHIP,CA':
 ROOM='NIC1_P3V3_BOM1';

SECTION_NUMBER 1
 '@S9S_MB_2U_LIB.S9S_MB_2U(SCH_1):PAGE153_I105@PURE_QUANTA.Q_RES(CHIPS)':
 C_PATH='@s9s_mb_2u_lib.s9s_mb_2u(sch_1):page153_i105@pure_quanta.q_res(chips)',
 P_PATH='@s9s_mb_2u_lib.s9s_mb_2u(sch_1):page156_i105@pure_quanta.q_res(chips)',
 PATH='I105',
 DRAWING='@S9S_MB_2U_LIB.S9S_MB_2U(SCH_1):PAGE153',
 PHYS_PAGE='156',
 XY='(9225,12800)',
 ROT='0',
 VER='1',
 PACK_TYPE='0402LF',
 CDS_LIB='pure_quanta',
 CDS_PART_NAME='Q_RES_0402LF-0,5%,1/16W,CHIP,CA',
 WATTAGE='1/16W',
 TOLERANCE='5%',
 MATERIAL='CHIP',
 ROOM='NIC1_P3V3_BOM1',
 VALUE='0',
 PRIM_FILE='./archive_libs/logical/q_res/chips/chips.prt';

PART_NAME
 R3796 'Q_RES_0402LF-100K,1%,1/16W,CHIA':
 ROOM='NIC1_P3V3_BOM1';

SECTION_NUMBER 1
 '@S9S_MB_2U_LIB.S9S_MB_2U(SCH_1):PAGE153_I108@PURE_QUANTA.Q_RES(CHIPS)':
 C_PATH='@s9s_mb_2u_lib.s9s_mb_2u(sch_1):page153_i108@pure_quanta.q_res(chips)',
 P_PATH='@s9s_mb_2u_lib.s9s_mb_2u(sch_1):page156_i108@pure_quanta.q_res(chips)',
 PATH='I108',
 DRAWING='@S9S_MB_2U_LIB.S9S_MB_2U(SCH_1):PAGE153',
 PHYS_PAGE='156',
 XY='(9575,13075)',
 ROT='0',
 VER='2',
 PACK_TYPE='0402LF',
 LOCATION='R3796',
 CDS_LIB='pure_quanta',
 CDS_PART_NAME='Q_RES_0402LF-100K,1%,1/16W,CHIA',
 WATTAGE='1/16W',
 TOLERANCE='1%',
 MATERIAL='CHIP',
 ROOM='NIC1_P3V3_BOM1',
 VALUE='100K',
 PRIM_FILE='./archive_libs/logical/q_res/chips/chips.prt';

PART_NAME
 R3797 'Q_RES_0402LF-100K,1%,1/16W,EMPA':
 ROOM='NIC1_P12V_MAM_MAM_BOM1';

SECTION_NUMBER 1
 '@S9S_MB_2U_LIB.S9S_MB_2U(SCH_1):PAGE153_I92@PURE_QUANTA.Q_RES(CHIPS)':
 C_PATH='@s9s_mb_2u_lib.s9s_mb_2u(sch_1):page153_i92@pure_quanta.q_res(chips)',
 P_PATH='@s9s_mb_2u_lib.s9s_mb_2u(sch_1):page156_i92@pure_quanta.q_res(chips)',
 PATH='I92',
 DRAWING='@S9S_MB_2U_LIB.S9S_MB_2U(SCH_1):PAGE153',
 ROOM1='NIC1_P12V_MAM_TIC_BOM2',
 PHYS_PAGE='156',
 XY='(9800,10975)',
 ROT='0',
 VER='2',
 PACK_TYPE='0402LF',
 LOCATION='R3797',
 CDS_LIB='pure_quanta',
 CDS_PART_NAME='Q_RES_0402LF-100K,1%,1/16W,EMPA',
 WATTAGE='1/16W',
 TOLERANCE='1%',
 MATERIAL='EMPTY',
 ROOM='NIC1_P12V_MAM_MAM_BOM1',
 VALUE='100K',
 PRIM_FILE='./archive_libs/logical/q_res/chips/chips.prt';

PART_NAME
 R3799 'Q_RES_0402LF-100K,1%,1/16W,EMPA':
 ROOM='NIC1_P12V_MAM_MAM_BOM1';

SECTION_NUMBER 1
 '@S9S_MB_2U_LIB.S9S_MB_2U(SCH_1):PAGE153_I90@PURE_QUANTA.Q_RES(CHIPS)':
 C_PATH='@s9s_mb_2u_lib.s9s_mb_2u(sch_1):page153_i90@pure_quanta.q_res(chips)',
 P_PATH='@s9s_mb_2u_lib.s9s_mb_2u(sch_1):page156_i90@pure_quanta.q_res(chips)',
 PATH='I90',
 DRAWING='@S9S_MB_2U_LIB.S9S_MB_2U(SCH_1):PAGE153',
 ROOM1='NIC1_P12V_MAM_TIC_BOM2',
 PHYS_PAGE='156',
 XY='(9375,10975)',
 ROT='0',
 VER='2',
 PACK_TYPE='0402LF',
 LOCATION='R3799',
 CDS_LIB='pure_quanta',
 CDS_PART_NAME='Q_RES_0402LF-100K,1%,1/16W,EMPA',
 WATTAGE='1/16W',
 TOLERANCE='1%',
 MATERIAL='EMPTY',
 ROOM='NIC1_P12V_MAM_MAM_BOM1',
 VALUE='100K',
 PRIM_FILE='./archive_libs/logical/q_res/chips/chips.prt';

PART_NAME
 R3807 'Q_RES_0402LF-0,5%,1/16W,CHIP,CA':
 ROOM='NIC1_P3V3_BOM1';

SECTION_NUMBER 1
 '@S9S_MB_2U_LIB.S9S_MB_2U(SCH_1):PAGE131_I47@PURE_QUANTA.Q_RES(CHIPS)':
 C_PATH='@s9s_mb_2u_lib.s9s_mb_2u(sch_1):page131_i47@pure_quanta.q_res(chips)',
 P_PATH='@s9s_mb_2u_lib.s9s_mb_2u(sch_1):page162_i47@pure_quanta.q_res(chips)',
 PATH='I47',
 DRAWING='@S9S_MB_2U_LIB.S9S_MB_2U(SCH_1):PAGE131',
 PHYS_PAGE='162',
 XY='(-550,1900)',
 ROT='0',
 VER='1',
 PACK_TYPE='0402LF',
 CDS_LIB='pure_quanta',
 CDS_PART_NAME='Q_RES_0402LF-0,5%,1/16W,CHIP,CA',
 WATTAGE='1/16W',
 TOLERANCE='5%',
 MATERIAL='CHIP',
 ROOM='NIC1_P3V3_BOM1',
 VALUE='0',
 PRIM_FILE='./archive_libs/logical/q_res/chips/chips.prt';

PART_NAME
 R3816 'Q_RES_0402LF-100K,1%,1/16W,EMPA':
 ROOM='NIC1_P12V_MAM_MAM_BOM1';

SECTION_NUMBER 1
 '@S9S_MB_2U_LIB.S9S_MB_2U(SCH_1):PAGE131_I80@PURE_QUANTA.Q_RES(CHIPS)':
 C_PATH='@s9s_mb_2u_lib.s9s_mb_2u(sch_1):page131_i80@pure_quanta.q_res(chips)',
 P_PATH='@s9s_mb_2u_lib.s9s_mb_2u(sch_1):page162_i80@pure_quanta.q_res(chips)',
 PATH='I80',
 DRAWING='@S9S_MB_2U_LIB.S9S_MB_2U(SCH_1):PAGE131',
 ROOM1='NIC1_P12V_MAM_TIC_BOM2',
 PHYS_PAGE='162',
 XY='(3250,-275)',
 ROT='0',
 VER='2',
 PACK_TYPE='0402LF',
 LOCATION='R3816',
 CDS_LIB='pure_quanta',
 CDS_PART_NAME='Q_RES_0402LF-100K,1%,1/16W,EMPA',
 WATTAGE='1/16W',
 TOLERANCE='1%',
 MATERIAL='EMPTY',
 ROOM='NIC1_P12V_MAM_MAM_BOM1',
 VALUE='100K',
 PRIM_FILE='./archive_libs/logical/q_res/chips/chips.prt';

PART_NAME
 R3825 'Q_RES_0402LF-100K,1%,1/16W,EMPA':
 ROOM='NIC1_P12V_MAM_MAM_BOM1';

SECTION_NUMBER 1
 '@S9S_MB_2U_LIB.S9S_MB_2U(SCH_1):PAGE131_I81@PURE_QUANTA.Q_RES(CHIPS)':
 C_PATH='@s9s_mb_2u_lib.s9s_mb_2u(sch_1):page131_i81@pure_quanta.q_res(chips)',
 P_PATH='@s9s_mb_2u_lib.s9s_mb_2u(sch_1):page162_i81@pure_quanta.q_res(chips)',
 PATH='I81',
 DRAWING='@S9S_MB_2U_LIB.S9S_MB_2U(SCH_1):PAGE131',
 ROOM1='NIC1_P12V_MAM_TIC_BOM2',
 PHYS_PAGE='162',
 XY='(3675,-275)',
 ROT='0',
 VER='2',
 PACK_TYPE='0402LF',
 LOCATION='R3825',
 CDS_LIB='pure_quanta',
 CDS_PART_NAME='Q_RES_0402LF-100K,1%,1/16W,EMPA',
 WATTAGE='1/16W',
 TOLERANCE='1%',
 MATERIAL='EMPTY',
 ROOM='NIC1_P12V_MAM_MAM_BOM1',
 VALUE='100K',
 PRIM_FILE='./archive_libs/logical/q_res/chips/chips.prt';

PART_NAME
 R3826 'Q_RES_0402LF-100K,1%,1/16W,CHIA':
 ROOM='NIC1_P3V3_BOM1';

SECTION_NUMBER 1
 '@S9S_MB_2U_LIB.S9S_MB_2U(SCH_1):PAGE131_I110@PURE_QUANTA.Q_RES(CHIPS)':
 C_PATH='@s9s_mb_2u_lib.s9s_mb_2u(sch_1):page131_i110@pure_quanta.q_res(chips)',
 P_PATH='@s9s_mb_2u_lib.s9s_mb_2u(sch_1):page162_i110@pure_quanta.q_res(chips)',
 PATH='I110',
 DRAWING='@S9S_MB_2U_LIB.S9S_MB_2U(SCH_1):PAGE131',
 PHYS_PAGE='162',
 XY='(3800,2100)',
 ROT='0',
 VER='2',
 PACK_TYPE='0402LF',
 LOCATION='R3826',
 CDS_LIB='pure_quanta',
 CDS_PART_NAME='Q_RES_0402LF-100K,1%,1/16W,CHIA',
 WATTAGE='1/16W',
 TOLERANCE='1%',
 MATERIAL='CHIP',
 ROOM='NIC1_P3V3_BOM1',
 VALUE='100K',
 PRIM_FILE='./archive_libs/logical/q_res/chips/chips.prt';

PART_NAME
 R3827 'Q_RES_0402LF-0,5%,1/16W,EMPTY,A':
 ROOM='NIC1_P12V_MAM_MAM_BOM1';

SECTION_NUMBER 1
 '@S9S_MB_2U_LIB.S9S_MB_2U(SCH_1):PAGE131_I30@PURE_QUANTA.Q_RES(CHIPS)':
 C_PATH='@s9s_mb_2u_lib.s9s_mb_2u(sch_1):page131_i30@pure_quanta.q_res(chips)',
 P_PATH='@s9s_mb_2u_lib.s9s_mb_2u(sch_1):page162_i30@pure_quanta.q_res(chips)',
 PATH='I30',
 DRAWING='@S9S_MB_2U_LIB.S9S_MB_2U(SCH_1):PAGE131',
 ROOM1='NIC1_P12V_MAM_TIC_BOM2',
 PHYS_PAGE='162',
 XY='(-775,-425)',
 ROT='0',
 VER='1',
 PACK_TYPE='0402LF',
 CDS_LIB='pure_quanta',
 CDS_PART_NAME='Q_RES_0402LF-0,5%,1/16W,EMPTY,A',
 WATTAGE='1/16W',
 TOLERANCE='5%',
 MATERIAL='EMPTY',
 ROOM='NIC1_P12V_MAM_MAM_BOM1',
 VALUE='0',
 PRIM_FILE='./archive_libs/logical/q_res/chips/chips.prt';

PART_NAME
 R3831 'Q_RES_0402LF-0,5%,1/16W,EMPTY,A':
 ROOM='NIC1_P12V_MAM_MAM_BOM1';

SECTION_NUMBER 1
 '@S9S_MB_2U_LIB.S9S_MB_2U(SCH_1):PAGE131_I78@PURE_QUANTA.Q_RES(CHIPS)':
 C_PATH='@s9s_mb_2u_lib.s9s_mb_2u(sch_1):page131_i78@pure_quanta.q_res(chips)',
 P_PATH='@s9s_mb_2u_lib.s9s_mb_2u(sch_1):page162_i78@pure_quanta.q_res(chips)',
 PATH='I78',
 DRAWING='@S9S_MB_2U_LIB.S9S_MB_2U(SCH_1):PAGE131',
 ROOM1='NIC1_P12V_MAM_TIC_BOM2',
 PHYS_PAGE='162',
 XY='(2900,-525)',
 ROT='0',
 VER='1',
 PACK_TYPE='0402LF',
 CDS_LIB='pure_quanta',
 CDS_PART_NAME='Q_RES_0402LF-0,5%,1/16W,EMPTY,A',
 WATTAGE='1/16W',
 TOLERANCE='5%',
 MATERIAL='EMPTY',
 ROOM='NIC1_P12V_MAM_MAM_BOM1',
 VALUE='0',
 PRIM_FILE='./archive_libs/logical/q_res/chips/chips.prt';

PART_NAME
 R3832 'Q_RES_0402LF-0,5%,1/16W,CHIP,CA':
 ROOM='NIC1_P3V3_BOM1';

SECTION_NUMBER 1
 '@S9S_MB_2U_LIB.S9S_MB_2U(SCH_1):PAGE131_I97@PURE_QUANTA.Q_RES(CHIPS)':
 C_PATH='@s9s_mb_2u_lib.s9s_mb_2u(sch_1):page131_i97@pure_quanta.q_res(chips)',
 P_PATH='@s9s_mb_2u_lib.s9s_mb_2u(sch_1):page162_i97@pure_quanta.q_res(chips)',
 PATH='I97',
 DRAWING='@S9S_MB_2U_LIB.S9S_MB_2U(SCH_1):PAGE131',
 PHYS_PAGE='162',
 XY='(3050,1800)',
 ROT='0',
 VER='1',
 PACK_TYPE='0402LF',
 LOCATION='R3832',
 CDS_LIB='pure_quanta',
 CDS_PART_NAME='Q_RES_0402LF-0,5%,1/16W,CHIP,CA',
 WATTAGE='1/16W',
 TOLERANCE='5%',
 MATERIAL='CHIP',
 ROOM='NIC1_P3V3_BOM1',
 VALUE='0',
 PRIM_FILE='./archive_libs/logical/q_res/chips/chips.prt';

PART_NAME
 R3833 'Q_RES_0402LF-100K,1%,1/16W,CHIA':
 ROOM='NIC1_P3V3_BOM1';

SECTION_NUMBER 1
 '@S9S_MB_2U_LIB.S9S_MB_2U(SCH_1):PAGE131_I108@PURE_QUANTA.Q_RES(CHIPS)':
 C_PATH='@s9s_mb_2u_lib.s9s_mb_2u(sch_1):page131_i108@pure_quanta.q_res(chips)',
 P_PATH='@s9s_mb_2u_lib.s9s_mb_2u(sch_1):page162_i108@pure_quanta.q_res(chips)',
 PATH='I108',
 DRAWING='@S9S_MB_2U_LIB.S9S_MB_2U(SCH_1):PAGE131',
 PHYS_PAGE='162',
 XY='(3400,2100)',
 ROT='0',
 VER='2',
 PACK_TYPE='0402LF',
 LOCATION='R3833',
 CDS_LIB='pure_quanta',
 CDS_PART_NAME='Q_RES_0402LF-100K,1%,1/16W,CHIA',
 WATTAGE='1/16W',
 TOLERANCE='1%',
 MATERIAL='CHIP',
 ROOM='NIC1_P3V3_BOM1',
 VALUE='100K',
 PRIM_FILE='./archive_libs/logical/q_res/chips/chips.prt';

PART_NAME
 R3834 'Q_RES_0402LF-0,5%,1/16W,CHIP,CA':
 ROOM='NIC1_P12V_MPS_MAM_BOM3';

SECTION_NUMBER 1
 '@S9S_MB_2U_LIB.S9S_MB_2U(SCH_1):PAGE236_I65@PURE_QUANTA.Q_RES(CHIPS)':
 C_PATH='@s9s_mb_2u_lib.s9s_mb_2u(sch_1):page236_i65@pure_quanta.q_res(chips)',
 P_PATH='@s9s_mb_2u_lib.s9s_mb_2u(sch_1):page157_i65@pure_quanta.q_res(chips)',
 PATH='I65',
 DRAWING='@S9S_MB_2U_LIB.S9S_MB_2U(SCH_1):PAGE236',
 ROOM1='NIC1_P12V_MPS_TIC_BOM4',
 PHYS_PAGE='157',
 XY='(-7750,9650)',
 ROT='0',
 VER='1',
 PACK_TYPE='0402LF',
 CDS_LIB='pure_quanta',
 CDS_PART_NAME='Q_RES_0402LF-0,5%,1/16W,CHIP,CA',
 WATTAGE='1/16W',
 TOLERANCE='5%',
 MATERIAL='CHIP',
 ROOM='NIC1_P12V_MPS_MAM_BOM3',
 VALUE='0',
 PRIM_FILE='./archive_libs/logical/q_res/chips/chips.prt';

PART_NAME
 R3836 'Q_RES_0402LF-10K,1%,1/16W,CHIPA':
 ROOM='SCM_P12V_BOM2';

SECTION_NUMBER 1
 '@S9S_MB_2U_LIB.S9S_MB_2U(SCH_1):PAGE229_I92@PURE_QUANTA.Q_RES(CHIPS)':
 C_PATH='@s9s_mb_2u_lib.s9s_mb_2u(sch_1):page229_i92@pure_quanta.q_res(chips)',
 P_PATH='@s9s_mb_2u_lib.s9s_mb_2u(sch_1):page242_i92@pure_quanta.q_res(chips)',
 PATH='I92',
 DRAWING='@S9S_MB_2U_LIB.S9S_MB_2U(SCH_1):PAGE229',
 PHYS_PAGE='242',
 XY='(2275,-650)',
 ROT='0',
 VER='2',
 PACK_TYPE='0402LF',
 LOCATION='R3836',
 CDS_LIB='pure_quanta',
 CDS_PART_NAME='Q_RES_0402LF-10K,1%,1/16W,CHIPA',
 WATTAGE='1/16W',
 TOLERANCE='1%',
 MATERIAL='CHIP',
 ROOM='SCM_P12V_BOM2',
 VALUE='10K',
 PRIM_FILE='./archive_libs/logical/q_res/chips/chips.prt';

PART_NAME
 R3845 'Q_RES_0402LF-0,5%,1/16W,EMPTY,A':
 ROOM='NIC1_P3V3_BOM2';

SECTION_NUMBER 1
 '@S9S_MB_2U_LIB.S9S_MB_2U(SCH_1):PAGE236_I46@PURE_QUANTA.Q_RES(CHIPS)':
 C_PATH='@s9s_mb_2u_lib.s9s_mb_2u(sch_1):page236_i46@pure_quanta.q_res(chips)',
 P_PATH='@s9s_mb_2u_lib.s9s_mb_2u(sch_1):page157_i46@pure_quanta.q_res(chips)',
 PATH='I46',
 DRAWING='@S9S_MB_2U_LIB.S9S_MB_2U(SCH_1):PAGE236',
 PHYS_PAGE='157',
 XY='(-3775,12600)',
 ROT='0',
 VER='1',
 PACK_TYPE='0402LF',
 LOCATION='R3845',
 CDS_LIB='pure_quanta',
 CDS_PART_NAME='Q_RES_0402LF-0,5%,1/16W,EMPTY,A',
 WATTAGE='1/16W',
 TOLERANCE='5%',
 MATERIAL='EMPTY',
 ROOM='NIC1_P3V3_BOM2',
 VALUE='0',
 PRIM_FILE='./archive_libs/logical/q_res/chips/chips.prt';

PART_NAME
 R3848 'Q_RES_0402LF-10K,1%,1/16W,CHIPA':
 ROOM='NIC1_P12V_MPS_MAM_BOM3';

SECTION_NUMBER 1
 '@S9S_MB_2U_LIB.S9S_MB_2U(SCH_1):PAGE237_I75@PURE_QUANTA.Q_RES(CHIPS)':
 C_PATH='@s9s_mb_2u_lib.s9s_mb_2u(sch_1):page237_i75@pure_quanta.q_res(chips)',
 P_PATH='@s9s_mb_2u_lib.s9s_mb_2u(sch_1):page163_i75@pure_quanta.q_res(chips)',
 PATH='I75',
 DRAWING='@S9S_MB_2U_LIB.S9S_MB_2U(SCH_1):PAGE237',
 ROOM1='NIC1_P12V_MPS_TIC_BOM4',
 PHYS_PAGE='163',
 XY='(-2050,3725)',
 ROT='0',
 VER='2',
 PACK_TYPE='0402LF',
 CDS_LIB='pure_quanta',
 CDS_PART_NAME='Q_RES_0402LF-10K,1%,1/16W,CHIPA',
 WATTAGE='1/16W',
 TOLERANCE='1%',
 MATERIAL='CHIP',
 ROOM='NIC1_P12V_MPS_MAM_BOM3',
 VALUE='10K',
 PRIM_FILE='./archive_libs/logical/q_res/chips/chips.prt';

PART_NAME
 R3858 'Q_RES_0402LF-33.2,1%,1/16W,CHIA':;

SECTION_NUMBER 1
 '@S9S_MB_2U_LIB.S9S_MB_2U(SCH_1):PAGE227_I94@PURE_QUANTA.Q_RES(CHIPS)':
 C_PATH='@s9s_mb_2u_lib.s9s_mb_2u(sch_1):page227_i94@pure_quanta.q_res(chips)',
 P_PATH='@s9s_mb_2u_lib.s9s_mb_2u(sch_1):page240_i94@pure_quanta.q_res(chips)',
 PATH='I94',
 DRAWING='@S9S_MB_2U_LIB.S9S_MB_2U(SCH_1):PAGE227',
 PHYS_PAGE='240',
 XY='(-13275,825)',
 ROT='0',
 VER='1',
 PACK_TYPE='0402LF',
 CDS_LIB='pure_quanta',
 CDS_PART_NAME='Q_RES_0402LF-33.2,1%,1/16W,CHIA',
 WATTAGE='1/16W',
 TOLERANCE='1%',
 MATERIAL='CHIP',
 VALUE='33.2',
 PRIM_FILE='./archive_libs/logical/q_res/chips/chips.prt';

PART_NAME
 R3859 'Q_RES_0402LF-0,5%,1/16W,EMPTY,A':
 ROOM='NIC1_P12V_MAM_MAM_BOM1 ';

SECTION_NUMBER 1
 '@S9S_MB_2U_LIB.S9S_MB_2U(SCH_1):PAGE239_I321@PURE_QUANTA.Q_RES(CHIPS)':
 C_PATH='@s9s_mb_2u_lib.s9s_mb_2u(sch_1):page239_i321@pure_quanta.q_res(chips)',
 P_PATH='@s9s_mb_2u_lib.s9s_mb_2u(sch_1):page250_i321@pure_quanta.q_res(chips)',
 PATH='I321',
 DRAWING='@S9S_MB_2U_LIB.S9S_MB_2U(SCH_1):PAGE239',
 PHYS_PAGE='250',
 XY='(2225,4225)',
 ROT='0',
 VER='1',
 PACK_TYPE='0402LF',
 CDS_LIB='pure_quanta',
 CDS_PART_NAME='Q_RES_0402LF-0,5%,1/16W,EMPTY,A',
 WATTAGE='1/16W',
 TOLERANCE='5%',
 MATERIAL='EMPTY',
 ROOM='NIC1_P12V_MAM_MAM_BOM1 ',
 VALUE='0',
 PRIM_FILE='./archive_libs/logical/q_res/chips/chips.prt';

PART_NAME
 R3860 'Q_RES_0402LF-0,5%,1/16W,EMPTY,A':
 ROOM='NIC1_P12V_MPS_MAM_BOM3 ';

SECTION_NUMBER 1
 '@S9S_MB_2U_LIB.S9S_MB_2U(SCH_1):PAGE239_I322@PURE_QUANTA.Q_RES(CHIPS)':
 C_PATH='@s9s_mb_2u_lib.s9s_mb_2u(sch_1):page239_i322@pure_quanta.q_res(chips)',
 P_PATH='@s9s_mb_2u_lib.s9s_mb_2u(sch_1):page250_i322@pure_quanta.q_res(chips)',
 PATH='I322',
 DRAWING='@S9S_MB_2U_LIB.S9S_MB_2U(SCH_1):PAGE239',
 PHYS_PAGE='250',
 XY='(2225,4075)',
 ROT='0',
 VER='1',
 PACK_TYPE='0402LF',
 CDS_LIB='pure_quanta',
 CDS_PART_NAME='Q_RES_0402LF-0,5%,1/16W,EMPTY,A',
 WATTAGE='1/16W',
 TOLERANCE='5%',
 MATERIAL='EMPTY',
 ROOM='NIC1_P12V_MPS_MAM_BOM3 ',
 VALUE='0',
 PRIM_FILE='./archive_libs/logical/q_res/chips/chips.prt';

PART_NAME
 R3861 'Q_RES_0402LF-0,5%,1/16W,EMPTY,A':;

SECTION_NUMBER 1
 '@S9S_MB_2U_LIB.S9S_MB_2U(SCH_1):PAGE239_I323@PURE_QUANTA.Q_RES(CHIPS)':
 C_PATH='@s9s_mb_2u_lib.s9s_mb_2u(sch_1):page239_i323@pure_quanta.q_res(chips)',
 P_PATH='@s9s_mb_2u_lib.s9s_mb_2u(sch_1):page250_i323@pure_quanta.q_res(chips)',
 PATH='I323',
 DRAWING='@S9S_MB_2U_LIB.S9S_MB_2U(SCH_1):PAGE239',
 ROOM1='NIC1_P12V_MAM_TIC_BOM2 ',
 PHYS_PAGE='250',
 XY='(2225,3725)',
 ROT='0',
 VER='1',
 PACK_TYPE='0402LF',
 CDS_LIB='pure_quanta',
 CDS_PART_NAME='Q_RES_0402LF-0,5%,1/16W,EMPTY,A',
 WATTAGE='1/16W',
 TOLERANCE='5%',
 MATERIAL='EMPTY',
 VALUE='0',
 PRIM_FILE='./archive_libs/logical/q_res/chips/chips.prt';

PART_NAME
 R3862 'Q_RES_0402LF-0,5%,1/16W,CHIP,CA':;

SECTION_NUMBER 1
 '@S9S_MB_2U_LIB.S9S_MB_2U(SCH_1):PAGE239_I324@PURE_QUANTA.Q_RES(CHIPS)':
 C_PATH='@s9s_mb_2u_lib.s9s_mb_2u(sch_1):page239_i324@pure_quanta.q_res(chips)',
 P_PATH='@s9s_mb_2u_lib.s9s_mb_2u(sch_1):page250_i324@pure_quanta.q_res(chips)',
 PATH='I324',
 DRAWING='@S9S_MB_2U_LIB.S9S_MB_2U(SCH_1):PAGE239',
 ROOM1='NIC1_P12V_MPS_TIC_BOM4 ',
 PHYS_PAGE='250',
 XY='(2225,3575)',
 ROT='0',
 VER='1',
 PACK_TYPE='0402LF',
 CDS_LIB='pure_quanta',
 CDS_PART_NAME='Q_RES_0402LF-0,5%,1/16W,CHIP,CA',
 WATTAGE='1/16W',
 TOLERANCE='5%',
 MATERIAL='CHIP',
 VALUE='0',
 PRIM_FILE='./archive_libs/logical/q_res/chips/chips.prt';

PART_NAME
 R3863 'Q_RES_0402LF-0,5%,1/16W,EMPTY,A':
 ROOM='NIC1_P12V_MAM_MAM_BOM1';

SECTION_NUMBER 1
 '@S9S_MB_2U_LIB.S9S_MB_2U(SCH_1):PAGE239_I313@PURE_QUANTA.Q_RES(CHIPS)':
 C_PATH='@s9s_mb_2u_lib.s9s_mb_2u(sch_1):page239_i313@pure_quanta.q_res(chips)',
 P_PATH='@s9s_mb_2u_lib.s9s_mb_2u(sch_1):page250_i313@pure_quanta.q_res(chips)',
 PATH='I313',
 DRAWING='@S9S_MB_2U_LIB.S9S_MB_2U(SCH_1):PAGE239',
 PHYS_PAGE='250',
 XY='(2250,5200)',
 ROT='0',
 VER='1',
 PACK_TYPE='0402LF',
 CDS_LIB='pure_quanta',
 CDS_PART_NAME='Q_RES_0402LF-0,5%,1/16W,EMPTY,A',
 WATTAGE='1/16W',
 TOLERANCE='5%',
 MATERIAL='EMPTY',
 ROOM='NIC1_P12V_MAM_MAM_BOM1',
 VALUE='0',
 PRIM_FILE='./archive_libs/logical/q_res/chips/chips.prt';

PART_NAME
 R3864 'Q_RES_0402LF-0,5%,1/16W,EMPTY,A':
 ROOM='NIC1_P12V_MPS_MAM_BOM3';

SECTION_NUMBER 1
 '@S9S_MB_2U_LIB.S9S_MB_2U(SCH_1):PAGE239_I314@PURE_QUANTA.Q_RES(CHIPS)':
 C_PATH='@s9s_mb_2u_lib.s9s_mb_2u(sch_1):page239_i314@pure_quanta.q_res(chips)',
 P_PATH='@s9s_mb_2u_lib.s9s_mb_2u(sch_1):page250_i314@pure_quanta.q_res(chips)',
 PATH='I314',
 DRAWING='@S9S_MB_2U_LIB.S9S_MB_2U(SCH_1):PAGE239',
 PHYS_PAGE='250',
 XY='(2250,5050)',
 ROT='0',
 VER='1',
 PACK_TYPE='0402LF',
 CDS_LIB='pure_quanta',
 CDS_PART_NAME='Q_RES_0402LF-0,5%,1/16W,EMPTY,A',
 WATTAGE='1/16W',
 TOLERANCE='5%',
 MATERIAL='EMPTY',
 ROOM='NIC1_P12V_MPS_MAM_BOM3',
 VALUE='0',
 PRIM_FILE='./archive_libs/logical/q_res/chips/chips.prt';

PART_NAME
 R3865 'Q_RES_0402LF-0,5%,1/16W,EMPTY,A':;

SECTION_NUMBER 1
 '@S9S_MB_2U_LIB.S9S_MB_2U(SCH_1):PAGE239_I315@PURE_QUANTA.Q_RES(CHIPS)':
 C_PATH='@s9s_mb_2u_lib.s9s_mb_2u(sch_1):page239_i315@pure_quanta.q_res(chips)',
 P_PATH='@s9s_mb_2u_lib.s9s_mb_2u(sch_1):page250_i315@pure_quanta.q_res(chips)',
 PATH='I315',
 DRAWING='@S9S_MB_2U_LIB.S9S_MB_2U(SCH_1):PAGE239',
 ROOM1='NIC1_P12V_MAM_TIC_BOM2',
 PHYS_PAGE='250',
 XY='(2250,4700)',
 ROT='0',
 VER='1',
 PACK_TYPE='0402LF',
 CDS_LIB='pure_quanta',
 CDS_PART_NAME='Q_RES_0402LF-0,5%,1/16W,EMPTY,A',
 WATTAGE='1/16W',
 TOLERANCE='5%',
 MATERIAL='EMPTY',
 VALUE='0',
 PRIM_FILE='./archive_libs/logical/q_res/chips/chips.prt';

PART_NAME
 R3866 'Q_RES_0402LF-0,5%,1/16W,CHIP,CA':;

SECTION_NUMBER 1
 '@S9S_MB_2U_LIB.S9S_MB_2U(SCH_1):PAGE239_I316@PURE_QUANTA.Q_RES(CHIPS)':
 C_PATH='@s9s_mb_2u_lib.s9s_mb_2u(sch_1):page239_i316@pure_quanta.q_res(chips)',
 P_PATH='@s9s_mb_2u_lib.s9s_mb_2u(sch_1):page250_i316@pure_quanta.q_res(chips)',
 PATH='I316',
 DRAWING='@S9S_MB_2U_LIB.S9S_MB_2U(SCH_1):PAGE239',
 ROOM1='NIC1_P12V_MPS_TIC_BOM4',
 PHYS_PAGE='250',
 XY='(2250,4550)',
 ROT='0',
 VER='1',
 PACK_TYPE='0402LF',
 CDS_LIB='pure_quanta',
 CDS_PART_NAME='Q_RES_0402LF-0,5%,1/16W,CHIP,CA',
 WATTAGE='1/16W',
 TOLERANCE='5%',
 MATERIAL='CHIP',
 VALUE='0',
 PRIM_FILE='./archive_libs/logical/q_res/chips/chips.prt';

PART_NAME
 R3867 'Q_RES_0402LF-0,5%,1/16W,EMPTY,A':
 ROOM='NIC1_P12V_MAM_MAM_BOM1';

SECTION_NUMBER 1
 '@S9S_MB_2U_LIB.S9S_MB_2U(SCH_1):PAGE131_I75@PURE_QUANTA.Q_RES(CHIPS)':
 C_PATH='@s9s_mb_2u_lib.s9s_mb_2u(sch_1):page131_i75@pure_quanta.q_res(chips)',
 P_PATH='@s9s_mb_2u_lib.s9s_mb_2u(sch_1):page162_i75@pure_quanta.q_res(chips)',
 PATH='I75',
 DRAWING='@S9S_MB_2U_LIB.S9S_MB_2U(SCH_1):PAGE131',
 PHYS_PAGE='162',
 XY='(3050,-725)',
 ROT='0',
 VER='1',
 PACK_TYPE='0402LF',
 CDS_LIB='pure_quanta',
 CDS_PART_NAME='Q_RES_0402LF-0,5%,1/16W,EMPTY,A',
 WATTAGE='1/16W',
 TOLERANCE='5%',
 MATERIAL='EMPTY',
 ROOM='NIC1_P12V_MAM_MAM_BOM1',
 VALUE='0',
 PRIM_FILE='./archive_libs/logical/q_res/chips/chips.prt';

PART_NAME
 R3868 'Q_RES_0402LF-0,5%,1/16W,EMPTY,A':;

SECTION_NUMBER 1
 '@S9S_MB_2U_LIB.S9S_MB_2U(SCH_1):PAGE131_I74@PURE_QUANTA.Q_RES(CHIPS)':
 C_PATH='@s9s_mb_2u_lib.s9s_mb_2u(sch_1):page131_i74@pure_quanta.q_res(chips)',
 P_PATH='@s9s_mb_2u_lib.s9s_mb_2u(sch_1):page162_i74@pure_quanta.q_res(chips)',
 PATH='I74',
 DRAWING='@S9S_MB_2U_LIB.S9S_MB_2U(SCH_1):PAGE131',
 ROOM1='NIC1_P12V_MAM_TIC_BOM2',
 PHYS_PAGE='162',
 XY='(3050,-850)',
 ROT='0',
 VER='1',
 PACK_TYPE='0402LF',
 CDS_LIB='pure_quanta',
 CDS_PART_NAME='Q_RES_0402LF-0,5%,1/16W,EMPTY,A',
 WATTAGE='1/16W',
 TOLERANCE='5%',
 MATERIAL='EMPTY',
 VALUE='0',
 PRIM_FILE='./archive_libs/logical/q_res/chips/chips.prt';

PART_NAME
 R3869 'Q_RES_0402LF-0,5%,1/16W,EMPTY,A':
 ROOM='NIC1_P12V_MAM_MAM_BOM1';

SECTION_NUMBER 1
 '@S9S_MB_2U_LIB.S9S_MB_2U(SCH_1):PAGE153_I87@PURE_QUANTA.Q_RES(CHIPS)':
 C_PATH='@s9s_mb_2u_lib.s9s_mb_2u(sch_1):page153_i87@pure_quanta.q_res(chips)',
 P_PATH='@s9s_mb_2u_lib.s9s_mb_2u(sch_1):page156_i87@pure_quanta.q_res(chips)',
 PATH='I87',
 DRAWING='@S9S_MB_2U_LIB.S9S_MB_2U(SCH_1):PAGE153',
 PHYS_PAGE='156',
 XY='(9275,10500)',
 ROT='0',
 VER='1',
 PACK_TYPE='0402LF',
 CDS_LIB='pure_quanta',
 CDS_PART_NAME='Q_RES_0402LF-0,5%,1/16W,EMPTY,A',
 WATTAGE='1/16W',
 TOLERANCE='5%',
 MATERIAL='EMPTY',
 ROOM='NIC1_P12V_MAM_MAM_BOM1',
 VALUE='0',
 PRIM_FILE='./archive_libs/logical/q_res/chips/chips.prt';

PART_NAME
 R3870 'Q_RES_0402LF-0,5%,1/16W,EMPTY,A':;

SECTION_NUMBER 1
 '@S9S_MB_2U_LIB.S9S_MB_2U(SCH_1):PAGE153_I88@PURE_QUANTA.Q_RES(CHIPS)':
 C_PATH='@s9s_mb_2u_lib.s9s_mb_2u(sch_1):page153_i88@pure_quanta.q_res(chips)',
 P_PATH='@s9s_mb_2u_lib.s9s_mb_2u(sch_1):page156_i88@pure_quanta.q_res(chips)',
 PATH='I88',
 DRAWING='@S9S_MB_2U_LIB.S9S_MB_2U(SCH_1):PAGE153',
 ROOM1='NIC1_P12V_MAM_TIC_BOM2',
 PHYS_PAGE='156',
 XY='(9275,10375)',
 ROT='0',
 VER='1',
 PACK_TYPE='0402LF',
 CDS_LIB='pure_quanta',
 CDS_PART_NAME='Q_RES_0402LF-0,5%,1/16W,EMPTY,A',
 WATTAGE='1/16W',
 TOLERANCE='5%',
 MATERIAL='EMPTY',
 VALUE='0',
 PRIM_FILE='./archive_libs/logical/q_res/chips/chips.prt';

PART_NAME
 R3871 'Q_RES_0402LF-0,5%,1/16W,EMPTY,A':
 ROOM='NIC1_P12V_MPS_MAM_BOM3';

SECTION_NUMBER 1
 '@S9S_MB_2U_LIB.S9S_MB_2U(SCH_1):PAGE236_I82@PURE_QUANTA.Q_RES(CHIPS)':
 C_PATH='@s9s_mb_2u_lib.s9s_mb_2u(sch_1):page236_i82@pure_quanta.q_res(chips)',
 P_PATH='@s9s_mb_2u_lib.s9s_mb_2u(sch_1):page157_i82@pure_quanta.q_res(chips)',
 PATH='I82',
 DRAWING='@S9S_MB_2U_LIB.S9S_MB_2U(SCH_1):PAGE236',
 PHYS_PAGE='157',
 XY='(-4000,8625)',
 ROT='0',
 VER='1',
 PACK_TYPE='0402LF',
 CDS_LIB='pure_quanta',
 CDS_PART_NAME='Q_RES_0402LF-0,5%,1/16W,EMPTY,A',
 WATTAGE='1/16W',
 TOLERANCE='5%',
 MATERIAL='EMPTY',
 ROOM='NIC1_P12V_MPS_MAM_BOM3',
 VALUE='0',
 PRIM_FILE='./archive_libs/logical/q_res/chips/chips.prt';

PART_NAME
 R3872 'Q_RES_0402LF-0,5%,1/16W,CHIP,CA':;

SECTION_NUMBER 1
 '@S9S_MB_2U_LIB.S9S_MB_2U(SCH_1):PAGE236_I81@PURE_QUANTA.Q_RES(CHIPS)':
 C_PATH='@s9s_mb_2u_lib.s9s_mb_2u(sch_1):page236_i81@pure_quanta.q_res(chips)',
 P_PATH='@s9s_mb_2u_lib.s9s_mb_2u(sch_1):page157_i81@pure_quanta.q_res(chips)',
 PATH='I81',
 DRAWING='@S9S_MB_2U_LIB.S9S_MB_2U(SCH_1):PAGE236',
 ROOM1='NIC1_P12V_MPS_TIC_BOM4',
 PHYS_PAGE='157',
 XY='(-4000,8450)',
 ROT='0',
 VER='1',
 PACK_TYPE='0402LF',
 CDS_LIB='pure_quanta',
 CDS_PART_NAME='Q_RES_0402LF-0,5%,1/16W,CHIP,CA',
 WATTAGE='1/16W',
 TOLERANCE='5%',
 MATERIAL='CHIP',
 VALUE='0',
 PRIM_FILE='./archive_libs/logical/q_res/chips/chips.prt';

PART_NAME
 R3873 'Q_RES_0402LF-0,5%,1/16W,EMPTY,A':
 ROOM='NIC1_P12V_MPS_MAM_BOM3';

SECTION_NUMBER 1
 '@S9S_MB_2U_LIB.S9S_MB_2U(SCH_1):PAGE237_I81@PURE_QUANTA.Q_RES(CHIPS)':
 C_PATH='@s9s_mb_2u_lib.s9s_mb_2u(sch_1):page237_i81@pure_quanta.q_res(chips)',
 P_PATH='@s9s_mb_2u_lib.s9s_mb_2u(sch_1):page163_i81@pure_quanta.q_res(chips)',
 PATH='I81',
 DRAWING='@S9S_MB_2U_LIB.S9S_MB_2U(SCH_1):PAGE237',
 PHYS_PAGE='163',
 XY='(-150,2200)',
 ROT='0',
 VER='1',
 PACK_TYPE='0402LF',
 CDS_LIB='pure_quanta',
 CDS_PART_NAME='Q_RES_0402LF-0,5%,1/16W,EMPTY,A',
 WATTAGE='1/16W',
 TOLERANCE='5%',
 MATERIAL='EMPTY',
 ROOM='NIC1_P12V_MPS_MAM_BOM3',
 VALUE='0',
 PRIM_FILE='./archive_libs/logical/q_res/chips/chips.prt';

PART_NAME
 R3874 'Q_RES_0402LF-0,5%,1/16W,CHIP,CA':;

SECTION_NUMBER 1
 '@S9S_MB_2U_LIB.S9S_MB_2U(SCH_1):PAGE237_I80@PURE_QUANTA.Q_RES(CHIPS)':
 C_PATH='@s9s_mb_2u_lib.s9s_mb_2u(sch_1):page237_i80@pure_quanta.q_res(chips)',
 P_PATH='@s9s_mb_2u_lib.s9s_mb_2u(sch_1):page163_i80@pure_quanta.q_res(chips)',
 PATH='I80',
 DRAWING='@S9S_MB_2U_LIB.S9S_MB_2U(SCH_1):PAGE237',
 ROOM1='NIC1_P12V_MPS_TIC_BOM4',
 PHYS_PAGE='163',
 XY='(-150,2075)',
 ROT='0',
 VER='1',
 PACK_TYPE='0402LF',
 CDS_LIB='pure_quanta',
 CDS_PART_NAME='Q_RES_0402LF-0,5%,1/16W,CHIP,CA',
 WATTAGE='1/16W',
 TOLERANCE='5%',
 MATERIAL='CHIP',
 VALUE='0',
 PRIM_FILE='./archive_libs/logical/q_res/chips/chips.prt';

PART_NAME
 R3875 'Q_RES_0402LF-49.9,1%,1/16W,CHIA':;

SECTION_NUMBER 1
 '@S9S_MB_2U_LIB.S9S_MB_2U(SCH_1):PAGE82_I204@PURE_QUANTA.Q_RES(CHIPS)':
 C_PATH='@s9s_mb_2u_lib.s9s_mb_2u(sch_1):page82_i204@pure_quanta.q_res(chips)',
 P_PATH='@s9s_mb_2u_lib.s9s_mb_2u(sch_1):page82_i204@pure_quanta.q_res(chips)',
 PATH='I204',
 DRAWING='@S9S_MB_2U_LIB.S9S_MB_2U(SCH_1):PAGE82',
 PHYS_PAGE='82',
 XY='(-3275,1625)',
 ROT='0',
 VER='1',
 PACK_TYPE='0402LF',
 CDS_LIB='pure_quanta',
 CDS_PART_NAME='Q_RES_0402LF-49.9,1%,1/16W,CHIA',
 WATTAGE='1/16W',
 TOLERANCE='1%',
 MATERIAL='CHIP',
 VALUE='49.9',
 PRIM_FILE='./archive_libs/logical/q_res/chips/chips.prt';

PART_NAME
 R3876 'Q_RES_0402LF-49.9,1%,1/16W,CHIA':;

SECTION_NUMBER 1
 '@S9S_MB_2U_LIB.S9S_MB_2U(SCH_1):PAGE83_I182@PURE_QUANTA.Q_RES(CHIPS)':
 C_PATH='@s9s_mb_2u_lib.s9s_mb_2u(sch_1):page83_i182@pure_quanta.q_res(chips)',
 P_PATH='@s9s_mb_2u_lib.s9s_mb_2u(sch_1):page83_i182@pure_quanta.q_res(chips)',
 PATH='I182',
 DRAWING='@S9S_MB_2U_LIB.S9S_MB_2U(SCH_1):PAGE83',
 PHYS_PAGE='83',
 XY='(-2650,1500)',
 ROT='0',
 VER='1',
 PACK_TYPE='0402LF',
 CDS_LIB='pure_quanta',
 CDS_PART_NAME='Q_RES_0402LF-49.9,1%,1/16W,CHIA',
 WATTAGE='1/16W',
 TOLERANCE='1%',
 MATERIAL='CHIP',
 VALUE='49.9',
 PRIM_FILE='./archive_libs/logical/q_res/chips/chips.prt';

PART_NAME
 R3877 'Q_RES_0402LF-49.9,1%,1/16W,CHIA':;

SECTION_NUMBER 1
 '@S9S_MB_2U_LIB.S9S_MB_2U(SCH_1):PAGE84_I182@PURE_QUANTA.Q_RES(CHIPS)':
 C_PATH='@s9s_mb_2u_lib.s9s_mb_2u(sch_1):page84_i182@pure_quanta.q_res(chips)',
 P_PATH='@s9s_mb_2u_lib.s9s_mb_2u(sch_1):page84_i182@pure_quanta.q_res(chips)',
 PATH='I182',
 DRAWING='@S9S_MB_2U_LIB.S9S_MB_2U(SCH_1):PAGE84',
 PHYS_PAGE='84',
 XY='(-2800,1200)',
 ROT='0',
 VER='1',
 PACK_TYPE='0402LF',
 CDS_LIB='pure_quanta',
 CDS_PART_NAME='Q_RES_0402LF-49.9,1%,1/16W,CHIA',
 WATTAGE='1/16W',
 TOLERANCE='1%',
 MATERIAL='CHIP',
 VALUE='49.9',
 PRIM_FILE='./archive_libs/logical/q_res/chips/chips.prt';

PART_NAME
 R3878 'Q_RES_0402LF-49.9,1%,1/16W,CHIA':;

SECTION_NUMBER 1
 '@S9S_MB_2U_LIB.S9S_MB_2U(SCH_1):PAGE85_I180@PURE_QUANTA.Q_RES(CHIPS)':
 C_PATH='@s9s_mb_2u_lib.s9s_mb_2u(sch_1):page85_i180@pure_quanta.q_res(chips)',
 P_PATH='@s9s_mb_2u_lib.s9s_mb_2u(sch_1):page85_i180@pure_quanta.q_res(chips)',
 PATH='I180',
 DRAWING='@S9S_MB_2U_LIB.S9S_MB_2U(SCH_1):PAGE85',
 PHYS_PAGE='85',
 XY='(-3275,1700)',
 ROT='0',
 VER='1',
 PACK_TYPE='0402LF',
 CDS_LIB='pure_quanta',
 CDS_PART_NAME='Q_RES_0402LF-49.9,1%,1/16W,CHIA',
 WATTAGE='1/16W',
 TOLERANCE='1%',
 MATERIAL='CHIP',
 VALUE='49.9',
 PRIM_FILE='./archive_libs/logical/q_res/chips/chips.prt';

PART_NAME
 R3879 'Q_RES_0402LF-49.9,1%,1/16W,CHIA':;

SECTION_NUMBER 1
 '@S9S_MB_2U_LIB.S9S_MB_2U(SCH_1):PAGE86_I180@PURE_QUANTA.Q_RES(CHIPS)':
 C_PATH='@s9s_mb_2u_lib.s9s_mb_2u(sch_1):page86_i180@pure_quanta.q_res(chips)',
 P_PATH='@s9s_mb_2u_lib.s9s_mb_2u(sch_1):page86_i180@pure_quanta.q_res(chips)',
 PATH='I180',
 DRAWING='@S9S_MB_2U_LIB.S9S_MB_2U(SCH_1):PAGE86',
 PHYS_PAGE='86',
 XY='(-3925,1450)',
 ROT='0',
 VER='1',
 PACK_TYPE='0402LF',
 CDS_LIB='pure_quanta',
 CDS_PART_NAME='Q_RES_0402LF-49.9,1%,1/16W,CHIA',
 WATTAGE='1/16W',
 TOLERANCE='1%',
 MATERIAL='CHIP',
 VALUE='49.9',
 PRIM_FILE='./archive_libs/logical/q_res/chips/chips.prt';

PART_NAME
 R3880 'Q_RES_0402LF-49.9,1%,1/16W,CHIA':;

SECTION_NUMBER 1
 '@S9S_MB_2U_LIB.S9S_MB_2U(SCH_1):PAGE87_I180@PURE_QUANTA.Q_RES(CHIPS)':
 C_PATH='@s9s_mb_2u_lib.s9s_mb_2u(sch_1):page87_i180@pure_quanta.q_res(chips)',
 P_PATH='@s9s_mb_2u_lib.s9s_mb_2u(sch_1):page87_i180@pure_quanta.q_res(chips)',
 PATH='I180',
 DRAWING='@S9S_MB_2U_LIB.S9S_MB_2U(SCH_1):PAGE87',
 PHYS_PAGE='87',
 XY='(-3150,1500)',
 ROT='0',
 VER='1',
 PACK_TYPE='0402LF',
 CDS_LIB='pure_quanta',
 CDS_PART_NAME='Q_RES_0402LF-49.9,1%,1/16W,CHIA',
 WATTAGE='1/16W',
 TOLERANCE='1%',
 MATERIAL='CHIP',
 VALUE='49.9',
 PRIM_FILE='./archive_libs/logical/q_res/chips/chips.prt';

PART_NAME
 R3881 'Q_RES_0402LF-49.9,1%,1/16W,CHIA':;

SECTION_NUMBER 1
 '@S9S_MB_2U_LIB.S9S_MB_2U(SCH_1):PAGE88_I180@PURE_QUANTA.Q_RES(CHIPS)':
 C_PATH='@s9s_mb_2u_lib.s9s_mb_2u(sch_1):page88_i180@pure_quanta.q_res(chips)',
 P_PATH='@s9s_mb_2u_lib.s9s_mb_2u(sch_1):page88_i180@pure_quanta.q_res(chips)',
 PATH='I180',
 DRAWING='@S9S_MB_2U_LIB.S9S_MB_2U(SCH_1):PAGE88',
 PHYS_PAGE='88',
 XY='(-2975,1325)',
 ROT='0',
 VER='1',
 PACK_TYPE='0402LF',
 CDS_LIB='pure_quanta',
 CDS_PART_NAME='Q_RES_0402LF-49.9,1%,1/16W,CHIA',
 WATTAGE='1/16W',
 TOLERANCE='1%',
 MATERIAL='CHIP',
 VALUE='49.9',
 PRIM_FILE='./archive_libs/logical/q_res/chips/chips.prt';

PART_NAME
 R3882 'Q_RES_0402LF-49.9,1%,1/16W,CHIA':;

SECTION_NUMBER 1
 '@S9S_MB_2U_LIB.S9S_MB_2U(SCH_1):PAGE89_I180@PURE_QUANTA.Q_RES(CHIPS)':
 C_PATH='@s9s_mb_2u_lib.s9s_mb_2u(sch_1):page89_i180@pure_quanta.q_res(chips)',
 P_PATH='@s9s_mb_2u_lib.s9s_mb_2u(sch_1):page89_i180@pure_quanta.q_res(chips)',
 PATH='I180',
 DRAWING='@S9S_MB_2U_LIB.S9S_MB_2U(SCH_1):PAGE89',
 PHYS_PAGE='89',
 XY='(-3400,1525)',
 ROT='0',
 VER='1',
 PACK_TYPE='0402LF',
 CDS_LIB='pure_quanta',
 CDS_PART_NAME='Q_RES_0402LF-49.9,1%,1/16W,CHIA',
 WATTAGE='1/16W',
 TOLERANCE='1%',
 MATERIAL='CHIP',
 VALUE='49.9',
 PRIM_FILE='./archive_libs/logical/q_res/chips/chips.prt';

PART_NAME
 R3883 'Q_RES_0402LF-49.9,1%,1/16W,CHIA':;

SECTION_NUMBER 1
 '@S9S_MB_2U_LIB.S9S_MB_2U(SCH_1):PAGE90_I179@PURE_QUANTA.Q_RES(CHIPS)':
 C_PATH='@s9s_mb_2u_lib.s9s_mb_2u(sch_1):page90_i179@pure_quanta.q_res(chips)',
 P_PATH='@s9s_mb_2u_lib.s9s_mb_2u(sch_1):page90_i179@pure_quanta.q_res(chips)',
 PATH='I179',
 DRAWING='@S9S_MB_2U_LIB.S9S_MB_2U(SCH_1):PAGE90',
 PHYS_PAGE='90',
 XY='(-2650,1325)',
 ROT='0',
 VER='1',
 PACK_TYPE='0402LF',
 CDS_LIB='pure_quanta',
 CDS_PART_NAME='Q_RES_0402LF-49.9,1%,1/16W,CHIA',
 WATTAGE='1/16W',
 TOLERANCE='1%',
 MATERIAL='CHIP',
 VALUE='49.9',
 PRIM_FILE='./archive_libs/logical/q_res/chips/chips.prt';

PART_NAME
 R3884 'Q_RES_0402LF-49.9,1%,1/16W,CHIA':;

SECTION_NUMBER 1
 '@S9S_MB_2U_LIB.S9S_MB_2U(SCH_1):PAGE91_I179@PURE_QUANTA.Q_RES(CHIPS)':
 C_PATH='@s9s_mb_2u_lib.s9s_mb_2u(sch_1):page91_i179@pure_quanta.q_res(chips)',
 P_PATH='@s9s_mb_2u_lib.s9s_mb_2u(sch_1):page91_i179@pure_quanta.q_res(chips)',
 PATH='I179',
 DRAWING='@S9S_MB_2U_LIB.S9S_MB_2U(SCH_1):PAGE91',
 PHYS_PAGE='91',
 XY='(-2825,1400)',
 ROT='0',
 VER='1',
 PACK_TYPE='0402LF',
 CDS_LIB='pure_quanta',
 CDS_PART_NAME='Q_RES_0402LF-49.9,1%,1/16W,CHIA',
 WATTAGE='1/16W',
 TOLERANCE='1%',
 MATERIAL='CHIP',
 VALUE='49.9',
 PRIM_FILE='./archive_libs/logical/q_res/chips/chips.prt';

PART_NAME
 R3885 'Q_RES_0402LF-49.9,1%,1/16W,CHIA':;

SECTION_NUMBER 1
 '@S9S_MB_2U_LIB.S9S_MB_2U(SCH_1):PAGE92_I179@PURE_QUANTA.Q_RES(CHIPS)':
 C_PATH='@s9s_mb_2u_lib.s9s_mb_2u(sch_1):page92_i179@pure_quanta.q_res(chips)',
 P_PATH='@s9s_mb_2u_lib.s9s_mb_2u(sch_1):page92_i179@pure_quanta.q_res(chips)',
 PATH='I179',
 DRAWING='@S9S_MB_2U_LIB.S9S_MB_2U(SCH_1):PAGE92',
 PHYS_PAGE='92',
 XY='(-3725,1700)',
 ROT='0',
 VER='1',
 PACK_TYPE='0402LF',
 CDS_LIB='pure_quanta',
 CDS_PART_NAME='Q_RES_0402LF-49.9,1%,1/16W,CHIA',
 WATTAGE='1/16W',
 TOLERANCE='1%',
 MATERIAL='CHIP',
 VALUE='49.9',
 PRIM_FILE='./archive_libs/logical/q_res/chips/chips.prt';

PART_NAME
 R3886 'Q_RES_0402LF-49.9,1%,1/16W,CHIA':;

SECTION_NUMBER 1
 '@S9S_MB_2U_LIB.S9S_MB_2U(SCH_1):PAGE93_I179@PURE_QUANTA.Q_RES(CHIPS)':
 C_PATH='@s9s_mb_2u_lib.s9s_mb_2u(sch_1):page93_i179@pure_quanta.q_res(chips)',
 P_PATH='@s9s_mb_2u_lib.s9s_mb_2u(sch_1):page93_i179@pure_quanta.q_res(chips)',
 PATH='I179',
 DRAWING='@S9S_MB_2U_LIB.S9S_MB_2U(SCH_1):PAGE93',
 PHYS_PAGE='93',
 XY='(-3050,1725)',
 ROT='0',
 VER='1',
 PACK_TYPE='0402LF',
 CDS_LIB='pure_quanta',
 CDS_PART_NAME='Q_RES_0402LF-49.9,1%,1/16W,CHIA',
 WATTAGE='1/16W',
 TOLERANCE='1%',
 MATERIAL='CHIP',
 VALUE='49.9',
 PRIM_FILE='./archive_libs/logical/q_res/chips/chips.prt';

PART_NAME
 R3887 'Q_RES_0402LF-49.9,1%,1/16W,CHIA':;

SECTION_NUMBER 1
 '@S9S_MB_2U_LIB.S9S_MB_2U(SCH_1):PAGE94_I179@PURE_QUANTA.Q_RES(CHIPS)':
 C_PATH='@s9s_mb_2u_lib.s9s_mb_2u(sch_1):page94_i179@pure_quanta.q_res(chips)',
 P_PATH='@s9s_mb_2u_lib.s9s_mb_2u(sch_1):page94_i179@pure_quanta.q_res(chips)',
 PATH='I179',
 DRAWING='@S9S_MB_2U_LIB.S9S_MB_2U(SCH_1):PAGE94',
 PHYS_PAGE='94',
 XY='(-3150,1650)',
 ROT='0',
 VER='1',
 PACK_TYPE='0402LF',
 CDS_LIB='pure_quanta',
 CDS_PART_NAME='Q_RES_0402LF-49.9,1%,1/16W,CHIA',
 WATTAGE='1/16W',
 TOLERANCE='1%',
 MATERIAL='CHIP',
 VALUE='49.9',
 PRIM_FILE='./archive_libs/logical/q_res/chips/chips.prt';

PART_NAME
 R3888 'Q_RES_0402LF-49.9,1%,1/16W,CHIA':;

SECTION_NUMBER 1
 '@S9S_MB_2U_LIB.S9S_MB_2U(SCH_1):PAGE95_I179@PURE_QUANTA.Q_RES(CHIPS)':
 C_PATH='@s9s_mb_2u_lib.s9s_mb_2u(sch_1):page95_i179@pure_quanta.q_res(chips)',
 P_PATH='@s9s_mb_2u_lib.s9s_mb_2u(sch_1):page95_i179@pure_quanta.q_res(chips)',
 PATH='I179',
 DRAWING='@S9S_MB_2U_LIB.S9S_MB_2U(SCH_1):PAGE95',
 PHYS_PAGE='95',
 XY='(-2025,625)',
 ROT='0',
 VER='1',
 PACK_TYPE='0402LF',
 CDS_LIB='pure_quanta',
 CDS_PART_NAME='Q_RES_0402LF-49.9,1%,1/16W,CHIA',
 WATTAGE='1/16W',
 TOLERANCE='1%',
 MATERIAL='CHIP',
 VALUE='49.9',
 PRIM_FILE='./archive_libs/logical/q_res/chips/chips.prt';

PART_NAME
 R3889 'Q_RES_0402LF-49.9,1%,1/16W,CHIA':;

SECTION_NUMBER 1
 '@S9S_MB_2U_LIB.S9S_MB_2U(SCH_1):PAGE96_I179@PURE_QUANTA.Q_RES(CHIPS)':
 C_PATH='@s9s_mb_2u_lib.s9s_mb_2u(sch_1):page96_i179@pure_quanta.q_res(chips)',
 P_PATH='@s9s_mb_2u_lib.s9s_mb_2u(sch_1):page96_i179@pure_quanta.q_res(chips)',
 PATH='I179',
 DRAWING='@S9S_MB_2U_LIB.S9S_MB_2U(SCH_1):PAGE96',
 PHYS_PAGE='96',
 XY='(-3450,1250)',
 ROT='0',
 VER='1',
 PACK_TYPE='0402LF',
 CDS_LIB='pure_quanta',
 CDS_PART_NAME='Q_RES_0402LF-49.9,1%,1/16W,CHIA',
 WATTAGE='1/16W',
 TOLERANCE='1%',
 MATERIAL='CHIP',
 VALUE='49.9',
 PRIM_FILE='./archive_libs/logical/q_res/chips/chips.prt';

PART_NAME
 R3890 'Q_RES_0402LF-49.9,1%,1/16W,CHIA':;

SECTION_NUMBER 1
 '@S9S_MB_2U_LIB.S9S_MB_2U(SCH_1):PAGE97_I179@PURE_QUANTA.Q_RES(CHIPS)':
 C_PATH='@s9s_mb_2u_lib.s9s_mb_2u(sch_1):page97_i179@pure_quanta.q_res(chips)',
 P_PATH='@s9s_mb_2u_lib.s9s_mb_2u(sch_1):page97_i179@pure_quanta.q_res(chips)',
 PATH='I179',
 DRAWING='@S9S_MB_2U_LIB.S9S_MB_2U(SCH_1):PAGE97',
 PHYS_PAGE='97',
 XY='(-2975,1450)',
 ROT='0',
 VER='1',
 PACK_TYPE='0402LF',
 CDS_LIB='pure_quanta',
 CDS_PART_NAME='Q_RES_0402LF-49.9,1%,1/16W,CHIA',
 WATTAGE='1/16W',
 TOLERANCE='1%',
 MATERIAL='CHIP',
 VALUE='49.9',
 PRIM_FILE='./archive_libs/logical/q_res/chips/chips.prt';

PART_NAME
 R3891 'Q_RES_0402LF-49.9,1%,1/16W,CHIA':;

SECTION_NUMBER 1
 '@S9S_MB_2U_LIB.S9S_MB_2U(SCH_1):PAGE98_I179@PURE_QUANTA.Q_RES(CHIPS)':
 C_PATH='@s9s_mb_2u_lib.s9s_mb_2u(sch_1):page98_i179@pure_quanta.q_res(chips)',
 P_PATH='@s9s_mb_2u_lib.s9s_mb_2u(sch_1):page98_i179@pure_quanta.q_res(chips)',
 PATH='I179',
 DRAWING='@S9S_MB_2U_LIB.S9S_MB_2U(SCH_1):PAGE98',
 PHYS_PAGE='98',
 XY='(-2625,1350)',
 ROT='0',
 VER='1',
 PACK_TYPE='0402LF',
 CDS_LIB='pure_quanta',
 CDS_PART_NAME='Q_RES_0402LF-49.9,1%,1/16W,CHIA',
 WATTAGE='1/16W',
 TOLERANCE='1%',
 MATERIAL='CHIP',
 VALUE='49.9',
 PRIM_FILE='./archive_libs/logical/q_res/chips/chips.prt';

PART_NAME
 R3892 'Q_RES_0402LF-49.9,1%,1/16W,CHIA':;

SECTION_NUMBER 1
 '@S9S_MB_2U_LIB.S9S_MB_2U(SCH_1):PAGE99_I180@PURE_QUANTA.Q_RES(CHIPS)':
 C_PATH='@s9s_mb_2u_lib.s9s_mb_2u(sch_1):page99_i180@pure_quanta.q_res(chips)',
 P_PATH='@s9s_mb_2u_lib.s9s_mb_2u(sch_1):page99_i180@pure_quanta.q_res(chips)',
 PATH='I180',
 DRAWING='@S9S_MB_2U_LIB.S9S_MB_2U(SCH_1):PAGE99',
 PHYS_PAGE='99',
 XY='(-2850,1075)',
 ROT='0',
 VER='1',
 PACK_TYPE='0402LF',
 CDS_LIB='pure_quanta',
 CDS_PART_NAME='Q_RES_0402LF-49.9,1%,1/16W,CHIA',
 WATTAGE='1/16W',
 TOLERANCE='1%',
 MATERIAL='CHIP',
 VALUE='49.9',
 PRIM_FILE='./archive_libs/logical/q_res/chips/chips.prt';

PART_NAME
 R3893 'Q_RES_0402LF-49.9,1%,1/16W,CHIA':;

SECTION_NUMBER 1
 '@S9S_MB_2U_LIB.S9S_MB_2U(SCH_1):PAGE100_I180@PURE_QUANTA.Q_RES(CHIPS)':
 C_PATH='@s9s_mb_2u_lib.s9s_mb_2u(sch_1):page100_i180@pure_quanta.q_res(chips)',
 P_PATH='@s9s_mb_2u_lib.s9s_mb_2u(sch_1):page100_i180@pure_quanta.q_res(chips)',
 PATH='I180',
 DRAWING='@S9S_MB_2U_LIB.S9S_MB_2U(SCH_1):PAGE100',
 PHYS_PAGE='100',
 XY='(-3175,1675)',
 ROT='0',
 VER='1',
 PACK_TYPE='0402LF',
 CDS_LIB='pure_quanta',
 CDS_PART_NAME='Q_RES_0402LF-49.9,1%,1/16W,CHIA',
 WATTAGE='1/16W',
 TOLERANCE='1%',
 MATERIAL='CHIP',
 VALUE='49.9',
 PRIM_FILE='./archive_libs/logical/q_res/chips/chips.prt';

PART_NAME
 R3894 'Q_RES_0402LF-49.9,1%,1/16W,CHIA':;

SECTION_NUMBER 1
 '@S9S_MB_2U_LIB.S9S_MB_2U(SCH_1):PAGE101_I180@PURE_QUANTA.Q_RES(CHIPS)':
 C_PATH='@s9s_mb_2u_lib.s9s_mb_2u(sch_1):page101_i180@pure_quanta.q_res(chips)',
 P_PATH='@s9s_mb_2u_lib.s9s_mb_2u(sch_1):page101_i180@pure_quanta.q_res(chips)',
 PATH='I180',
 DRAWING='@S9S_MB_2U_LIB.S9S_MB_2U(SCH_1):PAGE101',
 PHYS_PAGE='101',
 XY='(-5275,1950)',
 ROT='0',
 VER='1',
 PACK_TYPE='0402LF',
 CDS_LIB='pure_quanta',
 CDS_PART_NAME='Q_RES_0402LF-49.9,1%,1/16W,CHIA',
 WATTAGE='1/16W',
 TOLERANCE='1%',
 MATERIAL='CHIP',
 VALUE='49.9',
 PRIM_FILE='./archive_libs/logical/q_res/chips/chips.prt';

PART_NAME
 R3895 'Q_RES_0402LF-49.9,1%,1/16W,CHIA':;

SECTION_NUMBER 1
 '@S9S_MB_2U_LIB.S9S_MB_2U(SCH_1):PAGE102_I180@PURE_QUANTA.Q_RES(CHIPS)':
 C_PATH='@s9s_mb_2u_lib.s9s_mb_2u(sch_1):page102_i180@pure_quanta.q_res(chips)',
 P_PATH='@s9s_mb_2u_lib.s9s_mb_2u(sch_1):page102_i180@pure_quanta.q_res(chips)',
 PATH='I180',
 DRAWING='@S9S_MB_2U_LIB.S9S_MB_2U(SCH_1):PAGE102',
 PHYS_PAGE='102',
 XY='(-3825,1450)',
 ROT='0',
 VER='1',
 PACK_TYPE='0402LF',
 CDS_LIB='pure_quanta',
 CDS_PART_NAME='Q_RES_0402LF-49.9,1%,1/16W,CHIA',
 WATTAGE='1/16W',
 TOLERANCE='1%',
 MATERIAL='CHIP',
 VALUE='49.9',
 PRIM_FILE='./archive_libs/logical/q_res/chips/chips.prt';

PART_NAME
 R3896 'Q_RES_0402LF-49.9,1%,1/16W,CHIA':;

SECTION_NUMBER 1
 '@S9S_MB_2U_LIB.S9S_MB_2U(SCH_1):PAGE103_I180@PURE_QUANTA.Q_RES(CHIPS)':
 C_PATH='@s9s_mb_2u_lib.s9s_mb_2u(sch_1):page103_i180@pure_quanta.q_res(chips)',
 P_PATH='@s9s_mb_2u_lib.s9s_mb_2u(sch_1):page103_i180@pure_quanta.q_res(chips)',
 PATH='I180',
 DRAWING='@S9S_MB_2U_LIB.S9S_MB_2U(SCH_1):PAGE103',
 PHYS_PAGE='103',
 XY='(-3850,1200)',
 ROT='0',
 VER='1',
 PACK_TYPE='0402LF',
 CDS_LIB='pure_quanta',
 CDS_PART_NAME='Q_RES_0402LF-49.9,1%,1/16W,CHIA',
 WATTAGE='1/16W',
 TOLERANCE='1%',
 MATERIAL='CHIP',
 VALUE='49.9',
 PRIM_FILE='./archive_libs/logical/q_res/chips/chips.prt';

PART_NAME
 R3897 'Q_RES_0402LF-49.9,1%,1/16W,CHIA':;

SECTION_NUMBER 1
 '@S9S_MB_2U_LIB.S9S_MB_2U(SCH_1):PAGE104_I180@PURE_QUANTA.Q_RES(CHIPS)':
 C_PATH='@s9s_mb_2u_lib.s9s_mb_2u(sch_1):page104_i180@pure_quanta.q_res(chips)',
 P_PATH='@s9s_mb_2u_lib.s9s_mb_2u(sch_1):page104_i180@pure_quanta.q_res(chips)',
 PATH='I180',
 DRAWING='@S9S_MB_2U_LIB.S9S_MB_2U(SCH_1):PAGE104',
 PHYS_PAGE='104',
 XY='(-4300,1425)',
 ROT='0',
 VER='1',
 PACK_TYPE='0402LF',
 CDS_LIB='pure_quanta',
 CDS_PART_NAME='Q_RES_0402LF-49.9,1%,1/16W,CHIA',
 WATTAGE='1/16W',
 TOLERANCE='1%',
 MATERIAL='CHIP',
 VALUE='49.9',
 PRIM_FILE='./archive_libs/logical/q_res/chips/chips.prt';

PART_NAME
 R3898 'Q_RES_0402LF-49.9,1%,1/16W,CHIA':;

SECTION_NUMBER 1
 '@S9S_MB_2U_LIB.S9S_MB_2U(SCH_1):PAGE105_I183@PURE_QUANTA.Q_RES(CHIPS)':
 C_PATH='@s9s_mb_2u_lib.s9s_mb_2u(sch_1):page105_i183@pure_quanta.q_res(chips)',
 P_PATH='@s9s_mb_2u_lib.s9s_mb_2u(sch_1):page105_i183@pure_quanta.q_res(chips)',
 PATH='I183',
 DRAWING='@S9S_MB_2U_LIB.S9S_MB_2U(SCH_1):PAGE105',
 PHYS_PAGE='105',
 XY='(-3850,1575)',
 ROT='0',
 VER='1',
 PACK_TYPE='0402LF',
 CDS_LIB='pure_quanta',
 CDS_PART_NAME='Q_RES_0402LF-49.9,1%,1/16W,CHIA',
 WATTAGE='1/16W',
 TOLERANCE='1%',
 MATERIAL='CHIP',
 VALUE='49.9',
 PRIM_FILE='./archive_libs/logical/q_res/chips/chips.prt';

PART_NAME
 R3899 'Q_RES_0402LF-49.9,1%,1/16W,CHIA':;

SECTION_NUMBER 1
 '@S9S_MB_2U_LIB.S9S_MB_2U(SCH_1):PAGE106_I183@PURE_QUANTA.Q_RES(CHIPS)':
 C_PATH='@s9s_mb_2u_lib.s9s_mb_2u(sch_1):page106_i183@pure_quanta.q_res(chips)',
 P_PATH='@s9s_mb_2u_lib.s9s_mb_2u(sch_1):page106_i183@pure_quanta.q_res(chips)',
 PATH='I183',
 DRAWING='@S9S_MB_2U_LIB.S9S_MB_2U(SCH_1):PAGE106',
 PHYS_PAGE='106',
 XY='(-3725,1275)',
 ROT='0',
 VER='1',
 PACK_TYPE='0402LF',
 CDS_LIB='pure_quanta',
 CDS_PART_NAME='Q_RES_0402LF-49.9,1%,1/16W,CHIA',
 WATTAGE='1/16W',
 TOLERANCE='1%',
 MATERIAL='CHIP',
 VALUE='49.9',
 PRIM_FILE='./archive_libs/logical/q_res/chips/chips.prt';

PART_NAME
 R3900 'Q_RES_0402LF-49.9,1%,1/16W,CHIA':;

SECTION_NUMBER 1
 '@S9S_MB_2U_LIB.S9S_MB_2U(SCH_1):PAGE107_I183@PURE_QUANTA.Q_RES(CHIPS)':
 C_PATH='@s9s_mb_2u_lib.s9s_mb_2u(sch_1):page107_i183@pure_quanta.q_res(chips)',
 P_PATH='@s9s_mb_2u_lib.s9s_mb_2u(sch_1):page107_i183@pure_quanta.q_res(chips)',
 PATH='I183',
 DRAWING='@S9S_MB_2U_LIB.S9S_MB_2U(SCH_1):PAGE107',
 PHYS_PAGE='107',
 XY='(-3500,1675)',
 ROT='0',
 VER='1',
 PACK_TYPE='0402LF',
 CDS_LIB='pure_quanta',
 CDS_PART_NAME='Q_RES_0402LF-49.9,1%,1/16W,CHIA',
 WATTAGE='1/16W',
 TOLERANCE='1%',
 MATERIAL='CHIP',
 VALUE='49.9',
 PRIM_FILE='./archive_libs/logical/q_res/chips/chips.prt';

PART_NAME
 R3901 'Q_RES_0402LF-49.9,1%,1/16W,CHIA':;

SECTION_NUMBER 1
 '@S9S_MB_2U_LIB.S9S_MB_2U(SCH_1):PAGE108_I182@PURE_QUANTA.Q_RES(CHIPS)':
 C_PATH='@s9s_mb_2u_lib.s9s_mb_2u(sch_1):page108_i182@pure_quanta.q_res(chips)',
 P_PATH='@s9s_mb_2u_lib.s9s_mb_2u(sch_1):page108_i182@pure_quanta.q_res(chips)',
 PATH='I182',
 DRAWING='@S9S_MB_2U_LIB.S9S_MB_2U(SCH_1):PAGE108',
 PHYS_PAGE='108',
 XY='(-3700,2675)',
 ROT='0',
 VER='1',
 PACK_TYPE='0402LF',
 CDS_LIB='pure_quanta',
 CDS_PART_NAME='Q_RES_0402LF-49.9,1%,1/16W,CHIA',
 WATTAGE='1/16W',
 TOLERANCE='1%',
 MATERIAL='CHIP',
 VALUE='49.9',
 PRIM_FILE='./archive_libs/logical/q_res/chips/chips.prt';

PART_NAME
 R3902 'Q_RES_0402LF-49.9,1%,1/16W,CHIA':;

SECTION_NUMBER 1
 '@S9S_MB_2U_LIB.S9S_MB_2U(SCH_1):PAGE109_I180@PURE_QUANTA.Q_RES(CHIPS)':
 C_PATH='@s9s_mb_2u_lib.s9s_mb_2u(sch_1):page109_i180@pure_quanta.q_res(chips)',
 P_PATH='@s9s_mb_2u_lib.s9s_mb_2u(sch_1):page109_i180@pure_quanta.q_res(chips)',
 PATH='I180',
 DRAWING='@S9S_MB_2U_LIB.S9S_MB_2U(SCH_1):PAGE109',
 PHYS_PAGE='109',
 XY='(-3475,1500)',
 ROT='0',
 VER='1',
 PACK_TYPE='0402LF',
 CDS_LIB='pure_quanta',
 CDS_PART_NAME='Q_RES_0402LF-49.9,1%,1/16W,CHIA',
 WATTAGE='1/16W',
 TOLERANCE='1%',
 MATERIAL='CHIP',
 VALUE='49.9',
 PRIM_FILE='./archive_libs/logical/q_res/chips/chips.prt';

PART_NAME
 R3903 'Q_RES_0402LF-49.9,1%,1/16W,CHIA':;

SECTION_NUMBER 1
 '@S9S_MB_2U_LIB.S9S_MB_2U(SCH_1):PAGE110_I182@PURE_QUANTA.Q_RES(CHIPS)':
 C_PATH='@s9s_mb_2u_lib.s9s_mb_2u(sch_1):page110_i182@pure_quanta.q_res(chips)',
 P_PATH='@s9s_mb_2u_lib.s9s_mb_2u(sch_1):page110_i182@pure_quanta.q_res(chips)',
 PATH='I182',
 DRAWING='@S9S_MB_2U_LIB.S9S_MB_2U(SCH_1):PAGE110',
 PHYS_PAGE='110',
 XY='(-3575,1250)',
 ROT='0',
 VER='1',
 PACK_TYPE='0402LF',
 CDS_LIB='pure_quanta',
 CDS_PART_NAME='Q_RES_0402LF-49.9,1%,1/16W,CHIA',
 WATTAGE='1/16W',
 TOLERANCE='1%',
 MATERIAL='CHIP',
 VALUE='49.9',
 PRIM_FILE='./archive_libs/logical/q_res/chips/chips.prt';

PART_NAME
 R3904 'Q_RES_0402LF-49.9,1%,1/16W,CHIA':;

SECTION_NUMBER 1
 '@S9S_MB_2U_LIB.S9S_MB_2U(SCH_1):PAGE111_I182@PURE_QUANTA.Q_RES(CHIPS)':
 C_PATH='@s9s_mb_2u_lib.s9s_mb_2u(sch_1):page111_i182@pure_quanta.q_res(chips)',
 P_PATH='@s9s_mb_2u_lib.s9s_mb_2u(sch_1):page111_i182@pure_quanta.q_res(chips)',
 PATH='I182',
 DRAWING='@S9S_MB_2U_LIB.S9S_MB_2U(SCH_1):PAGE111',
 PHYS_PAGE='111',
 XY='(-4150,1675)',
 ROT='0',
 VER='1',
 PACK_TYPE='0402LF',
 CDS_LIB='pure_quanta',
 CDS_PART_NAME='Q_RES_0402LF-49.9,1%,1/16W,CHIA',
 WATTAGE='1/16W',
 TOLERANCE='1%',
 MATERIAL='CHIP',
 VALUE='49.9',
 PRIM_FILE='./archive_libs/logical/q_res/chips/chips.prt';

PART_NAME
 R3905 'Q_RES_0402LF-49.9,1%,1/16W,CHIA':;

SECTION_NUMBER 1
 '@S9S_MB_2U_LIB.S9S_MB_2U(SCH_1):PAGE112_I183@PURE_QUANTA.Q_RES(CHIPS)':
 C_PATH='@s9s_mb_2u_lib.s9s_mb_2u(sch_1):page112_i183@pure_quanta.q_res(chips)',
 P_PATH='@s9s_mb_2u_lib.s9s_mb_2u(sch_1):page112_i183@pure_quanta.q_res(chips)',
 PATH='I183',
 DRAWING='@S9S_MB_2U_LIB.S9S_MB_2U(SCH_1):PAGE112',
 PHYS_PAGE='112',
 XY='(-4200,1600)',
 ROT='0',
 VER='1',
 PACK_TYPE='0402LF',
 CDS_LIB='pure_quanta',
 CDS_PART_NAME='Q_RES_0402LF-49.9,1%,1/16W,CHIA',
 WATTAGE='1/16W',
 TOLERANCE='1%',
 MATERIAL='CHIP',
 VALUE='49.9',
 PRIM_FILE='./archive_libs/logical/q_res/chips/chips.prt';

PART_NAME
 R3906 'Q_RES_0402LF-49.9,1%,1/16W,CHIA':;

SECTION_NUMBER 1
 '@S9S_MB_2U_LIB.S9S_MB_2U(SCH_1):PAGE113_I182@PURE_QUANTA.Q_RES(CHIPS)':
 C_PATH='@s9s_mb_2u_lib.s9s_mb_2u(sch_1):page113_i182@pure_quanta.q_res(chips)',
 P_PATH='@s9s_mb_2u_lib.s9s_mb_2u(sch_1):page113_i182@pure_quanta.q_res(chips)',
 PATH='I182',
 DRAWING='@S9S_MB_2U_LIB.S9S_MB_2U(SCH_1):PAGE113',
 PHYS_PAGE='113',
 XY='(-4900,1750)',
 ROT='0',
 VER='1',
 PACK_TYPE='0402LF',
 CDS_LIB='pure_quanta',
 CDS_PART_NAME='Q_RES_0402LF-49.9,1%,1/16W,CHIA',
 WATTAGE='1/16W',
 TOLERANCE='1%',
 MATERIAL='CHIP',
 VALUE='49.9',
 PRIM_FILE='./archive_libs/logical/q_res/chips/chips.prt';

PART_NAME
 R3907 'Q_RES_0402LF-33K,1%,1/16W,CHIPA':;

SECTION_NUMBER 1
 '@S9S_MB_2U_LIB.S9S_MB_2U(SCH_1):PAGE303_I4@PURE_QUANTA.Q_RES(CHIPS)':
 C_PATH='@s9s_mb_2u_lib.s9s_mb_2u(sch_1):page303_i4@pure_quanta.q_res(chips)',
 P_PATH='@s9s_mb_2u_lib.s9s_mb_2u(sch_1):page301_i4@pure_quanta.q_res(chips)',
 PATH='I4',
 DRAWING='@S9S_MB_2U_LIB.S9S_MB_2U(SCH_1):PAGE303',
 PHYS_PAGE='301',
 XY='(-16525,450)',
 ROT='0',
 VER='2',
 PACK_TYPE='0402LF',
 LOCATION='R3907',
 CDS_LIB='pure_quanta',
 CDS_PART_NAME='Q_RES_0402LF-33K,1%,1/16W,CHIPA',
 WATTAGE='1/16W',
 TOLERANCE='1%',
 MATERIAL='CHIP',
 VALUE='33K',
 PRIM_FILE='./archive_libs/logical/q_res/chips/chips.prt';

PART_NAME
 R3909 'Q_RES_0402LF-33.2,1%,1/16W,CHIA':
 ROOM='HSC1_BOM1';

SECTION_NUMBER 1
 '@S9S_MB_2U_LIB.S9S_MB_2U(SCH_1):PAGE303_I38@PURE_QUANTA.Q_RES(CHIPS)':
 C_PATH='@s9s_mb_2u_lib.s9s_mb_2u(sch_1):page303_i38@pure_quanta.q_res(chips)',
 P_PATH='@s9s_mb_2u_lib.s9s_mb_2u(sch_1):page301_i38@pure_quanta.q_res(chips)',
 PATH='I38',
 DRAWING='@S9S_MB_2U_LIB.S9S_MB_2U(SCH_1):PAGE303',
 PHYS_PAGE='301',
 XY='(-15400,3875)',
 ROT='0',
 VER='1',
 PACK_TYPE='0402LF',
 LOCATION='R3909',
 CDS_LIB='pure_quanta',
 CDS_PART_NAME='Q_RES_0402LF-33.2,1%,1/16W,CHIA',
 WATTAGE='1/16W',
 TOLERANCE='1%',
 MATERIAL='CHIP',
 ROOM='HSC1_BOM1',
 VALUE='33.2',
 PRIM_FILE='./archive_libs/logical/q_res/chips/chips.prt';

PART_NAME
 R3923 'Q_RES_0402LF-63.4K,1%,1/16W,CHA':;

SECTION_NUMBER 1
 '@S9S_MB_2U_LIB.S9S_MB_2U(SCH_1):PAGE303_I10@PURE_QUANTA.Q_RES(CHIPS)':
 C_PATH='@s9s_mb_2u_lib.s9s_mb_2u(sch_1):page303_i10@pure_quanta.q_res(chips)',
 P_PATH='@s9s_mb_2u_lib.s9s_mb_2u(sch_1):page301_i10@pure_quanta.q_res(chips)',
 PATH='I10',
 DRAWING='@S9S_MB_2U_LIB.S9S_MB_2U(SCH_1):PAGE303',
 PHYS_PAGE='301',
 XY='(-16575,950)',
 ROT='0',
 VER='2',
 PACK_TYPE='0402LF',
 LOCATION='R3923',
 CDS_LIB='pure_quanta',
 CDS_PART_NAME='Q_RES_0402LF-63.4K,1%,1/16W,CHA',
 WATTAGE='1/16W',
 TOLERANCE='1%',
 MATERIAL='CHIP',
 VALUE='63.4K',
 PRIM_FILE='./archive_libs/logical/q_res/chips/chips.prt';

PART_NAME
 R3924 'Q_RES_0402LF-0,5%,1/16W,CHIP,CA':;

SECTION_NUMBER 1
 '@S9S_MB_2U_LIB.S9S_MB_2U(SCH_1):PAGE303_I17@PURE_QUANTA.Q_RES(CHIPS)':
 C_PATH='@s9s_mb_2u_lib.s9s_mb_2u(sch_1):page303_i17@pure_quanta.q_res(chips)',
 P_PATH='@s9s_mb_2u_lib.s9s_mb_2u(sch_1):page301_i17@pure_quanta.q_res(chips)',
 PATH='I17',
 DRAWING='@S9S_MB_2U_LIB.S9S_MB_2U(SCH_1):PAGE303',
 PHYS_PAGE='301',
 XY='(-16350,3200)',
 ROT='0',
 VER='1',
 PACK_TYPE='0402LF',
 CDS_LIB='pure_quanta',
 CDS_PART_NAME='Q_RES_0402LF-0,5%,1/16W,CHIP,CA',
 WATTAGE='1/16W',
 TOLERANCE='5%',
 MATERIAL='CHIP',
 VALUE='0',
 PRIM_FILE='./archive_libs/logical/q_res/chips/chips.prt';

PART_NAME
 R3925 'Q_RES_0402LF-1K,1%,1/16W,CHIP,A':;

SECTION_NUMBER 1
 '@S9S_MB_2U_LIB.S9S_MB_2U(SCH_1):PAGE303_I33@PURE_QUANTA.Q_RES(CHIPS)':
 C_PATH='@s9s_mb_2u_lib.s9s_mb_2u(sch_1):page303_i33@pure_quanta.q_res(chips)',
 P_PATH='@s9s_mb_2u_lib.s9s_mb_2u(sch_1):page301_i33@pure_quanta.q_res(chips)',
 PATH='I33',
 DRAWING='@S9S_MB_2U_LIB.S9S_MB_2U(SCH_1):PAGE303',
 PHYS_PAGE='301',
 XY='(-15950,3375)',
 ROT='1',
 VER='1',
 PACK_TYPE='0402LF',
 CDS_LIB='pure_quanta',
 CDS_PART_NAME='Q_RES_0402LF-1K,1%,1/16W,CHIP,A',
 WATTAGE='1/16W',
 TOLERANCE='1%',
 MATERIAL='CHIP',
 VALUE='1K',
 PRIM_FILE='./archive_libs/logical/q_res/chips/chips.prt';

PART_NAME
 R3933 'Q_RES_0402LF-16.9K,1%,1/16W,CHA':
 ROOM='HSC1_BOM1';

SECTION_NUMBER 1
 '@S9S_MB_2U_LIB.S9S_MB_2U(SCH_1):PAGE303_I62@PURE_QUANTA.Q_RES(CHIPS)':
 C_PATH='@s9s_mb_2u_lib.s9s_mb_2u(sch_1):page303_i62@pure_quanta.q_res(chips)',
 P_PATH='@s9s_mb_2u_lib.s9s_mb_2u(sch_1):page301_i62@pure_quanta.q_res(chips)',
 PATH='I62',
 DRAWING='@S9S_MB_2U_LIB.S9S_MB_2U(SCH_1):PAGE303',
 PHYS_PAGE='301',
 XY='(-11700,2600)',
 ROT='0',
 VER='2',
 PACK_TYPE='0402LF',
 LOCATION='R3933',
 CDS_LIB='pure_quanta',
 CDS_PART_NAME='Q_RES_0402LF-16.9K,1%,1/16W,CHA',
 WATTAGE='1/16W',
 TOLERANCE='1%',
 MATERIAL='CHIP',
 ROOM='HSC1_BOM1',
 VALUE='16.9K',
 PRIM_FILE='./archive_libs/logical/q_res/chips/chips.prt';

PART_NAME
 R3934 'Q_RES_0402LF-22,1%,1/16W,CHIP,A':
 ROOM='HSC1_BOM1';

SECTION_NUMBER 1
 '@S9S_MB_2U_LIB.S9S_MB_2U(SCH_1):PAGE303_I82@PURE_QUANTA.Q_RES(CHIPS)':
 C_PATH='@s9s_mb_2u_lib.s9s_mb_2u(sch_1):page303_i82@pure_quanta.q_res(chips)',
 P_PATH='@s9s_mb_2u_lib.s9s_mb_2u(sch_1):page301_i82@pure_quanta.q_res(chips)',
 PATH='I82',
 DRAWING='@S9S_MB_2U_LIB.S9S_MB_2U(SCH_1):PAGE303',
 PHYS_PAGE='301',
 XY='(-10675,4100)',
 ROT='0',
 VER='1',
 PACK_TYPE='0402LF',
 LOCATION='R3934',
 CDS_LIB='pure_quanta',
 CDS_PART_NAME='Q_RES_0402LF-22,1%,1/16W,CHIP,A',
 WATTAGE='1/16W',
 TOLERANCE='1%',
 MATERIAL='CHIP',
 ROOM='HSC1_BOM1',
 VALUE='22',
 PRIM_FILE='./archive_libs/logical/q_res/chips/chips.prt';

PART_NAME
 R3936 'Q_RES_0402LF-4.7K,1%,1/16W,CHIA':
 ROOM='HSC1_BOM1';

SECTION_NUMBER 1
 '@S9S_MB_2U_LIB.S9S_MB_2U(SCH_1):PAGE303_I85@PURE_QUANTA.Q_RES(CHIPS)':
 C_PATH='@s9s_mb_2u_lib.s9s_mb_2u(sch_1):page303_i85@pure_quanta.q_res(chips)',
 P_PATH='@s9s_mb_2u_lib.s9s_mb_2u(sch_1):page301_i85@pure_quanta.q_res(chips)',
 PATH='I85',
 DRAWING='@S9S_MB_2U_LIB.S9S_MB_2U(SCH_1):PAGE303',
 PHYS_PAGE='301',
 XY='(-10150,4600)',
 ROT='0',
 VER='2',
 PACK_TYPE='0402LF',
 LOCATION='R3936',
 CDS_LIB='pure_quanta',
 CDS_PART_NAME='Q_RES_0402LF-4.7K,1%,1/16W,CHIA',
 WATTAGE='1/16W',
 TOLERANCE='1%',
 MATERIAL='CHIP',
 ROOM='HSC1_BOM1',
 VALUE='4.7K',
 PRIM_FILE='./archive_libs/logical/q_res/chips/chips.prt';

PART_NAME
 R3938 'Q_RES_0402LF-10K,1%,1/16W,CHIPA':;

SECTION_NUMBER 1
 '@S9S_MB_2U_LIB.S9S_MB_2U(SCH_1):PAGE175_I272@PURE_QUANTA.Q_RES(CHIPS)':
 C_PATH='@s9s_mb_2u_lib.s9s_mb_2u(sch_1):page175_i272@pure_quanta.q_res(chips)',
 P_PATH='@s9s_mb_2u_lib.s9s_mb_2u(sch_1):page183_i272@pure_quanta.q_res(chips)',
 PATH='I272',
 DRAWING='@S9S_MB_2U_LIB.S9S_MB_2U(SCH_1):PAGE175',
 PHYS_PAGE='183',
 XY='(3475,-225)',
 ROT='0',
 VER='1',
 PACK_TYPE='0402LF',
 CDS_LIB='pure_quanta',
 CDS_PART_NAME='Q_RES_0402LF-10K,1%,1/16W,CHIPA',
 WATTAGE='1/16W',
 TOLERANCE='1%',
 MATERIAL='CHIP',
 VALUE='10K',
 PRIM_FILE='./archive_libs/logical/q_res/chips/chips.prt';

PART_NAME
 R3939 'Q_RES_0402LF-0,5%,1/16W,EMPTY,A':
 ROOM='E1S1_P12V_MAM_MAM_BOM1';

SECTION_NUMBER 1
 '@S9S_MB_2U_LIB.S9S_MB_2U(SCH_1):PAGE239_I330@PURE_QUANTA.Q_RES(CHIPS)':
 C_PATH='@s9s_mb_2u_lib.s9s_mb_2u(sch_1):page239_i330@pure_quanta.q_res(chips)',
 P_PATH='@s9s_mb_2u_lib.s9s_mb_2u(sch_1):page250_i330@pure_quanta.q_res(chips)',
 PATH='I330',
 DRAWING='@S9S_MB_2U_LIB.S9S_MB_2U(SCH_1):PAGE239',
 PHYS_PAGE='250',
 XY='(2200,3225)',
 ROT='0',
 VER='1',
 PACK_TYPE='0402LF',
 CDS_LIB='pure_quanta',
 CDS_PART_NAME='Q_RES_0402LF-0,5%,1/16W,EMPTY,A',
 WATTAGE='1/16W',
 TOLERANCE='5%',
 MATERIAL='EMPTY',
 ROOM='E1S1_P12V_MAM_MAM_BOM1',
 VALUE='0',
 PRIM_FILE='./archive_libs/logical/q_res/chips/chips.prt';

PART_NAME
 R3940 'Q_RES_0402LF-0,5%,1/16W,EMPTY,A':
 ROOM='E1S1_P12V_MPS_MAM_BOM3';

SECTION_NUMBER 1
 '@S9S_MB_2U_LIB.S9S_MB_2U(SCH_1):PAGE239_I337@PURE_QUANTA.Q_RES(CHIPS)':
 C_PATH='@s9s_mb_2u_lib.s9s_mb_2u(sch_1):page239_i337@pure_quanta.q_res(chips)',
 P_PATH='@s9s_mb_2u_lib.s9s_mb_2u(sch_1):page250_i337@pure_quanta.q_res(chips)',
 PATH='I337',
 DRAWING='@S9S_MB_2U_LIB.S9S_MB_2U(SCH_1):PAGE239',
 PHYS_PAGE='250',
 XY='(2200,3075)',
 ROT='0',
 VER='1',
 PACK_TYPE='0402LF',
 CDS_LIB='pure_quanta',
 CDS_PART_NAME='Q_RES_0402LF-0,5%,1/16W,EMPTY,A',
 WATTAGE='1/16W',
 TOLERANCE='5%',
 MATERIAL='EMPTY',
 ROOM='E1S1_P12V_MPS_MAM_BOM3',
 VALUE='0',
 PRIM_FILE='./archive_libs/logical/q_res/chips/chips.prt';

PART_NAME
 R3941 'Q_RES_0402LF-0,5%,1/16W,EMPTY,A':;

SECTION_NUMBER 1
 '@S9S_MB_2U_LIB.S9S_MB_2U(SCH_1):PAGE239_I338@PURE_QUANTA.Q_RES(CHIPS)':
 C_PATH='@s9s_mb_2u_lib.s9s_mb_2u(sch_1):page239_i338@pure_quanta.q_res(chips)',
 P_PATH='@s9s_mb_2u_lib.s9s_mb_2u(sch_1):page250_i338@pure_quanta.q_res(chips)',
 PATH='I338',
 DRAWING='@S9S_MB_2U_LIB.S9S_MB_2U(SCH_1):PAGE239',
 ROOM1='E1S1_P12V_MAM_TIC_BOM2',
 PHYS_PAGE='250',
 XY='(2200,2725)',
 ROT='0',
 VER='1',
 PACK_TYPE='0402LF',
 CDS_LIB='pure_quanta',
 CDS_PART_NAME='Q_RES_0402LF-0,5%,1/16W,EMPTY,A',
 WATTAGE='1/16W',
 TOLERANCE='5%',
 MATERIAL='EMPTY',
 VALUE='0',
 PRIM_FILE='./archive_libs/logical/q_res/chips/chips.prt';

PART_NAME
 R3942 'Q_RES_0402LF-0,5%,1/16W,CHIP,CA':;

SECTION_NUMBER 1
 '@S9S_MB_2U_LIB.S9S_MB_2U(SCH_1):PAGE239_I339@PURE_QUANTA.Q_RES(CHIPS)':
 C_PATH='@s9s_mb_2u_lib.s9s_mb_2u(sch_1):page239_i339@pure_quanta.q_res(chips)',
 P_PATH='@s9s_mb_2u_lib.s9s_mb_2u(sch_1):page250_i339@pure_quanta.q_res(chips)',
 PATH='I339',
 DRAWING='@S9S_MB_2U_LIB.S9S_MB_2U(SCH_1):PAGE239',
 ROOM1='E1S1_P12V_MPS_TIC_BOM4',
 PHYS_PAGE='250',
 XY='(2200,2575)',
 ROT='0',
 VER='1',
 PACK_TYPE='0402LF',
 CDS_LIB='pure_quanta',
 CDS_PART_NAME='Q_RES_0402LF-0,5%,1/16W,CHIP,CA',
 WATTAGE='1/16W',
 TOLERANCE='5%',
 MATERIAL='CHIP',
 VALUE='0',
 PRIM_FILE='./archive_libs/logical/q_res/chips/chips.prt';

PART_NAME
 R3943 'Q_RES_0402LF-0,5%,1/16W,CHIP,CA':
 ROOM='E1S1_P12V_MPS_MAM_BOM3';

SECTION_NUMBER 1
 '@S9S_MB_2U_LIB.S9S_MB_2U(SCH_1):PAGE323_I45@PURE_QUANTA.Q_RES(CHIPS)':
 C_PATH='@s9s_mb_2u_lib.s9s_mb_2u(sch_1):page323_i45@pure_quanta.q_res(chips)',
 P_PATH='@s9s_mb_2u_lib.s9s_mb_2u(sch_1):page193_i45@pure_quanta.q_res(chips)',
 PATH='I45',
 DRAWING='@S9S_MB_2U_LIB.S9S_MB_2U(SCH_1):PAGE323',
 ROOM1='E1S1_P12V_MPS_TIC_BOM4',
 PHYS_PAGE='193',
 XY='(-1425,1175)',
 ROT='0',
 VER='1',
 PACK_TYPE='0402LF',
 CDS_LIB='pure_quanta',
 CDS_PART_NAME='Q_RES_0402LF-0,5%,1/16W,CHIP,CA',
 WATTAGE='1/16W',
 TOLERANCE='5%',
 MATERIAL='CHIP',
 ROOM='E1S1_P12V_MPS_MAM_BOM3',
 VALUE='0',
 PRIM_FILE='./archive_libs/logical/q_res/chips/chips.prt';

PART_NAME
 R3946 'Q_RES_0402LF-0,5%,1/16W,EMPTY,A':
 ROOM='E1S1_P3V3_BOM2';

SECTION_NUMBER 1
 '@S9S_MB_2U_LIB.S9S_MB_2U(SCH_1):PAGE323_I5@PURE_QUANTA.Q_RES(CHIPS)':
 C_PATH='@s9s_mb_2u_lib.s9s_mb_2u(sch_1):page323_i5@pure_quanta.q_res(chips)',
 P_PATH='@s9s_mb_2u_lib.s9s_mb_2u(sch_1):page193_i5@pure_quanta.q_res(chips)',
 PATH='I5',
 DRAWING='@S9S_MB_2U_LIB.S9S_MB_2U(SCH_1):PAGE323',
 PHYS_PAGE='193',
 XY='(-675,-1325)',
 ROT='0',
 VER='1',
 PACK_TYPE='0402LF',
 CDS_LIB='pure_quanta',
 CDS_PART_NAME='Q_RES_0402LF-0,5%,1/16W,EMPTY,A',
 WATTAGE='1/16W',
 TOLERANCE='5%',
 MATERIAL='EMPTY',
 ROOM='E1S1_P3V3_BOM2',
 VALUE='0',
 PRIM_FILE='./archive_libs/logical/q_res/chips/chips.prt';

PART_NAME
 R3948 'Q_RES_0402LF-10K,1%,1/16W,CHIPA':
 ROOM='E1S1_P12V_MPS_MAM_BOM3';

SECTION_NUMBER 1
 '@S9S_MB_2U_LIB.S9S_MB_2U(SCH_1):PAGE323_I64@PURE_QUANTA.Q_RES(CHIPS)':
 C_PATH='@s9s_mb_2u_lib.s9s_mb_2u(sch_1):page323_i64@pure_quanta.q_res(chips)',
 P_PATH='@s9s_mb_2u_lib.s9s_mb_2u(sch_1):page193_i64@pure_quanta.q_res(chips)',
 PATH='I64',
 DRAWING='@S9S_MB_2U_LIB.S9S_MB_2U(SCH_1):PAGE323',
 ROOM1='E1S1_P12V_MPS_TIC_BOM4',
 PHYS_PAGE='193',
 XY='(375,1750)',
 ROT='0',
 VER='2',
 PACK_TYPE='0402LF',
 LOCATION='R3948',
 CDS_LIB='pure_quanta',
 CDS_PART_NAME='Q_RES_0402LF-10K,1%,1/16W,CHIPA',
 WATTAGE='1/16W',
 TOLERANCE='1%',
 MATERIAL='CHIP',
 ROOM='E1S1_P12V_MPS_MAM_BOM3',
 VALUE='10K',
 PRIM_FILE='./archive_libs/logical/q_res/chips/chips.prt';

PART_NAME
 R3955 'Q_RES_0402LF-0,5%,1/16W,EMPTY,A':
 ROOM='E1S1_P12V_MPS_MAM_BOM3';

SECTION_NUMBER 1
 '@S9S_MB_2U_LIB.S9S_MB_2U(SCH_1):PAGE323_I67@PURE_QUANTA.Q_RES(CHIPS)':
 C_PATH='@s9s_mb_2u_lib.s9s_mb_2u(sch_1):page323_i67@pure_quanta.q_res(chips)',
 P_PATH='@s9s_mb_2u_lib.s9s_mb_2u(sch_1):page193_i67@pure_quanta.q_res(chips)',
 PATH='I67',
 DRAWING='@S9S_MB_2U_LIB.S9S_MB_2U(SCH_1):PAGE323',
 PHYS_PAGE='193',
 XY='(2325,150)',
 ROT='0',
 VER='1',
 PACK_TYPE='0402LF',
 CDS_LIB='pure_quanta',
 CDS_PART_NAME='Q_RES_0402LF-0,5%,1/16W,EMPTY,A',
 WATTAGE='1/16W',
 TOLERANCE='5%',
 MATERIAL='EMPTY',
 ROOM='E1S1_P12V_MPS_MAM_BOM3',
 VALUE='0',
 PRIM_FILE='./archive_libs/logical/q_res/chips/chips.prt';

PART_NAME
 R3956 'Q_RES_0402LF-0,5%,1/16W,CHIP,CA':;

SECTION_NUMBER 1
 '@S9S_MB_2U_LIB.S9S_MB_2U(SCH_1):PAGE323_I66@PURE_QUANTA.Q_RES(CHIPS)':
 C_PATH='@s9s_mb_2u_lib.s9s_mb_2u(sch_1):page323_i66@pure_quanta.q_res(chips)',
 P_PATH='@s9s_mb_2u_lib.s9s_mb_2u(sch_1):page193_i66@pure_quanta.q_res(chips)',
 PATH='I66',
 DRAWING='@S9S_MB_2U_LIB.S9S_MB_2U(SCH_1):PAGE323',
 ROOM1='E1S1_P12V_MPS_TIC_BOM4',
 PHYS_PAGE='193',
 XY='(2325,-25)',
 ROT='0',
 VER='1',
 PACK_TYPE='0402LF',
 CDS_LIB='pure_quanta',
 CDS_PART_NAME='Q_RES_0402LF-0,5%,1/16W,CHIP,CA',
 WATTAGE='1/16W',
 TOLERANCE='5%',
 MATERIAL='CHIP',
 VALUE='0',
 PRIM_FILE='./archive_libs/logical/q_res/chips/chips.prt';

PART_NAME
 R3958 'Q_RES_0402LF-0,5%,1/16W,EMPTY,A':
 ROOM='E1S1_P12V_MAM_MAM_BOM1';

SECTION_NUMBER 1
 '@S9S_MB_2U_LIB.S9S_MB_2U(SCH_1):PAGE324_I26@PURE_QUANTA.Q_RES(CHIPS)':
 C_PATH='@s9s_mb_2u_lib.s9s_mb_2u(sch_1):page324_i26@pure_quanta.q_res(chips)',
 P_PATH='@s9s_mb_2u_lib.s9s_mb_2u(sch_1):page192_i26@pure_quanta.q_res(chips)',
 PATH='I26',
 DRAWING='@S9S_MB_2U_LIB.S9S_MB_2U(SCH_1):PAGE324',
 ROOM1='E1S1_P12V_MAM_TIC_BOM2',
 PHYS_PAGE='192',
 XY='(-750,1000)',
 ROT='0',
 VER='1',
 PACK_TYPE='0402LF',
 CDS_LIB='pure_quanta',
 CDS_PART_NAME='Q_RES_0402LF-0,5%,1/16W,EMPTY,A',
 WATTAGE='1/16W',
 TOLERANCE='5%',
 MATERIAL='EMPTY',
 ROOM='E1S1_P12V_MAM_MAM_BOM1',
 VALUE='0',
 PRIM_FILE='./archive_libs/logical/q_res/chips/chips.prt';

PART_NAME
 R3959 'Q_RES_0402LF-0,5%,1/16W,CHIP,CA':
 ROOM='E1S1_P3V3_BOM1';

SECTION_NUMBER 1
 '@S9S_MB_2U_LIB.S9S_MB_2U(SCH_1):PAGE324_I15@PURE_QUANTA.Q_RES(CHIPS)':
 C_PATH='@s9s_mb_2u_lib.s9s_mb_2u(sch_1):page324_i15@pure_quanta.q_res(chips)',
 P_PATH='@s9s_mb_2u_lib.s9s_mb_2u(sch_1):page192_i15@pure_quanta.q_res(chips)',
 PATH='I15',
 DRAWING='@S9S_MB_2U_LIB.S9S_MB_2U(SCH_1):PAGE324',
 PHYS_PAGE='192',
 XY='(-600,-1725)',
 ROT='0',
 VER='1',
 PACK_TYPE='0402LF',
 CDS_LIB='pure_quanta',
 CDS_PART_NAME='Q_RES_0402LF-0,5%,1/16W,CHIP,CA',
 WATTAGE='1/16W',
 TOLERANCE='5%',
 MATERIAL='CHIP',
 ROOM='E1S1_P3V3_BOM1',
 VALUE='0',
 PRIM_FILE='./archive_libs/logical/q_res/chips/chips.prt';

PART_NAME
 R3972 'Q_RES_0402LF-0,5%,1/16W,EMPTY,A':
 ROOM='E1S1_P12V_MAM_MAM_BOM1';

SECTION_NUMBER 1
 '@S9S_MB_2U_LIB.S9S_MB_2U(SCH_1):PAGE324_I68@PURE_QUANTA.Q_RES(CHIPS)':
 C_PATH='@s9s_mb_2u_lib.s9s_mb_2u(sch_1):page324_i68@pure_quanta.q_res(chips)',
 P_PATH='@s9s_mb_2u_lib.s9s_mb_2u(sch_1):page192_i68@pure_quanta.q_res(chips)',
 PATH='I68',
 DRAWING='@S9S_MB_2U_LIB.S9S_MB_2U(SCH_1):PAGE324',
 ROOM1='E1S1_P12V_MAM_TIC_BOM2',
 PHYS_PAGE='192',
 XY='(2925,900)',
 ROT='0',
 VER='1',
 PACK_TYPE='0402LF',
 CDS_LIB='pure_quanta',
 CDS_PART_NAME='Q_RES_0402LF-0,5%,1/16W,EMPTY,A',
 WATTAGE='1/16W',
 TOLERANCE='5%',
 MATERIAL='EMPTY',
 ROOM='E1S1_P12V_MAM_MAM_BOM1',
 VALUE='0',
 PRIM_FILE='./archive_libs/logical/q_res/chips/chips.prt';

PART_NAME
 R3973 'Q_RES_0402LF-0,5%,1/16W,CHIP,CA':
 ROOM='E1S1_P3V3_BOM1';

SECTION_NUMBER 1
 '@S9S_MB_2U_LIB.S9S_MB_2U(SCH_1):PAGE324_I44@PURE_QUANTA.Q_RES(CHIPS)':
 C_PATH='@s9s_mb_2u_lib.s9s_mb_2u(sch_1):page324_i44@pure_quanta.q_res(chips)',
 P_PATH='@s9s_mb_2u_lib.s9s_mb_2u(sch_1):page192_i44@pure_quanta.q_res(chips)',
 PATH='I44',
 DRAWING='@S9S_MB_2U_LIB.S9S_MB_2U(SCH_1):PAGE324',
 PHYS_PAGE='192',
 XY='(2975,-1825)',
 ROT='0',
 VER='1',
 PACK_TYPE='0402LF',
 CDS_LIB='pure_quanta',
 CDS_PART_NAME='Q_RES_0402LF-0,5%,1/16W,CHIP,CA',
 WATTAGE='1/16W',
 TOLERANCE='5%',
 MATERIAL='CHIP',
 ROOM='E1S1_P3V3_BOM1',
 VALUE='0',
 PRIM_FILE='./archive_libs/logical/q_res/chips/chips.prt';

PART_NAME
 R3974 'Q_RES_0402LF-0,5%,1/16W,EMPTY,A':
 ROOM='E1S1_P12V_MAM_MAM_BOM1';

SECTION_NUMBER 1
 '@S9S_MB_2U_LIB.S9S_MB_2U(SCH_1):PAGE324_I67@PURE_QUANTA.Q_RES(CHIPS)':
 C_PATH='@s9s_mb_2u_lib.s9s_mb_2u(sch_1):page324_i67@pure_quanta.q_res(chips)',
 P_PATH='@s9s_mb_2u_lib.s9s_mb_2u(sch_1):page192_i67@pure_quanta.q_res(chips)',
 PATH='I67',
 DRAWING='@S9S_MB_2U_LIB.S9S_MB_2U(SCH_1):PAGE324',
 PHYS_PAGE='192',
 XY='(3075,700)',
 ROT='0',
 VER='1',
 PACK_TYPE='0402LF',
 LOCATION='R3974',
 CDS_LIB='pure_quanta',
 CDS_PART_NAME='Q_RES_0402LF-0,5%,1/16W,EMPTY,A',
 WATTAGE='1/16W',
 TOLERANCE='5%',
 MATERIAL='EMPTY',
 ROOM='E1S1_P12V_MAM_MAM_BOM1',
 VALUE='0',
 PRIM_FILE='./archive_libs/logical/q_res/chips/chips.prt';

PART_NAME
 R3975 'Q_RES_0402LF-0,5%,1/16W,EMPTY,A':;

SECTION_NUMBER 1
 '@S9S_MB_2U_LIB.S9S_MB_2U(SCH_1):PAGE324_I65@PURE_QUANTA.Q_RES(CHIPS)':
 C_PATH='@s9s_mb_2u_lib.s9s_mb_2u(sch_1):page324_i65@pure_quanta.q_res(chips)',
 P_PATH='@s9s_mb_2u_lib.s9s_mb_2u(sch_1):page192_i65@pure_quanta.q_res(chips)',
 PATH='I65',
 DRAWING='@S9S_MB_2U_LIB.S9S_MB_2U(SCH_1):PAGE324',
 ROOM1='E1S1_P12V_MAM_TIC_BOM2',
 PHYS_PAGE='192',
 XY='(3075,475)',
 ROT='0',
 VER='1',
 PACK_TYPE='0402LF',
 CDS_LIB='pure_quanta',
 CDS_PART_NAME='Q_RES_0402LF-0,5%,1/16W,EMPTY,A',
 WATTAGE='1/16W',
 TOLERANCE='5%',
 MATERIAL='EMPTY',
 VALUE='0',
 PRIM_FILE='./archive_libs/logical/q_res/chips/chips.prt';

PART_NAME
 R3976 'Q_RES_0402LF-100K,1%,1/16W,EMPA':
 ROOM='E1S1_P12V_MAM_MAM_BOM1';

SECTION_NUMBER 1
 '@S9S_MB_2U_LIB.S9S_MB_2U(SCH_1):PAGE324_I73@PURE_QUANTA.Q_RES(CHIPS)':
 C_PATH='@s9s_mb_2u_lib.s9s_mb_2u(sch_1):page324_i73@pure_quanta.q_res(chips)',
 P_PATH='@s9s_mb_2u_lib.s9s_mb_2u(sch_1):page192_i73@pure_quanta.q_res(chips)',
 PATH='I73',
 DRAWING='@S9S_MB_2U_LIB.S9S_MB_2U(SCH_1):PAGE324',
 ROOM1='E1S1_P12V_MAM_TIC_BOM2',
 PHYS_PAGE='192',
 XY='(3275,1150)',
 ROT='0',
 VER='2',
 PACK_TYPE='0402LF',
 LOCATION='R3976',
 CDS_LIB='pure_quanta',
 CDS_PART_NAME='Q_RES_0402LF-100K,1%,1/16W,EMPA',
 WATTAGE='1/16W',
 TOLERANCE='1%',
 MATERIAL='EMPTY',
 ROOM='E1S1_P12V_MAM_MAM_BOM1',
 VALUE='100K',
 PRIM_FILE='./archive_libs/logical/q_res/chips/chips.prt';

PART_NAME
 R3977 'Q_RES_0402LF-100K,1%,1/16W,CHIA':
 ROOM='E1S1_P3V3_BOM1';

SECTION_NUMBER 1
 '@S9S_MB_2U_LIB.S9S_MB_2U(SCH_1):PAGE324_I48@PURE_QUANTA.Q_RES(CHIPS)':
 C_PATH='@s9s_mb_2u_lib.s9s_mb_2u(sch_1):page324_i48@pure_quanta.q_res(chips)',
 P_PATH='@s9s_mb_2u_lib.s9s_mb_2u(sch_1):page192_i48@pure_quanta.q_res(chips)',
 PATH='I48',
 DRAWING='@S9S_MB_2U_LIB.S9S_MB_2U(SCH_1):PAGE324',
 PHYS_PAGE='192',
 XY='(3325,-1525)',
 ROT='0',
 VER='2',
 PACK_TYPE='0402LF',
 LOCATION='R3977',
 CDS_LIB='pure_quanta',
 CDS_PART_NAME='Q_RES_0402LF-100K,1%,1/16W,CHIA',
 WATTAGE='1/16W',
 TOLERANCE='1%',
 MATERIAL='CHIP',
 ROOM='E1S1_P3V3_BOM1',
 VALUE='100K',
 PRIM_FILE='./archive_libs/logical/q_res/chips/chips.prt';

PART_NAME
 R3978 'Q_RES_0402LF-100K,1%,1/16W,EMPA':
 ROOM='E1S1_P12V_MAM_MAM_BOM1';

SECTION_NUMBER 1
 '@S9S_MB_2U_LIB.S9S_MB_2U(SCH_1):PAGE324_I76@PURE_QUANTA.Q_RES(CHIPS)':
 C_PATH='@s9s_mb_2u_lib.s9s_mb_2u(sch_1):page324_i76@pure_quanta.q_res(chips)',
 P_PATH='@s9s_mb_2u_lib.s9s_mb_2u(sch_1):page192_i76@pure_quanta.q_res(chips)',
 PATH='I76',
 DRAWING='@S9S_MB_2U_LIB.S9S_MB_2U(SCH_1):PAGE324',
 ROOM1='E1S1_P12V_MAM_TIC_BOM2',
 PHYS_PAGE='192',
 XY='(3700,1150)',
 ROT='0',
 VER='2',
 PACK_TYPE='0402LF',
 LOCATION='R3978',
 CDS_LIB='pure_quanta',
 CDS_PART_NAME='Q_RES_0402LF-100K,1%,1/16W,EMPA',
 WATTAGE='1/16W',
 TOLERANCE='1%',
 MATERIAL='EMPTY',
 ROOM='E1S1_P12V_MAM_MAM_BOM1',
 VALUE='100K',
 PRIM_FILE='./archive_libs/logical/q_res/chips/chips.prt';

PART_NAME
 R3979 'Q_RES_0402LF-100K,1%,1/16W,CHIA':
 ROOM='E1S1_P3V3_BOM1';

SECTION_NUMBER 1
 '@S9S_MB_2U_LIB.S9S_MB_2U(SCH_1):PAGE324_I50@PURE_QUANTA.Q_RES(CHIPS)':
 C_PATH='@s9s_mb_2u_lib.s9s_mb_2u(sch_1):page324_i50@pure_quanta.q_res(chips)',
 P_PATH='@s9s_mb_2u_lib.s9s_mb_2u(sch_1):page192_i50@pure_quanta.q_res(chips)',
 PATH='I50',
 DRAWING='@S9S_MB_2U_LIB.S9S_MB_2U(SCH_1):PAGE324',
 PHYS_PAGE='192',
 XY='(3725,-1525)',
 ROT='0',
 VER='2',
 PACK_TYPE='0402LF',
 LOCATION='R3979',
 CDS_LIB='pure_quanta',
 CDS_PART_NAME='Q_RES_0402LF-100K,1%,1/16W,CHIA',
 WATTAGE='1/16W',
 TOLERANCE='1%',
 MATERIAL='CHIP',
 ROOM='E1S1_P3V3_BOM1',
 VALUE='100K',
 PRIM_FILE='./archive_libs/logical/q_res/chips/chips.prt';

PART_NAME
 R3996 'Q_RES_0402LF-0,5%,1/16W,CHIP,CA':;

SECTION_NUMBER 1
 '@S9S_MB_2U_LIB.S9S_MB_2U(SCH_1):PAGE229_I17@PURE_QUANTA.Q_RES(CHIPS)':
 C_PATH='@s9s_mb_2u_lib.s9s_mb_2u(sch_1):page229_i17@pure_quanta.q_res(chips)',
 P_PATH='@s9s_mb_2u_lib.s9s_mb_2u(sch_1):page242_i17@pure_quanta.q_res(chips)',
 PATH='I17',
 DRAWING='@S9S_MB_2U_LIB.S9S_MB_2U(SCH_1):PAGE229',
 PHYS_PAGE='242',
 XY='(-3425,875)',
 ROT='0',
 VER='1',
 PACK_TYPE='0402LF',
 CDS_LIB='pure_quanta',
 CDS_PART_NAME='Q_RES_0402LF-0,5%,1/16W,CHIP,CA',
 WATTAGE='1/16W',
 TOLERANCE='5%',
 MATERIAL='CHIP',
 VALUE='0',
 PRIM_FILE='./archive_libs/logical/q_res/chips/chips.prt';

PART_NAME
 R3997 'Q_RES_0402LF-0,5%,1/16W,EMPTY,A':
 ROOM='SCM_P12V_BOM1';

SECTION_NUMBER 1
 '@S9S_MB_2U_LIB.S9S_MB_2U(SCH_1):PAGE229_I27@PURE_QUANTA.Q_RES(CHIPS)':
 C_PATH='@s9s_mb_2u_lib.s9s_mb_2u(sch_1):page229_i27@pure_quanta.q_res(chips)',
 P_PATH='@s9s_mb_2u_lib.s9s_mb_2u(sch_1):page242_i27@pure_quanta.q_res(chips)',
 PATH='I27',
 DRAWING='@S9S_MB_2U_LIB.S9S_MB_2U(SCH_1):PAGE229',
 PHYS_PAGE='242',
 XY='(-500,1600)',
 ROT='0',
 VER='1',
 PACK_TYPE='0402LF',
 CDS_LIB='pure_quanta',
 CDS_PART_NAME='Q_RES_0402LF-0,5%,1/16W,EMPTY,A',
 WATTAGE='1/16W',
 TOLERANCE='5%',
 MATERIAL='EMPTY',
 ROOM='SCM_P12V_BOM1',
 VALUE='0',
 PRIM_FILE='./archive_libs/logical/q_res/chips/chips.prt';

PART_NAME
 R3998 'Q_RES_0402LF-0,5%,1/16W,CHIP,CA':
 ROOM='SCM_P12V_BOM2';

SECTION_NUMBER 1
 '@S9S_MB_2U_LIB.S9S_MB_2U(SCH_1):PAGE229_I14@PURE_QUANTA.Q_RES(CHIPS)':
 C_PATH='@s9s_mb_2u_lib.s9s_mb_2u(sch_1):page229_i14@pure_quanta.q_res(chips)',
 P_PATH='@s9s_mb_2u_lib.s9s_mb_2u(sch_1):page242_i14@pure_quanta.q_res(chips)',
 PATH='I14',
 DRAWING='@S9S_MB_2U_LIB.S9S_MB_2U(SCH_1):PAGE229',
 PHYS_PAGE='242',
 XY='(-300,-1250)',
 ROT='0',
 VER='1',
 PACK_TYPE='0402LF',
 CDS_LIB='pure_quanta',
 CDS_PART_NAME='Q_RES_0402LF-0,5%,1/16W,CHIP,CA',
 WATTAGE='1/16W',
 TOLERANCE='5%',
 MATERIAL='CHIP',
 ROOM='SCM_P12V_BOM2',
 VALUE='0',
 PRIM_FILE='./archive_libs/logical/q_res/chips/chips.prt';

PART_NAME
 R4013 'Q_RES_0402LF-100K,1%,1/16W,EMPA':
 ROOM='SCM_P12V_BOM1';

SECTION_NUMBER 1
 '@S9S_MB_2U_LIB.S9S_MB_2U(SCH_1):PAGE229_I79@PURE_QUANTA.Q_RES(CHIPS)':
 C_PATH='@s9s_mb_2u_lib.s9s_mb_2u(sch_1):page229_i79@pure_quanta.q_res(chips)',
 P_PATH='@s9s_mb_2u_lib.s9s_mb_2u(sch_1):page242_i79@pure_quanta.q_res(chips)',
 PATH='I79',
 DRAWING='@S9S_MB_2U_LIB.S9S_MB_2U(SCH_1):PAGE229',
 PHYS_PAGE='242',
 XY='(3500,1750)',
 ROT='0',
 VER='2',
 PACK_TYPE='0402LF',
 LOCATION='R4013',
 CDS_LIB='pure_quanta',
 CDS_PART_NAME='Q_RES_0402LF-100K,1%,1/16W,EMPA',
 WATTAGE='1/16W',
 TOLERANCE='1%',
 MATERIAL='EMPTY',
 ROOM='SCM_P12V_BOM1',
 VALUE='100K',
 PRIM_FILE='./archive_libs/logical/q_res/chips/chips.prt';

PART_NAME
 R4015 'Q_RES_0402LF-100K,1%,1/16W,EMPA':
 ROOM='SCM_P12V_BOM1';

SECTION_NUMBER 1
 '@S9S_MB_2U_LIB.S9S_MB_2U(SCH_1):PAGE229_I81@PURE_QUANTA.Q_RES(CHIPS)':
 C_PATH='@s9s_mb_2u_lib.s9s_mb_2u(sch_1):page229_i81@pure_quanta.q_res(chips)',
 P_PATH='@s9s_mb_2u_lib.s9s_mb_2u(sch_1):page242_i81@pure_quanta.q_res(chips)',
 PATH='I81',
 DRAWING='@S9S_MB_2U_LIB.S9S_MB_2U(SCH_1):PAGE229',
 PHYS_PAGE='242',
 XY='(3925,1750)',
 ROT='0',
 VER='2',
 PACK_TYPE='0402LF',
 LOCATION='R4015',
 CDS_LIB='pure_quanta',
 CDS_PART_NAME='Q_RES_0402LF-100K,1%,1/16W,EMPA',
 WATTAGE='1/16W',
 TOLERANCE='1%',
 MATERIAL='EMPTY',
 ROOM='SCM_P12V_BOM1',
 VALUE='100K',
 PRIM_FILE='./archive_libs/logical/q_res/chips/chips.prt';

PART_NAME
 R4016 'Q_RES_0402LF-4.32K,1%,1/16W,CHA':;

SECTION_NUMBER 1
 '@S9S_MB_2U_LIB.S9S_MB_2U(SCH_1):PAGE321_I97@PURE_QUANTA.Q_RES(CHIPS)':
 C_PATH='@s9s_mb_2u_lib.s9s_mb_2u(sch_1):page321_i97@pure_quanta.q_res(chips)',
 P_PATH='@s9s_mb_2u_lib.s9s_mb_2u(sch_1):page226_i97@pure_quanta.q_res(chips)',
 PATH='I97',
 DRAWING='@S9S_MB_2U_LIB.S9S_MB_2U(SCH_1):PAGE321',
 PHYS_PAGE='226',
 XY='(900,2225)',
 ROT='0',
 VER='2',
 PACK_TYPE='0402LF',
 LOCATION='R4016',
 CDS_LIB='pure_quanta',
 CDS_PART_NAME='Q_RES_0402LF-4.32K,1%,1/16W,CHA',
 WATTAGE='1/16W',
 TOLERANCE='1%',
 MATERIAL='CHIP',
 VALUE='4.32K',
 PRIM_FILE='./archive_libs/logical/q_res/chips/chips.prt';

PART_NAME
 R4019 'Q_RES_0402LF-1K,1%,1/16W,CHIP,A':;

SECTION_NUMBER 1
 '@S9S_MB_2U_LIB.S9S_MB_2U(SCH_1):PAGE321_I98@PURE_QUANTA.Q_RES(CHIPS)':
 C_PATH='@s9s_mb_2u_lib.s9s_mb_2u(sch_1):page321_i98@pure_quanta.q_res(chips)',
 P_PATH='@s9s_mb_2u_lib.s9s_mb_2u(sch_1):page226_i98@pure_quanta.q_res(chips)',
 PATH='I98',
 DRAWING='@S9S_MB_2U_LIB.S9S_MB_2U(SCH_1):PAGE321',
 PHYS_PAGE='226',
 XY='(900,1850)',
 ROT='0',
 VER='2',
 PACK_TYPE='0402LF',
 LOCATION='R4019',
 CDS_LIB='pure_quanta',
 CDS_PART_NAME='Q_RES_0402LF-1K,1%,1/16W,CHIP,A',
 WATTAGE='1/16W',
 TOLERANCE='1%',
 MATERIAL='CHIP',
 VALUE='1K',
 PRIM_FILE='./archive_libs/logical/q_res/chips/chips.prt';

PART_NAME
 R4021 'Q_RES_0402LF-33.2,1%,1/16W,CHIA':;

SECTION_NUMBER 1
 '@S9S_MB_2U_LIB.S9S_MB_2U(SCH_1):PAGE321_I78@PURE_QUANTA.Q_RES(CHIPS)':
 C_PATH='@s9s_mb_2u_lib.s9s_mb_2u(sch_1):page321_i78@pure_quanta.q_res(chips)',
 P_PATH='@s9s_mb_2u_lib.s9s_mb_2u(sch_1):page226_i78@pure_quanta.q_res(chips)',
 PATH='I78',
 DRAWING='@S9S_MB_2U_LIB.S9S_MB_2U(SCH_1):PAGE321',
 PHYS_PAGE='226',
 XY='(1050,1400)',
 ROT='0',
 VER='1',
 PACK_TYPE='0402LF',
 CDS_LIB='pure_quanta',
 CDS_PART_NAME='Q_RES_0402LF-33.2,1%,1/16W,CHIA',
 WATTAGE='1/16W',
 TOLERANCE='1%',
 MATERIAL='CHIP',
 VALUE='33.2',
 PRIM_FILE='./archive_libs/logical/q_res/chips/chips.prt';

PART_NAME
 R4022 'Q_RES_0402LF-33.2,1%,1/16W,CHIA':;

SECTION_NUMBER 1
 '@S9S_MB_2U_LIB.S9S_MB_2U(SCH_1):PAGE321_I79@PURE_QUANTA.Q_RES(CHIPS)':
 C_PATH='@s9s_mb_2u_lib.s9s_mb_2u(sch_1):page321_i79@pure_quanta.q_res(chips)',
 P_PATH='@s9s_mb_2u_lib.s9s_mb_2u(sch_1):page226_i79@pure_quanta.q_res(chips)',
 PATH='I79',
 DRAWING='@S9S_MB_2U_LIB.S9S_MB_2U(SCH_1):PAGE321',
 PHYS_PAGE='226',
 XY='(1050,1350)',
 ROT='0',
 VER='1',
 PACK_TYPE='0402LF',
 CDS_LIB='pure_quanta',
 CDS_PART_NAME='Q_RES_0402LF-33.2,1%,1/16W,CHIA',
 WATTAGE='1/16W',
 TOLERANCE='1%',
 MATERIAL='CHIP',
 VALUE='33.2',
 PRIM_FILE='./archive_libs/logical/q_res/chips/chips.prt';

PART_NAME
 R4023 'Q_RES_0402LF-33.2,1%,1/16W,CHIA':;

SECTION_NUMBER 1
 '@S9S_MB_2U_LIB.S9S_MB_2U(SCH_1):PAGE321_I80@PURE_QUANTA.Q_RES(CHIPS)':
 C_PATH='@s9s_mb_2u_lib.s9s_mb_2u(sch_1):page321_i80@pure_quanta.q_res(chips)',
 P_PATH='@s9s_mb_2u_lib.s9s_mb_2u(sch_1):page226_i80@pure_quanta.q_res(chips)',
 PATH='I80',
 DRAWING='@S9S_MB_2U_LIB.S9S_MB_2U(SCH_1):PAGE321',
 PHYS_PAGE='226',
 XY='(1050,1300)',
 ROT='0',
 VER='1',
 PACK_TYPE='0402LF',
 CDS_LIB='pure_quanta',
 CDS_PART_NAME='Q_RES_0402LF-33.2,1%,1/16W,CHIA',
 WATTAGE='1/16W',
 TOLERANCE='1%',
 MATERIAL='CHIP',
 VALUE='33.2',
 PRIM_FILE='./archive_libs/logical/q_res/chips/chips.prt';

PART_NAME
 R4029 'Q_RES_0402LF-1K,1%,1/16W,CHIP,A':;

SECTION_NUMBER 1
 '@S9S_MB_2U_LIB.S9S_MB_2U(SCH_1):PAGE321_I77@PURE_QUANTA.Q_RES(CHIPS)':
 C_PATH='@s9s_mb_2u_lib.s9s_mb_2u(sch_1):page321_i77@pure_quanta.q_res(chips)',
 P_PATH='@s9s_mb_2u_lib.s9s_mb_2u(sch_1):page226_i77@pure_quanta.q_res(chips)',
 PATH='I77',
 DRAWING='@S9S_MB_2U_LIB.S9S_MB_2U(SCH_1):PAGE321',
 PHYS_PAGE='226',
 XY='(1150,1550)',
 ROT='0',
 VER='1',
 PACK_TYPE='0402LF',
 CDS_LIB='pure_quanta',
 CDS_PART_NAME='Q_RES_0402LF-1K,1%,1/16W,CHIP,A',
 WATTAGE='1/16W',
 TOLERANCE='1%',
 MATERIAL='CHIP',
 VALUE='1K',
 PRIM_FILE='./archive_libs/logical/q_res/chips/chips.prt';

PART_NAME
 R4036 'Q_RES_0402LF-4.32K,1%,1/16W,CHA':;

SECTION_NUMBER 1
 '@S9S_MB_2U_LIB.S9S_MB_2U(SCH_1):PAGE322_I128@PURE_QUANTA.Q_RES(CHIPS)':
 C_PATH='@s9s_mb_2u_lib.s9s_mb_2u(sch_1):page322_i128@pure_quanta.q_res(chips)',
 P_PATH='@s9s_mb_2u_lib.s9s_mb_2u(sch_1):page225_i128@pure_quanta.q_res(chips)',
 PATH='I128',
 DRAWING='@S9S_MB_2U_LIB.S9S_MB_2U(SCH_1):PAGE322',
 PHYS_PAGE='225',
 XY='(-7850,2550)',
 ROT='0',
 VER='2',
 PACK_TYPE='0402LF',
 LOCATION='R4036',
 CDS_LIB='pure_quanta',
 CDS_PART_NAME='Q_RES_0402LF-4.32K,1%,1/16W,CHA',
 WATTAGE='1/16W',
 TOLERANCE='1%',
 MATERIAL='CHIP',
 VALUE='4.32K',
 PRIM_FILE='./archive_libs/logical/q_res/chips/chips.prt';

PART_NAME
 R4037 'Q_RES_0402LF-4.32K,1%,1/16W,CHA':;

SECTION_NUMBER 1
 '@S9S_MB_2U_LIB.S9S_MB_2U(SCH_1):PAGE322_I130@PURE_QUANTA.Q_RES(CHIPS)':
 C_PATH='@s9s_mb_2u_lib.s9s_mb_2u(sch_1):page322_i130@pure_quanta.q_res(chips)',
 P_PATH='@s9s_mb_2u_lib.s9s_mb_2u(sch_1):page225_i130@pure_quanta.q_res(chips)',
 PATH='I130',
 DRAWING='@S9S_MB_2U_LIB.S9S_MB_2U(SCH_1):PAGE322',
 PHYS_PAGE='225',
 XY='(-7850,475)',
 ROT='0',
 VER='2',
 PACK_TYPE='0402LF',
 LOCATION='R4037',
 CDS_LIB='pure_quanta',
 CDS_PART_NAME='Q_RES_0402LF-4.32K,1%,1/16W,CHA',
 WATTAGE='1/16W',
 TOLERANCE='1%',
 MATERIAL='CHIP',
 VALUE='4.32K',
 PRIM_FILE='./archive_libs/logical/q_res/chips/chips.prt';

PART_NAME
 R4038 'Q_RES_0402LF-4.32K,1%,1/16W,CHA':;

SECTION_NUMBER 1
 '@S9S_MB_2U_LIB.S9S_MB_2U(SCH_1):PAGE322_I182@PURE_QUANTA.Q_RES(CHIPS)':
 C_PATH='@s9s_mb_2u_lib.s9s_mb_2u(sch_1):page322_i182@pure_quanta.q_res(chips)',
 P_PATH='@s9s_mb_2u_lib.s9s_mb_2u(sch_1):page225_i182@pure_quanta.q_res(chips)',
 PATH='I182',
 DRAWING='@S9S_MB_2U_LIB.S9S_MB_2U(SCH_1):PAGE322',
 PHYS_PAGE='225',
 XY='(-7850,-1425)',
 ROT='0',
 VER='2',
 PACK_TYPE='0402LF',
 LOCATION='R4038',
 CDS_LIB='pure_quanta',
 CDS_PART_NAME='Q_RES_0402LF-4.32K,1%,1/16W,CHA',
 WATTAGE='1/16W',
 TOLERANCE='1%',
 MATERIAL='CHIP',
 VALUE='4.32K',
 PRIM_FILE='./archive_libs/logical/q_res/chips/chips.prt';

PART_NAME
 R4039 'Q_RES_0402LF-1K,1%,1/16W,CHIP,A':;

SECTION_NUMBER 1
 '@S9S_MB_2U_LIB.S9S_MB_2U(SCH_1):PAGE322_I129@PURE_QUANTA.Q_RES(CHIPS)':
 C_PATH='@s9s_mb_2u_lib.s9s_mb_2u(sch_1):page322_i129@pure_quanta.q_res(chips)',
 P_PATH='@s9s_mb_2u_lib.s9s_mb_2u(sch_1):page225_i129@pure_quanta.q_res(chips)',
 PATH='I129',
 DRAWING='@S9S_MB_2U_LIB.S9S_MB_2U(SCH_1):PAGE322',
 PHYS_PAGE='225',
 XY='(-7850,2175)',
 ROT='0',
 VER='2',
 PACK_TYPE='0402LF',
 LOCATION='R4039',
 CDS_LIB='pure_quanta',
 CDS_PART_NAME='Q_RES_0402LF-1K,1%,1/16W,CHIP,A',
 WATTAGE='1/16W',
 TOLERANCE='1%',
 MATERIAL='CHIP',
 VALUE='1K',
 PRIM_FILE='./archive_libs/logical/q_res/chips/chips.prt';

PART_NAME
 R4040 'Q_RES_0402LF-1K,1%,1/16W,CHIP,A':;

SECTION_NUMBER 1
 '@S9S_MB_2U_LIB.S9S_MB_2U(SCH_1):PAGE322_I131@PURE_QUANTA.Q_RES(CHIPS)':
 C_PATH='@s9s_mb_2u_lib.s9s_mb_2u(sch_1):page322_i131@pure_quanta.q_res(chips)',
 P_PATH='@s9s_mb_2u_lib.s9s_mb_2u(sch_1):page225_i131@pure_quanta.q_res(chips)',
 PATH='I131',
 DRAWING='@S9S_MB_2U_LIB.S9S_MB_2U(SCH_1):PAGE322',
 PHYS_PAGE='225',
 XY='(-7850,100)',
 ROT='0',
 VER='2',
 PACK_TYPE='0402LF',
 LOCATION='R4040',
 CDS_LIB='pure_quanta',
 CDS_PART_NAME='Q_RES_0402LF-1K,1%,1/16W,CHIP,A',
 WATTAGE='1/16W',
 TOLERANCE='1%',
 MATERIAL='CHIP',
 VALUE='1K',
 PRIM_FILE='./archive_libs/logical/q_res/chips/chips.prt';

PART_NAME
 R4041 'Q_RES_0402LF-1K,1%,1/16W,CHIP,A':;

SECTION_NUMBER 1
 '@S9S_MB_2U_LIB.S9S_MB_2U(SCH_1):PAGE322_I181@PURE_QUANTA.Q_RES(CHIPS)':
 C_PATH='@s9s_mb_2u_lib.s9s_mb_2u(sch_1):page322_i181@pure_quanta.q_res(chips)',
 P_PATH='@s9s_mb_2u_lib.s9s_mb_2u(sch_1):page225_i181@pure_quanta.q_res(chips)',
 PATH='I181',
 DRAWING='@S9S_MB_2U_LIB.S9S_MB_2U(SCH_1):PAGE322',
 PHYS_PAGE='225',
 XY='(-7850,-1800)',
 ROT='0',
 VER='2',
 PACK_TYPE='0402LF',
 LOCATION='R4041',
 CDS_LIB='pure_quanta',
 CDS_PART_NAME='Q_RES_0402LF-1K,1%,1/16W,CHIP,A',
 WATTAGE='1/16W',
 TOLERANCE='1%',
 MATERIAL='CHIP',
 VALUE='1K',
 PRIM_FILE='./archive_libs/logical/q_res/chips/chips.prt';

PART_NAME
 R4042 'Q_RES_0402LF-33.2,1%,1/16W,CHIA':;

SECTION_NUMBER 1
 '@S9S_MB_2U_LIB.S9S_MB_2U(SCH_1):PAGE322_I39@PURE_QUANTA.Q_RES(CHIPS)':
 C_PATH='@s9s_mb_2u_lib.s9s_mb_2u(sch_1):page322_i39@pure_quanta.q_res(chips)',
 P_PATH='@s9s_mb_2u_lib.s9s_mb_2u(sch_1):page225_i39@pure_quanta.q_res(chips)',
 PATH='I39',
 DRAWING='@S9S_MB_2U_LIB.S9S_MB_2U(SCH_1):PAGE322',
 PHYS_PAGE='225',
 XY='(-7700,1725)',
 ROT='0',
 VER='1',
 PACK_TYPE='0402LF',
 CDS_LIB='pure_quanta',
 CDS_PART_NAME='Q_RES_0402LF-33.2,1%,1/16W,CHIA',
 WATTAGE='1/16W',
 TOLERANCE='1%',
 MATERIAL='CHIP',
 VALUE='33.2',
 PRIM_FILE='./archive_libs/logical/q_res/chips/chips.prt';

PART_NAME
 R4043 'Q_RES_0402LF-33.2,1%,1/16W,CHIA':;

SECTION_NUMBER 1
 '@S9S_MB_2U_LIB.S9S_MB_2U(SCH_1):PAGE322_I38@PURE_QUANTA.Q_RES(CHIPS)':
 C_PATH='@s9s_mb_2u_lib.s9s_mb_2u(sch_1):page322_i38@pure_quanta.q_res(chips)',
 P_PATH='@s9s_mb_2u_lib.s9s_mb_2u(sch_1):page225_i38@pure_quanta.q_res(chips)',
 PATH='I38',
 DRAWING='@S9S_MB_2U_LIB.S9S_MB_2U(SCH_1):PAGE322',
 PHYS_PAGE='225',
 XY='(-7700,1675)',
 ROT='0',
 VER='1',
 PACK_TYPE='0402LF',
 CDS_LIB='pure_quanta',
 CDS_PART_NAME='Q_RES_0402LF-33.2,1%,1/16W,CHIA',
 WATTAGE='1/16W',
 TOLERANCE='1%',
 MATERIAL='CHIP',
 VALUE='33.2',
 PRIM_FILE='./archive_libs/logical/q_res/chips/chips.prt';

PART_NAME
 R4044 'Q_RES_0402LF-33.2,1%,1/16W,CHIA':;

SECTION_NUMBER 1
 '@S9S_MB_2U_LIB.S9S_MB_2U(SCH_1):PAGE322_I37@PURE_QUANTA.Q_RES(CHIPS)':
 C_PATH='@s9s_mb_2u_lib.s9s_mb_2u(sch_1):page322_i37@pure_quanta.q_res(chips)',
 P_PATH='@s9s_mb_2u_lib.s9s_mb_2u(sch_1):page225_i37@pure_quanta.q_res(chips)',
 PATH='I37',
 DRAWING='@S9S_MB_2U_LIB.S9S_MB_2U(SCH_1):PAGE322',
 PHYS_PAGE='225',
 XY='(-7700,1625)',
 ROT='0',
 VER='1',
 PACK_TYPE='0402LF',
 CDS_LIB='pure_quanta',
 CDS_PART_NAME='Q_RES_0402LF-33.2,1%,1/16W,CHIA',
 WATTAGE='1/16W',
 TOLERANCE='1%',
 MATERIAL='CHIP',
 VALUE='33.2',
 PRIM_FILE='./archive_libs/logical/q_res/chips/chips.prt';

PART_NAME
 R4045 'Q_RES_0402LF-33.2,1%,1/16W,CHIA':;

SECTION_NUMBER 1
 '@S9S_MB_2U_LIB.S9S_MB_2U(SCH_1):PAGE322_I36@PURE_QUANTA.Q_RES(CHIPS)':
 C_PATH='@s9s_mb_2u_lib.s9s_mb_2u(sch_1):page322_i36@pure_quanta.q_res(chips)',
 P_PATH='@s9s_mb_2u_lib.s9s_mb_2u(sch_1):page225_i36@pure_quanta.q_res(chips)',
 PATH='I36',
 DRAWING='@S9S_MB_2U_LIB.S9S_MB_2U(SCH_1):PAGE322',
 PHYS_PAGE='225',
 XY='(-7700,1575)',
 ROT='0',
 VER='1',
 PACK_TYPE='0402LF',
 CDS_LIB='pure_quanta',
 CDS_PART_NAME='Q_RES_0402LF-33.2,1%,1/16W,CHIA',
 WATTAGE='1/16W',
 TOLERANCE='1%',
 MATERIAL='CHIP',
 VALUE='33.2',
 PRIM_FILE='./archive_libs/logical/q_res/chips/chips.prt';

PART_NAME
 R4046 'Q_RES_0402LF-33.2,1%,1/16W,CHIA':;

SECTION_NUMBER 1
 '@S9S_MB_2U_LIB.S9S_MB_2U(SCH_1):PAGE322_I52@PURE_QUANTA.Q_RES(CHIPS)':
 C_PATH='@s9s_mb_2u_lib.s9s_mb_2u(sch_1):page322_i52@pure_quanta.q_res(chips)',
 P_PATH='@s9s_mb_2u_lib.s9s_mb_2u(sch_1):page225_i52@pure_quanta.q_res(chips)',
 PATH='I52',
 DRAWING='@S9S_MB_2U_LIB.S9S_MB_2U(SCH_1):PAGE322',
 PHYS_PAGE='225',
 XY='(-7700,-350)',
 ROT='0',
 VER='1',
 PACK_TYPE='0402LF',
 CDS_LIB='pure_quanta',
 CDS_PART_NAME='Q_RES_0402LF-33.2,1%,1/16W,CHIA',
 WATTAGE='1/16W',
 TOLERANCE='1%',
 MATERIAL='CHIP',
 VALUE='33.2',
 PRIM_FILE='./archive_libs/logical/q_res/chips/chips.prt';

PART_NAME
 R4047 'Q_RES_0402LF-33.2,1%,1/16W,CHIA':;

SECTION_NUMBER 1
 '@S9S_MB_2U_LIB.S9S_MB_2U(SCH_1):PAGE322_I53@PURE_QUANTA.Q_RES(CHIPS)':
 C_PATH='@s9s_mb_2u_lib.s9s_mb_2u(sch_1):page322_i53@pure_quanta.q_res(chips)',
 P_PATH='@s9s_mb_2u_lib.s9s_mb_2u(sch_1):page225_i53@pure_quanta.q_res(chips)',
 PATH='I53',
 DRAWING='@S9S_MB_2U_LIB.S9S_MB_2U(SCH_1):PAGE322',
 PHYS_PAGE='225',
 XY='(-7700,-400)',
 ROT='0',
 VER='1',
 PACK_TYPE='0402LF',
 CDS_LIB='pure_quanta',
 CDS_PART_NAME='Q_RES_0402LF-33.2,1%,1/16W,CHIA',
 WATTAGE='1/16W',
 TOLERANCE='1%',
 MATERIAL='CHIP',
 VALUE='33.2',
 PRIM_FILE='./archive_libs/logical/q_res/chips/chips.prt';

PART_NAME
 R4048 'Q_RES_0402LF-33.2,1%,1/16W,CHIA':;

SECTION_NUMBER 1
 '@S9S_MB_2U_LIB.S9S_MB_2U(SCH_1):PAGE322_I55@PURE_QUANTA.Q_RES(CHIPS)':
 C_PATH='@s9s_mb_2u_lib.s9s_mb_2u(sch_1):page322_i55@pure_quanta.q_res(chips)',
 P_PATH='@s9s_mb_2u_lib.s9s_mb_2u(sch_1):page225_i55@pure_quanta.q_res(chips)',
 PATH='I55',
 DRAWING='@S9S_MB_2U_LIB.S9S_MB_2U(SCH_1):PAGE322',
 PHYS_PAGE='225',
 XY='(-7700,-450)',
 ROT='0',
 VER='1',
 PACK_TYPE='0402LF',
 CDS_LIB='pure_quanta',
 CDS_PART_NAME='Q_RES_0402LF-33.2,1%,1/16W,CHIA',
 WATTAGE='1/16W',
 TOLERANCE='1%',
 MATERIAL='CHIP',
 VALUE='33.2',
 PRIM_FILE='./archive_libs/logical/q_res/chips/chips.prt';

PART_NAME
 R4049 'Q_RES_0402LF-33.2,1%,1/16W,CHIA':;

SECTION_NUMBER 1
 '@S9S_MB_2U_LIB.S9S_MB_2U(SCH_1):PAGE322_I54@PURE_QUANTA.Q_RES(CHIPS)':
 C_PATH='@s9s_mb_2u_lib.s9s_mb_2u(sch_1):page322_i54@pure_quanta.q_res(chips)',
 P_PATH='@s9s_mb_2u_lib.s9s_mb_2u(sch_1):page225_i54@pure_quanta.q_res(chips)',
 PATH='I54',
 DRAWING='@S9S_MB_2U_LIB.S9S_MB_2U(SCH_1):PAGE322',
 PHYS_PAGE='225',
 XY='(-7700,-500)',
 ROT='0',
 VER='1',
 PACK_TYPE='0402LF',
 CDS_LIB='pure_quanta',
 CDS_PART_NAME='Q_RES_0402LF-33.2,1%,1/16W,CHIA',
 WATTAGE='1/16W',
 TOLERANCE='1%',
 MATERIAL='CHIP',
 VALUE='33.2',
 PRIM_FILE='./archive_libs/logical/q_res/chips/chips.prt';

PART_NAME
 R4050 'Q_RES_0402LF-33.2,1%,1/16W,CHIA':;

SECTION_NUMBER 1
 '@S9S_MB_2U_LIB.S9S_MB_2U(SCH_1):PAGE322_I184@PURE_QUANTA.Q_RES(CHIPS)':
 C_PATH='@s9s_mb_2u_lib.s9s_mb_2u(sch_1):page322_i184@pure_quanta.q_res(chips)',
 P_PATH='@s9s_mb_2u_lib.s9s_mb_2u(sch_1):page225_i184@pure_quanta.q_res(chips)',
 PATH='I184',
 DRAWING='@S9S_MB_2U_LIB.S9S_MB_2U(SCH_1):PAGE322',
 PHYS_PAGE='225',
 XY='(-5800,-1800)',
 ROT='0',
 VER='1',
 PACK_TYPE='0402LF',
 CDS_LIB='pure_quanta',
 CDS_PART_NAME='Q_RES_0402LF-33.2,1%,1/16W,CHIA',
 WATTAGE='1/16W',
 TOLERANCE='1%',
 MATERIAL='CHIP',
 VALUE='33.2',
 PRIM_FILE='./archive_libs/logical/q_res/chips/chips.prt';

PART_NAME
 R4051 'Q_RES_0402LF-33.2,1%,1/16W,CHIA':;

SECTION_NUMBER 1
 '@S9S_MB_2U_LIB.S9S_MB_2U(SCH_1):PAGE322_I94@PURE_QUANTA.Q_RES(CHIPS)':
 C_PATH='@s9s_mb_2u_lib.s9s_mb_2u(sch_1):page322_i94@pure_quanta.q_res(chips)',
 P_PATH='@s9s_mb_2u_lib.s9s_mb_2u(sch_1):page225_i94@pure_quanta.q_res(chips)',
 PATH='I94',
 DRAWING='@S9S_MB_2U_LIB.S9S_MB_2U(SCH_1):PAGE322',
 PHYS_PAGE='225',
 XY='(-5800,-2300)',
 ROT='0',
 VER='1',
 PACK_TYPE='0402LF',
 CDS_LIB='pure_quanta',
 CDS_PART_NAME='Q_RES_0402LF-33.2,1%,1/16W,CHIA',
 WATTAGE='1/16W',
 TOLERANCE='1%',
 MATERIAL='CHIP',
 VALUE='33.2',
 PRIM_FILE='./archive_libs/logical/q_res/chips/chips.prt';

PART_NAME
 R4052 'Q_RES_0402LF-33.2,1%,1/16W,CHIA':;

SECTION_NUMBER 1
 '@S9S_MB_2U_LIB.S9S_MB_2U(SCH_1):PAGE322_I187@PURE_QUANTA.Q_RES(CHIPS)':
 C_PATH='@s9s_mb_2u_lib.s9s_mb_2u(sch_1):page322_i187@pure_quanta.q_res(chips)',
 P_PATH='@s9s_mb_2u_lib.s9s_mb_2u(sch_1):page225_i187@pure_quanta.q_res(chips)',
 PATH='I187',
 DRAWING='@S9S_MB_2U_LIB.S9S_MB_2U(SCH_1):PAGE322',
 PHYS_PAGE='225',
 XY='(-5800,-2800)',
 ROT='0',
 VER='1',
 PACK_TYPE='0402LF',
 CDS_LIB='pure_quanta',
 CDS_PART_NAME='Q_RES_0402LF-33.2,1%,1/16W,CHIA',
 WATTAGE='1/16W',
 TOLERANCE='1%',
 MATERIAL='CHIP',
 VALUE='33.2',
 PRIM_FILE='./archive_libs/logical/q_res/chips/chips.prt';

PART_NAME
 R4053 'Q_RES_0402LF-1K,1%,1/16W,CHIP,A':;

SECTION_NUMBER 1
 '@S9S_MB_2U_LIB.S9S_MB_2U(SCH_1):PAGE322_I66@PURE_QUANTA.Q_RES(CHIPS)':
 C_PATH='@s9s_mb_2u_lib.s9s_mb_2u(sch_1):page322_i66@pure_quanta.q_res(chips)',
 P_PATH='@s9s_mb_2u_lib.s9s_mb_2u(sch_1):page225_i66@pure_quanta.q_res(chips)',
 PATH='I66',
 DRAWING='@S9S_MB_2U_LIB.S9S_MB_2U(SCH_1):PAGE322',
 PHYS_PAGE='225',
 XY='(-7600,1875)',
 ROT='0',
 VER='1',
 PACK_TYPE='0402LF',
 CDS_LIB='pure_quanta',
 CDS_PART_NAME='Q_RES_0402LF-1K,1%,1/16W,CHIP,A',
 WATTAGE='1/16W',
 TOLERANCE='1%',
 MATERIAL='CHIP',
 VALUE='1K',
 PRIM_FILE='./archive_libs/logical/q_res/chips/chips.prt';

PART_NAME
 R4054 'Q_RES_0402LF-1K,1%,1/16W,CHIP,A':;

SECTION_NUMBER 1
 '@S9S_MB_2U_LIB.S9S_MB_2U(SCH_1):PAGE322_I67@PURE_QUANTA.Q_RES(CHIPS)':
 C_PATH='@s9s_mb_2u_lib.s9s_mb_2u(sch_1):page322_i67@pure_quanta.q_res(chips)',
 P_PATH='@s9s_mb_2u_lib.s9s_mb_2u(sch_1):page225_i67@pure_quanta.q_res(chips)',
 PATH='I67',
 DRAWING='@S9S_MB_2U_LIB.S9S_MB_2U(SCH_1):PAGE322',
 PHYS_PAGE='225',
 XY='(-7600,-200)',
 ROT='0',
 VER='1',
 PACK_TYPE='0402LF',
 CDS_LIB='pure_quanta',
 CDS_PART_NAME='Q_RES_0402LF-1K,1%,1/16W,CHIP,A',
 WATTAGE='1/16W',
 TOLERANCE='1%',
 MATERIAL='CHIP',
 VALUE='1K',
 PRIM_FILE='./archive_libs/logical/q_res/chips/chips.prt';

PART_NAME
 R4055 'Q_RES_0402LF-1K,1%,1/16W,CHIP,A':;

SECTION_NUMBER 1
 '@S9S_MB_2U_LIB.S9S_MB_2U(SCH_1):PAGE322_I91@PURE_QUANTA.Q_RES(CHIPS)':
 C_PATH='@s9s_mb_2u_lib.s9s_mb_2u(sch_1):page322_i91@pure_quanta.q_res(chips)',
 P_PATH='@s9s_mb_2u_lib.s9s_mb_2u(sch_1):page225_i91@pure_quanta.q_res(chips)',
 PATH='I91',
 DRAWING='@S9S_MB_2U_LIB.S9S_MB_2U(SCH_1):PAGE322',
 PHYS_PAGE='225',
 XY='(-7575,-2150)',
 ROT='0',
 VER='1',
 PACK_TYPE='0402LF',
 CDS_LIB='pure_quanta',
 CDS_PART_NAME='Q_RES_0402LF-1K,1%,1/16W,CHIP,A',
 WATTAGE='1/16W',
 TOLERANCE='1%',
 MATERIAL='CHIP',
 VALUE='1K',
 PRIM_FILE='./archive_libs/logical/q_res/chips/chips.prt';

PART_NAME
 R4056 'Q_RES_0402LF-0,5%,1/16W,CHIP,CA':;

SECTION_NUMBER 1
 '@S9S_MB_2U_LIB.S9S_MB_2U(SCH_1):PAGE312_I80@PURE_QUANTA.Q_RES(CHIPS)':
 C_PATH='@s9s_mb_2u_lib.s9s_mb_2u(sch_1):page312_i80@pure_quanta.q_res(chips)',
 P_PATH='@s9s_mb_2u_lib.s9s_mb_2u(sch_1):page215_i80@pure_quanta.q_res(chips)',
 PATH='I80',
 DRAWING='@S9S_MB_2U_LIB.S9S_MB_2U(SCH_1):PAGE312',
 PHYS_PAGE='215',
 XY='(-4550,875)',
 ROT='0',
 VER='1',
 PACK_TYPE='0402LF',
 CDS_LIB='pure_quanta',
 CDS_PART_NAME='Q_RES_0402LF-0,5%,1/16W,CHIP,CA',
 WATTAGE='1/16W',
 TOLERANCE='5%',
 MATERIAL='CHIP',
 VALUE='0',
 PRIM_FILE='./archive_libs/logical/q_res/chips/chips.prt';

PART_NAME
 R4057 'Q_RES_0402LF-33.2,1%,1/16W,CHIA':;

SECTION_NUMBER 1
 '@S9S_MB_2U_LIB.S9S_MB_2U(SCH_1):PAGE312_I217@PURE_QUANTA.Q_RES(CHIPS)':
 C_PATH='@s9s_mb_2u_lib.s9s_mb_2u(sch_1):page312_i217@pure_quanta.q_res(chips)',
 P_PATH='@s9s_mb_2u_lib.s9s_mb_2u(sch_1):page215_i217@pure_quanta.q_res(chips)',
 PATH='I217',
 DRAWING='@S9S_MB_2U_LIB.S9S_MB_2U(SCH_1):PAGE312',
 PHYS_PAGE='215',
 XY='(-4550,700)',
 ROT='0',
 VER='1',
 PACK_TYPE='0402LF',
 LOCATION='R4057',
 CDS_LIB='pure_quanta',
 CDS_PART_NAME='Q_RES_0402LF-33.2,1%,1/16W,CHIA',
 WATTAGE='1/16W',
 TOLERANCE='1%',
 MATERIAL='CHIP',
 VALUE='33.2',
 PRIM_FILE='./archive_libs/logical/q_res/chips/chips.prt';

PART_NAME
 R4059 'Q_RES_0402LF-0,5%,1/16W,EMPTY,A':
 ROOM='NIC1_P12V_MAM_MAM_BOM1';

SECTION_NUMBER 1
 '@S9S_MB_2U_LIB.S9S_MB_2U(SCH_1):PAGE131_I6@PURE_QUANTA.Q_RES(CHIPS)':
 C_PATH='@s9s_mb_2u_lib.s9s_mb_2u(sch_1):page131_i6@pure_quanta.q_res(chips)',
 P_PATH='@s9s_mb_2u_lib.s9s_mb_2u(sch_1):page162_i6@pure_quanta.q_res(chips)',
 PATH='I6',
 DRAWING='@S9S_MB_2U_LIB.S9S_MB_2U(SCH_1):PAGE131',
 ROOM1='NIC1_P12V_MAM_TIC_BOM2',
 PHYS_PAGE='162',
 XY='(-3900,-1000)',
 ROT='0',
 VER='1',
 PACK_TYPE='0402LF',
 CDS_LIB='pure_quanta',
 CDS_PART_NAME='Q_RES_0402LF-0,5%,1/16W,EMPTY,A',
 WATTAGE='1/16W',
 TOLERANCE='5%',
 MATERIAL='EMPTY',
 ROOM='NIC1_P12V_MAM_MAM_BOM1',
 VALUE='0',
 PRIM_FILE='./archive_libs/logical/q_res/chips/chips.prt';

PART_NAME
 R4060 'Q_RES_0402LF-0,5%,1/16W,CHIP,CA':;

SECTION_NUMBER 1
 '@S9S_MB_2U_LIB.S9S_MB_2U(SCH_1):PAGE131_I35@PURE_QUANTA.Q_RES(CHIPS)':
 C_PATH='@s9s_mb_2u_lib.s9s_mb_2u(sch_1):page131_i35@pure_quanta.q_res(chips)',
 P_PATH='@s9s_mb_2u_lib.s9s_mb_2u(sch_1):page162_i35@pure_quanta.q_res(chips)',
 PATH='I35',
 DRAWING='@S9S_MB_2U_LIB.S9S_MB_2U(SCH_1):PAGE131',
 PHYS_PAGE='162',
 XY='(-3275,1300)',
 ROT='0',
 VER='1',
 PACK_TYPE='0402LF',
 CDS_LIB='pure_quanta',
 CDS_PART_NAME='Q_RES_0402LF-0,5%,1/16W,CHIP,CA',
 WATTAGE='1/16W',
 TOLERANCE='5%',
 MATERIAL='CHIP',
 VALUE='0',
 PRIM_FILE='./archive_libs/logical/q_res/chips/chips.prt';

PART_NAME
 R4061 'Q_RES_0402LF-0,5%,1/16W,EMPTY,A':
 ROOM='NIC1_P12V_MAM_MAM_BOM1';

SECTION_NUMBER 1
 '@S9S_MB_2U_LIB.S9S_MB_2U(SCH_1):PAGE153_I4@PURE_QUANTA.Q_RES(CHIPS)':
 C_PATH='@s9s_mb_2u_lib.s9s_mb_2u(sch_1):page153_i4@pure_quanta.q_res(chips)',
 P_PATH='@s9s_mb_2u_lib.s9s_mb_2u(sch_1):page156_i4@pure_quanta.q_res(chips)',
 PATH='I4',
 DRAWING='@S9S_MB_2U_LIB.S9S_MB_2U(SCH_1):PAGE153',
 ROOM1='NIC1_P12V_MAM_TIC_BOM2',
 PHYS_PAGE='156',
 XY='(2425,10200)',
 ROT='0',
 VER='1',
 PACK_TYPE='0402LF',
 CDS_LIB='pure_quanta',
 CDS_PART_NAME='Q_RES_0402LF-0,5%,1/16W,EMPTY,A',
 WATTAGE='1/16W',
 TOLERANCE='5%',
 MATERIAL='EMPTY',
 ROOM='NIC1_P12V_MAM_MAM_BOM1',
 VALUE='0',
 PRIM_FILE='./archive_libs/logical/q_res/chips/chips.prt';

PART_NAME
 R4062 'Q_RES_0402LF-0,5%,1/16W,EMPTY,A':
 ROOM='SCM_P12V_BOM1';

SECTION_NUMBER 1
 '@S9S_MB_2U_LIB.S9S_MB_2U(SCH_1):PAGE229_I20@PURE_QUANTA.Q_RES(CHIPS)':
 C_PATH='@s9s_mb_2u_lib.s9s_mb_2u(sch_1):page229_i20@pure_quanta.q_res(chips)',
 P_PATH='@s9s_mb_2u_lib.s9s_mb_2u(sch_1):page242_i20@pure_quanta.q_res(chips)',
 PATH='I20',
 DRAWING='@S9S_MB_2U_LIB.S9S_MB_2U(SCH_1):PAGE229',
 PHYS_PAGE='242',
 XY='(-2625,875)',
 ROT='0',
 VER='1',
 PACK_TYPE='0402LF',
 CDS_LIB='pure_quanta',
 CDS_PART_NAME='Q_RES_0402LF-0,5%,1/16W,EMPTY,A',
 WATTAGE='1/16W',
 TOLERANCE='5%',
 MATERIAL='EMPTY',
 ROOM='SCM_P12V_BOM1',
 VALUE='0',
 PRIM_FILE='./archive_libs/logical/q_res/chips/chips.prt';

PART_NAME
 R4063 'Q_RES_0402LF-0,5%,1/16W,CHIP,CA':
 ROOM='E1S1_P3V3_BOM1';

SECTION_NUMBER 1
 '@S9S_MB_2U_LIB.S9S_MB_2U(SCH_1):PAGE324_I1@PURE_QUANTA.Q_RES(CHIPS)':
 C_PATH='@s9s_mb_2u_lib.s9s_mb_2u(sch_1):page324_i1@pure_quanta.q_res(chips)',
 P_PATH='@s9s_mb_2u_lib.s9s_mb_2u(sch_1):page192_i1@pure_quanta.q_res(chips)',
 PATH='I1',
 DRAWING='@S9S_MB_2U_LIB.S9S_MB_2U(SCH_1):PAGE324',
 PHYS_PAGE='192',
 XY='(-4100,-2400)',
 ROT='0',
 VER='1',
 PACK_TYPE='0402LF',
 CDS_LIB='pure_quanta',
 CDS_PART_NAME='Q_RES_0402LF-0,5%,1/16W,CHIP,CA',
 WATTAGE='1/16W',
 TOLERANCE='5%',
 MATERIAL='CHIP',
 ROOM='E1S1_P3V3_BOM1',
 VALUE='0',
 PRIM_FILE='./archive_libs/logical/q_res/chips/chips.prt';

PART_NAME
 R4064 'Q_RES_0402LF-0,5%,1/16W,CHIP,CA':;

SECTION_NUMBER 1
 '@S9S_MB_2U_LIB.S9S_MB_2U(SCH_1):PAGE324_I21@PURE_QUANTA.Q_RES(CHIPS)':
 C_PATH='@s9s_mb_2u_lib.s9s_mb_2u(sch_1):page324_i21@pure_quanta.q_res(chips)',
 P_PATH='@s9s_mb_2u_lib.s9s_mb_2u(sch_1):page192_i21@pure_quanta.q_res(chips)',
 PATH='I21',
 DRAWING='@S9S_MB_2U_LIB.S9S_MB_2U(SCH_1):PAGE324',
 PHYS_PAGE='192',
 XY='(-3400,100)',
 ROT='0',
 VER='1',
 PACK_TYPE='0402LF',
 CDS_LIB='pure_quanta',
 CDS_PART_NAME='Q_RES_0402LF-0,5%,1/16W,CHIP,CA',
 WATTAGE='1/16W',
 TOLERANCE='5%',
 MATERIAL='CHIP',
 VALUE='0',
 PRIM_FILE='./archive_libs/logical/q_res/chips/chips.prt';

PART_NAME
 R4065 'Q_RES_0402LF-10K,1%,1/16W,EMPTA':
 ROOM='NIC1_P12V_MAM_MAM_BOM1';

SECTION_NUMBER 1
 '@S9S_MB_2U_LIB.S9S_MB_2U(SCH_1):PAGE131_I14@PURE_QUANTA.Q_RES(CHIPS)':
 C_PATH='@s9s_mb_2u_lib.s9s_mb_2u(sch_1):page131_i14@pure_quanta.q_res(chips)',
 P_PATH='@s9s_mb_2u_lib.s9s_mb_2u(sch_1):page162_i14@pure_quanta.q_res(chips)',
 PATH='I14',
 DRAWING='@S9S_MB_2U_LIB.S9S_MB_2U(SCH_1):PAGE131',
 ROOM1='NIC1_P12V_MAM_TIC_BOM2',
 PHYS_PAGE='162',
 XY='(-2975,-350)',
 ROT='0',
 VER='2',
 PACK_TYPE='0402LF',
 CDS_LIB='pure_quanta',
 CDS_PART_NAME='Q_RES_0402LF-10K,1%,1/16W,EMPTA',
 WATTAGE='1/16W',
 TOLERANCE='1%',
 MATERIAL='EMPTY',
 ROOM='NIC1_P12V_MAM_MAM_BOM1',
 VALUE='10K',
 PRIM_FILE='./archive_libs/logical/q_res/chips/chips.prt';

PART_NAME
 R4066 'Q_RES_0402LF-4.7K,5%,1/16W,CHIA':;

SECTION_NUMBER 1
 '@S9S_MB_2U_LIB.S9S_MB_2U(SCH_1):PAGE131_I37@PURE_QUANTA.Q_RES(CHIPS)':
 C_PATH='@s9s_mb_2u_lib.s9s_mb_2u(sch_1):page131_i37@pure_quanta.q_res(chips)',
 P_PATH='@s9s_mb_2u_lib.s9s_mb_2u(sch_1):page162_i37@pure_quanta.q_res(chips)',
 PATH='I37',
 DRAWING='@S9S_MB_2U_LIB.S9S_MB_2U(SCH_1):PAGE131',
 PHYS_PAGE='162',
 XY='(-2825,975)',
 ROT='0',
 VER='2',
 PACK_TYPE='0402LF',
 CDS_LIB='pure_quanta',
 CDS_PART_NAME='Q_RES_0402LF-4.7K,5%,1/16W,CHIA',
 WATTAGE='1/16W',
 TOLERANCE='5%',
 MATERIAL='CHIP',
 VALUE='4.7K',
 PRIM_FILE='./archive_libs/logical/q_res/chips/chips.prt';

PART_NAME
 R4067 'Q_RES_0402LF-10K,1%,1/16W,CHIPA':
 ROOM='NIC1_P3V3_BOM1';

SECTION_NUMBER 1
 '@S9S_MB_2U_LIB.S9S_MB_2U(SCH_1):PAGE131_I40@PURE_QUANTA.Q_RES(CHIPS)':
 C_PATH='@s9s_mb_2u_lib.s9s_mb_2u(sch_1):page131_i40@pure_quanta.q_res(chips)',
 P_PATH='@s9s_mb_2u_lib.s9s_mb_2u(sch_1):page162_i40@pure_quanta.q_res(chips)',
 PATH='I40',
 DRAWING='@S9S_MB_2U_LIB.S9S_MB_2U(SCH_1):PAGE131',
 PHYS_PAGE='162',
 XY='(-2325,1950)',
 ROT='0',
 VER='2',
 PACK_TYPE='0402LF',
 CDS_LIB='pure_quanta',
 CDS_PART_NAME='Q_RES_0402LF-10K,1%,1/16W,CHIPA',
 WATTAGE='1/16W',
 TOLERANCE='1%',
 MATERIAL='CHIP',
 ROOM='NIC1_P3V3_BOM1',
 VALUE='10K',
 PRIM_FILE='./archive_libs/logical/q_res/chips/chips.prt';

PART_NAME
 R4068 'Q_RES_0402LF-10K,1%,1/16W,EMPTA':
 ROOM='NIC1_P12V_MAM_MAM_BOM1';

SECTION_NUMBER 1
 '@S9S_MB_2U_LIB.S9S_MB_2U(SCH_1):PAGE153_I15@PURE_QUANTA.Q_RES(CHIPS)':
 C_PATH='@s9s_mb_2u_lib.s9s_mb_2u(sch_1):page153_i15@pure_quanta.q_res(chips)',
 P_PATH='@s9s_mb_2u_lib.s9s_mb_2u(sch_1):page156_i15@pure_quanta.q_res(chips)',
 PATH='I15',
 DRAWING='@S9S_MB_2U_LIB.S9S_MB_2U(SCH_1):PAGE153',
 ROOM1='NIC1_P12V_MAM_TIC_BOM2',
 PHYS_PAGE='156',
 XY='(3375,10850)',
 ROT='0',
 VER='2',
 PACK_TYPE='0402LF',
 CDS_LIB='pure_quanta',
 CDS_PART_NAME='Q_RES_0402LF-10K,1%,1/16W,EMPTA',
 WATTAGE='1/16W',
 TOLERANCE='1%',
 MATERIAL='EMPTY',
 ROOM='NIC1_P12V_MAM_MAM_BOM1',
 VALUE='10K',
 PRIM_FILE='./archive_libs/logical/q_res/chips/chips.prt';

PART_NAME
 R4069 'Q_RES_0402LF-4.7K,5%,1/16W,CHIA':;

SECTION_NUMBER 1
 '@S9S_MB_2U_LIB.S9S_MB_2U(SCH_1):PAGE153_I20@PURE_QUANTA.Q_RES(CHIPS)':
 C_PATH='@s9s_mb_2u_lib.s9s_mb_2u(sch_1):page153_i20@pure_quanta.q_res(chips)',
 P_PATH='@s9s_mb_2u_lib.s9s_mb_2u(sch_1):page156_i20@pure_quanta.q_res(chips)',
 PATH='I20',
 DRAWING='@S9S_MB_2U_LIB.S9S_MB_2U(SCH_1):PAGE153',
 PHYS_PAGE='156',
 XY='(3550,11525)',
 ROT='0',
 VER='2',
 PACK_TYPE='0402LF',
 CDS_LIB='pure_quanta',
 CDS_PART_NAME='Q_RES_0402LF-4.7K,5%,1/16W,CHIA',
 WATTAGE='1/16W',
 TOLERANCE='5%',
 MATERIAL='CHIP',
 VALUE='4.7K',
 PRIM_FILE='./archive_libs/logical/q_res/chips/chips.prt';

PART_NAME
 R4070 'Q_RES_0402LF-10K,1%,1/16W,CHIPA':
 ROOM='NIC1_P3V3_BOM1';

SECTION_NUMBER 1
 '@S9S_MB_2U_LIB.S9S_MB_2U(SCH_1):PAGE153_I62@PURE_QUANTA.Q_RES(CHIPS)':
 C_PATH='@s9s_mb_2u_lib.s9s_mb_2u(sch_1):page153_i62@pure_quanta.q_res(chips)',
 P_PATH='@s9s_mb_2u_lib.s9s_mb_2u(sch_1):page156_i62@pure_quanta.q_res(chips)',
 PATH='I62',
 DRAWING='@S9S_MB_2U_LIB.S9S_MB_2U(SCH_1):PAGE153',
 PHYS_PAGE='156',
 XY='(4125,12500)',
 ROT='0',
 VER='2',
 PACK_TYPE='0402LF',
 CDS_LIB='pure_quanta',
 CDS_PART_NAME='Q_RES_0402LF-10K,1%,1/16W,CHIPA',
 WATTAGE='1/16W',
 TOLERANCE='1%',
 MATERIAL='CHIP',
 ROOM='NIC1_P3V3_BOM1',
 VALUE='10K',
 PRIM_FILE='./archive_libs/logical/q_res/chips/chips.prt';

PART_NAME
 R4071 'Q_RES_0402LF-10K,1%,1/16W,EMPTA':
 ROOM='SCM_P12V_BOM1';

SECTION_NUMBER 1
 '@S9S_MB_2U_LIB.S9S_MB_2U(SCH_1):PAGE229_I24@PURE_QUANTA.Q_RES(CHIPS)':
 C_PATH='@s9s_mb_2u_lib.s9s_mb_2u(sch_1):page229_i24@pure_quanta.q_res(chips)',
 P_PATH='@s9s_mb_2u_lib.s9s_mb_2u(sch_1):page242_i24@pure_quanta.q_res(chips)',
 PATH='I24',
 DRAWING='@S9S_MB_2U_LIB.S9S_MB_2U(SCH_1):PAGE229',
 PHYS_PAGE='242',
 XY='(-1725,1525)',
 ROT='0',
 VER='2',
 PACK_TYPE='0402LF',
 CDS_LIB='pure_quanta',
 CDS_PART_NAME='Q_RES_0402LF-10K,1%,1/16W,EMPTA',
 WATTAGE='1/16W',
 TOLERANCE='1%',
 MATERIAL='EMPTY',
 ROOM='SCM_P12V_BOM1',
 VALUE='10K',
 PRIM_FILE='./archive_libs/logical/q_res/chips/chips.prt';

PART_NAME
 R4072 'Q_RES_0402LF-10K,1%,1/16W,CHIPA':
 ROOM='E1S1_P3V3_BOM1';

SECTION_NUMBER 1
 '@S9S_MB_2U_LIB.S9S_MB_2U(SCH_1):PAGE324_I6@PURE_QUANTA.Q_RES(CHIPS)':
 C_PATH='@s9s_mb_2u_lib.s9s_mb_2u(sch_1):page324_i6@pure_quanta.q_res(chips)',
 P_PATH='@s9s_mb_2u_lib.s9s_mb_2u(sch_1):page192_i6@pure_quanta.q_res(chips)',
 PATH='I6',
 DRAWING='@S9S_MB_2U_LIB.S9S_MB_2U(SCH_1):PAGE324',
 PHYS_PAGE='192',
 XY='(-3150,-1775)',
 ROT='0',
 VER='2',
 PACK_TYPE='0402LF',
 CDS_LIB='pure_quanta',
 CDS_PART_NAME='Q_RES_0402LF-10K,1%,1/16W,CHIPA',
 WATTAGE='1/16W',
 TOLERANCE='1%',
 MATERIAL='CHIP',
 ROOM='E1S1_P3V3_BOM1',
 VALUE='10K',
 PRIM_FILE='./archive_libs/logical/q_res/chips/chips.prt';

PART_NAME
 R4073 'Q_RES_0402LF-4.7K,5%,1/16W,CHIA':;

SECTION_NUMBER 1
 '@S9S_MB_2U_LIB.S9S_MB_2U(SCH_1):PAGE324_I9@PURE_QUANTA.Q_RES(CHIPS)':
 C_PATH='@s9s_mb_2u_lib.s9s_mb_2u(sch_1):page324_i9@pure_quanta.q_res(chips)',
 P_PATH='@s9s_mb_2u_lib.s9s_mb_2u(sch_1):page192_i9@pure_quanta.q_res(chips)',
 PATH='I9',
 DRAWING='@S9S_MB_2U_LIB.S9S_MB_2U(SCH_1):PAGE324',
 PHYS_PAGE='192',
 XY='(-3025,-225)',
 ROT='0',
 VER='2',
 PACK_TYPE='0402LF',
 CDS_LIB='pure_quanta',
 CDS_PART_NAME='Q_RES_0402LF-4.7K,5%,1/16W,CHIA',
 WATTAGE='1/16W',
 TOLERANCE='5%',
 MATERIAL='CHIP',
 VALUE='4.7K',
 PRIM_FILE='./archive_libs/logical/q_res/chips/chips.prt';

PART_NAME
 R4074 'Q_RES_0402LF-10K,1%,1/16W,EMPTA':
 ROOM='E1S1_P12V_MAM_MAM_BOM1';

SECTION_NUMBER 1
 '@S9S_MB_2U_LIB.S9S_MB_2U(SCH_1):PAGE324_I22@PURE_QUANTA.Q_RES(CHIPS)':
 C_PATH='@s9s_mb_2u_lib.s9s_mb_2u(sch_1):page324_i22@pure_quanta.q_res(chips)',
 P_PATH='@s9s_mb_2u_lib.s9s_mb_2u(sch_1):page192_i22@pure_quanta.q_res(chips)',
 PATH='I22',
 DRAWING='@S9S_MB_2U_LIB.S9S_MB_2U(SCH_1):PAGE324',
 ROOM1='E1S1_P12V_MAM_TIC_BOM2',
 PHYS_PAGE='192',
 XY='(-2525,750)',
 ROT='0',
 VER='2',
 PACK_TYPE='0402LF',
 CDS_LIB='pure_quanta',
 CDS_PART_NAME='Q_RES_0402LF-10K,1%,1/16W,EMPTA',
 WATTAGE='1/16W',
 TOLERANCE='1%',
 MATERIAL='EMPTY',
 ROOM='E1S1_P12V_MAM_MAM_BOM1',
 VALUE='10K',
 PRIM_FILE='./archive_libs/logical/q_res/chips/chips.prt';

PART_NAME
 R4075 'Q_RES_0402LF-0,5%,1/16W,CHIP,CA':;

SECTION_NUMBER 1
 '@S9S_MB_2U_LIB.S9S_MB_2U(SCH_1):PAGE201_I147@PURE_QUANTA.Q_RES(CHIPS)':
 C_PATH='@s9s_mb_2u_lib.s9s_mb_2u(sch_1):page201_i147@pure_quanta.q_res(chips)',
 P_PATH='@s9s_mb_2u_lib.s9s_mb_2u(sch_1):page212_i147@pure_quanta.q_res(chips)',
 PATH='I147',
 DRAWING='@S9S_MB_2U_LIB.S9S_MB_2U(SCH_1):PAGE201',
 PHYS_PAGE='212',
 XY='(-3300,3350)',
 ROT='0',
 VER='1',
 PACK_TYPE='0402LF',
 CDS_LIB='pure_quanta',
 CDS_PART_NAME='Q_RES_0402LF-0,5%,1/16W,CHIP,CA',
 WATTAGE='1/16W',
 TOLERANCE='5%',
 MATERIAL='CHIP',
 VALUE='0',
 PRIM_FILE='./archive_libs/logical/q_res/chips/chips.prt';

PART_NAME
 R4076 'Q_RES_0402LF-0,5%,1/16W,CHIP,CA':;

SECTION_NUMBER 1
 '@S9S_MB_2U_LIB.S9S_MB_2U(SCH_1):PAGE201_I146@PURE_QUANTA.Q_RES(CHIPS)':
 C_PATH='@s9s_mb_2u_lib.s9s_mb_2u(sch_1):page201_i146@pure_quanta.q_res(chips)',
 P_PATH='@s9s_mb_2u_lib.s9s_mb_2u(sch_1):page212_i146@pure_quanta.q_res(chips)',
 PATH='I146',
 DRAWING='@S9S_MB_2U_LIB.S9S_MB_2U(SCH_1):PAGE201',
 PHYS_PAGE='212',
 XY='(-3300,3300)',
 ROT='0',
 VER='1',
 PACK_TYPE='0402LF',
 CDS_LIB='pure_quanta',
 CDS_PART_NAME='Q_RES_0402LF-0,5%,1/16W,CHIP,CA',
 WATTAGE='1/16W',
 TOLERANCE='5%',
 MATERIAL='CHIP',
 VALUE='0',
 PRIM_FILE='./archive_libs/logical/q_res/chips/chips.prt';

PART_NAME
 R4077 'Q_RES_0402LF-1,1%,1/16W,CHIP,CA':;

SECTION_NUMBER 1
 '@S9S_MB_2U_LIB.S9S_MB_2U(SCH_1):PAGE201_I102@PURE_QUANTA.Q_RES(CHIPS)':
 C_PATH='@s9s_mb_2u_lib.s9s_mb_2u(sch_1):page201_i102@pure_quanta.q_res(chips)',
 P_PATH='@s9s_mb_2u_lib.s9s_mb_2u(sch_1):page212_i102@pure_quanta.q_res(chips)',
 PATH='I102',
 DRAWING='@S9S_MB_2U_LIB.S9S_MB_2U(SCH_1):PAGE201',
 PHYS_PAGE='212',
 XY='(-1275,5200)',
 ROT='0',
 VER='1',
 PACK_TYPE='0402LF',
 CDS_LIB='pure_quanta',
 CDS_PART_NAME='Q_RES_0402LF-1,1%,1/16W,CHIP,CA',
 WATTAGE='1/16W',
 TOLERANCE='1%',
 MATERIAL='CHIP',
 VALUE='1',
 PRIM_FILE='./archive_libs/logical/q_res/chips/chips.prt';

PART_NAME
 R4078 'Q_RES_0402LF-10K,1%,1/16W,EMPTA':;

SECTION_NUMBER 1
 '@S9S_MB_2U_LIB.S9S_MB_2U(SCH_1):PAGE201_I127@PURE_QUANTA.Q_RES(CHIPS)':
 C_PATH='@s9s_mb_2u_lib.s9s_mb_2u(sch_1):page201_i127@pure_quanta.q_res(chips)',
 P_PATH='@s9s_mb_2u_lib.s9s_mb_2u(sch_1):page212_i127@pure_quanta.q_res(chips)',
 PATH='I127',
 DRAWING='@S9S_MB_2U_LIB.S9S_MB_2U(SCH_1):PAGE201',
 PHYS_PAGE='212',
 XY='(250,1475)',
 ROT='2',
 VER='2',
 PACK_TYPE='0402LF',
 CDS_LIB='pure_quanta',
 CDS_PART_NAME='Q_RES_0402LF-10K,1%,1/16W,EMPTA',
 WATTAGE='1/16W',
 TOLERANCE='1%',
 MATERIAL='EMPTY',
 VALUE='10K',
 PRIM_FILE='./archive_libs/logical/q_res/chips/chips.prt';

PART_NAME
 R4079 'Q_RES_0402LF-10K,1%,1/16W,CHIPA':;

SECTION_NUMBER 1
 '@S9S_MB_2U_LIB.S9S_MB_2U(SCH_1):PAGE201_I128@PURE_QUANTA.Q_RES(CHIPS)':
 C_PATH='@s9s_mb_2u_lib.s9s_mb_2u(sch_1):page201_i128@pure_quanta.q_res(chips)',
 P_PATH='@s9s_mb_2u_lib.s9s_mb_2u(sch_1):page212_i128@pure_quanta.q_res(chips)',
 PATH='I128',
 DRAWING='@S9S_MB_2U_LIB.S9S_MB_2U(SCH_1):PAGE201',
 PHYS_PAGE='212',
 XY='(250,1000)',
 ROT='2',
 VER='2',
 PACK_TYPE='0402LF',
 CDS_LIB='pure_quanta',
 CDS_PART_NAME='Q_RES_0402LF-10K,1%,1/16W,CHIPA',
 WATTAGE='1/16W',
 TOLERANCE='1%',
 MATERIAL='CHIP',
 VALUE='10K',
 PRIM_FILE='./archive_libs/logical/q_res/chips/chips.prt';

PART_NAME
 R4080 'Q_RES_0402LF-10K,1%,1/16W,CHIPA':;

SECTION_NUMBER 1
 '@S9S_MB_2U_LIB.S9S_MB_2U(SCH_1):PAGE201_I142@PURE_QUANTA.Q_RES(CHIPS)':
 C_PATH='@s9s_mb_2u_lib.s9s_mb_2u(sch_1):page201_i142@pure_quanta.q_res(chips)',
 P_PATH='@s9s_mb_2u_lib.s9s_mb_2u(sch_1):page212_i142@pure_quanta.q_res(chips)',
 PATH='I142',
 DRAWING='@S9S_MB_2U_LIB.S9S_MB_2U(SCH_1):PAGE201',
 PHYS_PAGE='212',
 XY='(1575,2300)',
 ROT='2',
 VER='2',
 PACK_TYPE='0402LF',
 CDS_LIB='pure_quanta',
 CDS_PART_NAME='Q_RES_0402LF-10K,1%,1/16W,CHIPA',
 WATTAGE='1/16W',
 TOLERANCE='1%',
 MATERIAL='CHIP',
 VALUE='10K',
 PRIM_FILE='./archive_libs/logical/q_res/chips/chips.prt';

PART_NAME
 R4081 'Q_RES_0402LF-10K,1%,1/16W,CHIPA':;

SECTION_NUMBER 1
 '@S9S_MB_2U_LIB.S9S_MB_2U(SCH_1):PAGE201_I135@PURE_QUANTA.Q_RES(CHIPS)':
 C_PATH='@s9s_mb_2u_lib.s9s_mb_2u(sch_1):page201_i135@pure_quanta.q_res(chips)',
 P_PATH='@s9s_mb_2u_lib.s9s_mb_2u(sch_1):page212_i135@pure_quanta.q_res(chips)',
 PATH='I135',
 DRAWING='@S9S_MB_2U_LIB.S9S_MB_2U(SCH_1):PAGE201',
 PHYS_PAGE='212',
 XY='(1575,1500)',
 ROT='2',
 VER='2',
 PACK_TYPE='0402LF',
 CDS_LIB='pure_quanta',
 CDS_PART_NAME='Q_RES_0402LF-10K,1%,1/16W,CHIPA',
 WATTAGE='1/16W',
 TOLERANCE='1%',
 MATERIAL='CHIP',
 VALUE='10K',
 PRIM_FILE='./archive_libs/logical/q_res/chips/chips.prt';

PART_NAME
 R4082 'Q_RES_0402LF-10K,1%,1/16W,EMPTA':;

SECTION_NUMBER 1
 '@S9S_MB_2U_LIB.S9S_MB_2U(SCH_1):PAGE201_I134@PURE_QUANTA.Q_RES(CHIPS)':
 C_PATH='@s9s_mb_2u_lib.s9s_mb_2u(sch_1):page201_i134@pure_quanta.q_res(chips)',
 P_PATH='@s9s_mb_2u_lib.s9s_mb_2u(sch_1):page212_i134@pure_quanta.q_res(chips)',
 PATH='I134',
 DRAWING='@S9S_MB_2U_LIB.S9S_MB_2U(SCH_1):PAGE201',
 PHYS_PAGE='212',
 XY='(1575,1025)',
 ROT='2',
 VER='2',
 PACK_TYPE='0402LF',
 CDS_LIB='pure_quanta',
 CDS_PART_NAME='Q_RES_0402LF-10K,1%,1/16W,EMPTA',
 WATTAGE='1/16W',
 TOLERANCE='1%',
 MATERIAL='EMPTY',
 VALUE='10K',
 PRIM_FILE='./archive_libs/logical/q_res/chips/chips.prt';

PART_NAME
 R4083 'Q_RES_0402LF-0,5%,1/16W,EMPTY,A':;

SECTION_NUMBER 1
 '@S9S_MB_2U_LIB.S9S_MB_2U(SCH_1):PAGE175_I274@PURE_QUANTA.Q_RES(CHIPS)':
 C_PATH='@s9s_mb_2u_lib.s9s_mb_2u(sch_1):page175_i274@pure_quanta.q_res(chips)',
 P_PATH='@s9s_mb_2u_lib.s9s_mb_2u(sch_1):page183_i274@pure_quanta.q_res(chips)',
 PATH='I274',
 DRAWING='@S9S_MB_2U_LIB.S9S_MB_2U(SCH_1):PAGE175',
 PHYS_PAGE='183',
 XY='(-2700,4000)',
 ROT='0',
 VER='1',
 PACK_TYPE='0402LF',
 CDS_LIB='pure_quanta',
 CDS_PART_NAME='Q_RES_0402LF-0,5%,1/16W,EMPTY,A',
 WATTAGE='1/16W',
 TOLERANCE='5%',
 MATERIAL='EMPTY',
 VALUE='0',
 PRIM_FILE='./archive_libs/logical/q_res/chips/chips.prt';

PART_NAME
 R4084 'Q_RES_0402LF-0,5%,1/16W,EMPTY,A':;

SECTION_NUMBER 1
 '@S9S_MB_2U_LIB.S9S_MB_2U(SCH_1):PAGE175_I275@PURE_QUANTA.Q_RES(CHIPS)':
 C_PATH='@s9s_mb_2u_lib.s9s_mb_2u(sch_1):page175_i275@pure_quanta.q_res(chips)',
 P_PATH='@s9s_mb_2u_lib.s9s_mb_2u(sch_1):page183_i275@pure_quanta.q_res(chips)',
 PATH='I275',
 DRAWING='@S9S_MB_2U_LIB.S9S_MB_2U(SCH_1):PAGE175',
 PHYS_PAGE='183',
 XY='(-2700,3900)',
 ROT='0',
 VER='1',
 PACK_TYPE='0402LF',
 CDS_LIB='pure_quanta',
 CDS_PART_NAME='Q_RES_0402LF-0,5%,1/16W,EMPTY,A',
 WATTAGE='1/16W',
 TOLERANCE='5%',
 MATERIAL='EMPTY',
 VALUE='0',
 PRIM_FILE='./archive_libs/logical/q_res/chips/chips.prt';

PART_NAME
 R4086 'Q_RES_0402LF-10K,1%,1/16W,CHIPA':;

SECTION_NUMBER 1
 '@S9S_MB_2U_LIB.S9S_MB_2U(SCH_1):PAGE312_I86@PURE_QUANTA.Q_RES(CHIPS)':
 C_PATH='@s9s_mb_2u_lib.s9s_mb_2u(sch_1):page312_i86@pure_quanta.q_res(chips)',
 P_PATH='@s9s_mb_2u_lib.s9s_mb_2u(sch_1):page215_i86@pure_quanta.q_res(chips)',
 PATH='I86',
 DRAWING='@S9S_MB_2U_LIB.S9S_MB_2U(SCH_1):PAGE312',
 PHYS_PAGE='215',
 XY='(1775,1825)',
 ROT='0',
 VER='2',
 PACK_TYPE='0402LF',
 CDS_LIB='pure_quanta',
 CDS_PART_NAME='Q_RES_0402LF-10K,1%,1/16W,CHIPA',
 WATTAGE='1/16W',
 TOLERANCE='1%',
 MATERIAL='CHIP',
 VALUE='10K',
 PRIM_FILE='./archive_libs/logical/q_res/chips/chips.prt';

PART_NAME
 R4087 'Q_RES_0402LF-33.2,1%,1/16W,CHIA':;

SECTION_NUMBER 1
 '@S9S_MB_2U_LIB.S9S_MB_2U(SCH_1):PAGE227_I28@PURE_QUANTA.Q_RES(CHIPS)':
 C_PATH='@s9s_mb_2u_lib.s9s_mb_2u(sch_1):page227_i28@pure_quanta.q_res(chips)',
 P_PATH='@s9s_mb_2u_lib.s9s_mb_2u(sch_1):page240_i28@pure_quanta.q_res(chips)',
 PATH='I28',
 DRAWING='@S9S_MB_2U_LIB.S9S_MB_2U(SCH_1):PAGE227',
 PHYS_PAGE='240',
 XY='(-13075,-925)',
 ROT='0',
 VER='1',
 PACK_TYPE='0402LF',
 LOCATION='R4087',
 CDS_LIB='pure_quanta',
 CDS_PART_NAME='Q_RES_0402LF-33.2,1%,1/16W,CHIA',
 WATTAGE='1/16W',
 TOLERANCE='1%',
 MATERIAL='CHIP',
 VALUE='33.2',
 PRIM_FILE='./archive_libs/logical/q_res/chips/chips.prt';

PART_NAME
 R4088 'Q_RES_0402LF-0,5%,1/16W,CHIP,CA':;

SECTION_NUMBER 1
 '@S9S_MB_2U_LIB.S9S_MB_2U(SCH_1):PAGE313_I166@PURE_QUANTA.Q_RES(CHIPS)':
 C_PATH='@s9s_mb_2u_lib.s9s_mb_2u(sch_1):page313_i166@pure_quanta.q_res(chips)',
 P_PATH='@s9s_mb_2u_lib.s9s_mb_2u(sch_1):page214_i166@pure_quanta.q_res(chips)',
 PATH='I166',
 DRAWING='@S9S_MB_2U_LIB.S9S_MB_2U(SCH_1):PAGE313',
 PHYS_PAGE='214',
 XY='(2675,-2950)',
 ROT='0',
 VER='1',
 PACK_TYPE='0402LF',
 CDS_LIB='pure_quanta',
 CDS_PART_NAME='Q_RES_0402LF-0,5%,1/16W,CHIP,CA',
 WATTAGE='1/16W',
 TOLERANCE='5%',
 MATERIAL='CHIP',
 VALUE='0',
 PRIM_FILE='./archive_libs/logical/q_res/chips/chips.prt';

PART_NAME
 R4089 'Q_RES_0402LF-33.2,1%,1/16W,CHIA':;

SECTION_NUMBER 1
 '@S9S_MB_2U_LIB.S9S_MB_2U(SCH_1):PAGE14_I128@PURE_QUANTA.Q_RES(CHIPS)':
 C_PATH='@s9s_mb_2u_lib.s9s_mb_2u(sch_1):page14_i128@pure_quanta.q_res(chips)',
 P_PATH='@s9s_mb_2u_lib.s9s_mb_2u(sch_1):page14_i128@pure_quanta.q_res(chips)',
 PATH='I128',
 DRAWING='@S9S_MB_2U_LIB.S9S_MB_2U(SCH_1):PAGE14',
 PHYS_PAGE='14',
 XY='(-1600,-725)',
 ROT='0',
 VER='1',
 PACK_TYPE='0402LF',
 CDS_LIB='pure_quanta',
 CDS_PART_NAME='Q_RES_0402LF-33.2,1%,1/16W,CHIA',
 WATTAGE='1/16W',
 TOLERANCE='1%',
 MATERIAL='CHIP',
 VALUE='33.2',
 PRIM_FILE='./archive_libs/logical/q_res/chips/chips.prt';

PART_NAME
 R4090 'Q_RES_0402LF-4.7K,1%,1/16W,CHIA':;

SECTION_NUMBER 1
 '@S9S_MB_2U_LIB.S9S_MB_2U(SCH_1):PAGE163_I124@PURE_QUANTA.Q_RES(CHIPS)':
 C_PATH='@s9s_mb_2u_lib.s9s_mb_2u(sch_1):page163_i124@pure_quanta.q_res(chips)',
 P_PATH='@s9s_mb_2u_lib.s9s_mb_2u(sch_1):page172_i124@pure_quanta.q_res(chips)',
 PATH='I124',
 DRAWING='@S9S_MB_2U_LIB.S9S_MB_2U(SCH_1):PAGE163',
 PHYS_PAGE='172',
 XY='(2500,-1275)',
 ROT='0',
 VER='2',
 PACK_TYPE='0402LF',
 CDS_LIB='pure_quanta',
 CDS_PART_NAME='Q_RES_0402LF-4.7K,1%,1/16W,CHIA',
 WATTAGE='1/16W',
 TOLERANCE='1%',
 MATERIAL='CHIP',
 VALUE='4.7K',
 PRIM_FILE='./archive_libs/logical/q_res/chips/chips.prt';

PART_NAME
 R4091 'Q_RES_0402LF-4.7K,1%,1/16W,CHIA':;

SECTION_NUMBER 1
 '@S9S_MB_2U_LIB.S9S_MB_2U(SCH_1):PAGE163_I122@PURE_QUANTA.Q_RES(CHIPS)':
 C_PATH='@s9s_mb_2u_lib.s9s_mb_2u(sch_1):page163_i122@pure_quanta.q_res(chips)',
 P_PATH='@s9s_mb_2u_lib.s9s_mb_2u(sch_1):page172_i122@pure_quanta.q_res(chips)',
 PATH='I122',
 DRAWING='@S9S_MB_2U_LIB.S9S_MB_2U(SCH_1):PAGE163',
 PHYS_PAGE='172',
 XY='(2575,-3425)',
 ROT='0',
 VER='2',
 PACK_TYPE='0402LF',
 CDS_LIB='pure_quanta',
 CDS_PART_NAME='Q_RES_0402LF-4.7K,1%,1/16W,CHIA',
 WATTAGE='1/16W',
 TOLERANCE='1%',
 MATERIAL='CHIP',
 VALUE='4.7K',
 PRIM_FILE='./archive_libs/logical/q_res/chips/chips.prt';

PART_NAME
 R4092 'Q_RES_0402LF-4.7K,1%,1/16W,CHIA':;

SECTION_NUMBER 1
 '@S9S_MB_2U_LIB.S9S_MB_2U(SCH_1):PAGE163_I126@PURE_QUANTA.Q_RES(CHIPS)':
 C_PATH='@s9s_mb_2u_lib.s9s_mb_2u(sch_1):page163_i126@pure_quanta.q_res(chips)',
 P_PATH='@s9s_mb_2u_lib.s9s_mb_2u(sch_1):page172_i126@pure_quanta.q_res(chips)',
 PATH='I126',
 DRAWING='@S9S_MB_2U_LIB.S9S_MB_2U(SCH_1):PAGE163',
 PHYS_PAGE='172',
 XY='(3075,825)',
 ROT='0',
 VER='2',
 PACK_TYPE='0402LF',
 CDS_LIB='pure_quanta',
 CDS_PART_NAME='Q_RES_0402LF-4.7K,1%,1/16W,CHIA',
 WATTAGE='1/16W',
 TOLERANCE='1%',
 MATERIAL='CHIP',
 VALUE='4.7K',
 PRIM_FILE='./archive_libs/logical/q_res/chips/chips.prt';

PART_NAME
 R4093 'Q_RES_0402LF-4.7K,1%,1/16W,CHIA':;

SECTION_NUMBER 1
 '@S9S_MB_2U_LIB.S9S_MB_2U(SCH_1):PAGE295_I149@PURE_QUANTA.Q_RES(CHIPS)':
 C_PATH='@s9s_mb_2u_lib.s9s_mb_2u(sch_1):page295_i149@pure_quanta.q_res(chips)',
 P_PATH='@s9s_mb_2u_lib.s9s_mb_2u(sch_1):page171_i149@pure_quanta.q_res(chips)',
 PATH='I149',
 DRAWING='@S9S_MB_2U_LIB.S9S_MB_2U(SCH_1):PAGE295',
 PHYS_PAGE='171',
 XY='(4125,1175)',
 ROT='0',
 VER='2',
 PACK_TYPE='0402LF',
 CDS_LIB='pure_quanta',
 CDS_PART_NAME='Q_RES_0402LF-4.7K,1%,1/16W,CHIA',
 WATTAGE='1/16W',
 TOLERANCE='1%',
 MATERIAL='CHIP',
 VALUE='4.7K',
 PRIM_FILE='./archive_libs/logical/q_res/chips/chips.prt';

PART_NAME
 R4094 'Q_RES_0402LF-4.7K,1%,1/16W,CHIA':;

SECTION_NUMBER 1
 '@S9S_MB_2U_LIB.S9S_MB_2U(SCH_1):PAGE295_I151@PURE_QUANTA.Q_RES(CHIPS)':
 C_PATH='@s9s_mb_2u_lib.s9s_mb_2u(sch_1):page295_i151@pure_quanta.q_res(chips)',
 P_PATH='@s9s_mb_2u_lib.s9s_mb_2u(sch_1):page171_i151@pure_quanta.q_res(chips)',
 PATH='I151',
 DRAWING='@S9S_MB_2U_LIB.S9S_MB_2U(SCH_1):PAGE295',
 PHYS_PAGE='171',
 XY='(4150,3775)',
 ROT='0',
 VER='2',
 PACK_TYPE='0402LF',
 CDS_LIB='pure_quanta',
 CDS_PART_NAME='Q_RES_0402LF-4.7K,1%,1/16W,CHIA',
 WATTAGE='1/16W',
 TOLERANCE='1%',
 MATERIAL='CHIP',
 VALUE='4.7K',
 PRIM_FILE='./archive_libs/logical/q_res/chips/chips.prt';

PART_NAME
 R4095 'Q_RES_0402LF-10K,1%,1/16W,CHIPA':;

SECTION_NUMBER 1
 '@S9S_MB_2U_LIB.S9S_MB_2U(SCH_1):PAGE175_I284@PURE_QUANTA.Q_RES(CHIPS)':
 C_PATH='@s9s_mb_2u_lib.s9s_mb_2u(sch_1):page175_i284@pure_quanta.q_res(chips)',
 P_PATH='@s9s_mb_2u_lib.s9s_mb_2u(sch_1):page183_i284@pure_quanta.q_res(chips)',
 PATH='I284',
 DRAWING='@S9S_MB_2U_LIB.S9S_MB_2U(SCH_1):PAGE175',
 PHYS_PAGE='183',
 XY='(-1425,-600)',
 ROT='0',
 VER='1',
 PACK_TYPE='0402LF',
 CDS_LIB='pure_quanta',
 CDS_PART_NAME='Q_RES_0402LF-10K,1%,1/16W,CHIPA',
 WATTAGE='1/16W',
 TOLERANCE='1%',
 MATERIAL='CHIP',
 VALUE='10K',
 PRIM_FILE='./archive_libs/logical/q_res/chips/chips.prt';

PART_NAME
 R4096 'Q_RES_0402LF-10K,1%,1/16W,CHIPA':;

SECTION_NUMBER 1
 '@S9S_MB_2U_LIB.S9S_MB_2U(SCH_1):PAGE175_I285@PURE_QUANTA.Q_RES(CHIPS)':
 C_PATH='@s9s_mb_2u_lib.s9s_mb_2u(sch_1):page175_i285@pure_quanta.q_res(chips)',
 P_PATH='@s9s_mb_2u_lib.s9s_mb_2u(sch_1):page183_i285@pure_quanta.q_res(chips)',
 PATH='I285',
 DRAWING='@S9S_MB_2U_LIB.S9S_MB_2U(SCH_1):PAGE175',
 PHYS_PAGE='183',
 XY='(-1425,-650)',
 ROT='0',
 VER='1',
 PACK_TYPE='0402LF',
 CDS_LIB='pure_quanta',
 CDS_PART_NAME='Q_RES_0402LF-10K,1%,1/16W,CHIPA',
 WATTAGE='1/16W',
 TOLERANCE='1%',
 MATERIAL='CHIP',
 VALUE='10K',
 PRIM_FILE='./archive_libs/logical/q_res/chips/chips.prt';

PART_NAME
 R4097 'Q_RES_0402LF-10K,1%,1/16W,CHIPA':;

SECTION_NUMBER 1
 '@S9S_MB_2U_LIB.S9S_MB_2U(SCH_1):PAGE175_I286@PURE_QUANTA.Q_RES(CHIPS)':
 C_PATH='@s9s_mb_2u_lib.s9s_mb_2u(sch_1):page175_i286@pure_quanta.q_res(chips)',
 P_PATH='@s9s_mb_2u_lib.s9s_mb_2u(sch_1):page183_i286@pure_quanta.q_res(chips)',
 PATH='I286',
 DRAWING='@S9S_MB_2U_LIB.S9S_MB_2U(SCH_1):PAGE175',
 PHYS_PAGE='183',
 XY='(-1425,-700)',
 ROT='0',
 VER='1',
 PACK_TYPE='0402LF',
 CDS_LIB='pure_quanta',
 CDS_PART_NAME='Q_RES_0402LF-10K,1%,1/16W,CHIPA',
 WATTAGE='1/16W',
 TOLERANCE='1%',
 MATERIAL='CHIP',
 VALUE='10K',
 PRIM_FILE='./archive_libs/logical/q_res/chips/chips.prt';

PART_NAME
 R4098 'Q_RES_0402LF-10K,1%,1/16W,CHIPA':;

SECTION_NUMBER 1
 '@S9S_MB_2U_LIB.S9S_MB_2U(SCH_1):PAGE175_I287@PURE_QUANTA.Q_RES(CHIPS)':
 C_PATH='@s9s_mb_2u_lib.s9s_mb_2u(sch_1):page175_i287@pure_quanta.q_res(chips)',
 P_PATH='@s9s_mb_2u_lib.s9s_mb_2u(sch_1):page183_i287@pure_quanta.q_res(chips)',
 PATH='I287',
 DRAWING='@S9S_MB_2U_LIB.S9S_MB_2U(SCH_1):PAGE175',
 PHYS_PAGE='183',
 XY='(-1425,-750)',
 ROT='0',
 VER='1',
 PACK_TYPE='0402LF',
 CDS_LIB='pure_quanta',
 CDS_PART_NAME='Q_RES_0402LF-10K,1%,1/16W,CHIPA',
 WATTAGE='1/16W',
 TOLERANCE='1%',
 MATERIAL='CHIP',
 VALUE='10K',
 PRIM_FILE='./archive_libs/logical/q_res/chips/chips.prt';

PART_NAME
 R4099 'Q_RES_0402LF-10K,1%,1/16W,CHIPA':;

SECTION_NUMBER 1
 '@S9S_MB_2U_LIB.S9S_MB_2U(SCH_1):PAGE175_I288@PURE_QUANTA.Q_RES(CHIPS)':
 C_PATH='@s9s_mb_2u_lib.s9s_mb_2u(sch_1):page175_i288@pure_quanta.q_res(chips)',
 P_PATH='@s9s_mb_2u_lib.s9s_mb_2u(sch_1):page183_i288@pure_quanta.q_res(chips)',
 PATH='I288',
 DRAWING='@S9S_MB_2U_LIB.S9S_MB_2U(SCH_1):PAGE175',
 PHYS_PAGE='183',
 XY='(-1425,-800)',
 ROT='0',
 VER='1',
 PACK_TYPE='0402LF',
 CDS_LIB='pure_quanta',
 CDS_PART_NAME='Q_RES_0402LF-10K,1%,1/16W,CHIPA',
 WATTAGE='1/16W',
 TOLERANCE='1%',
 MATERIAL='CHIP',
 VALUE='10K',
 PRIM_FILE='./archive_libs/logical/q_res/chips/chips.prt';

PART_NAME
 R4100 'Q_RES_0402LF-10K,1%,1/16W,CHIPA':;

SECTION_NUMBER 1
 '@S9S_MB_2U_LIB.S9S_MB_2U(SCH_1):PAGE175_I300@PURE_QUANTA.Q_RES(CHIPS)':
 C_PATH='@s9s_mb_2u_lib.s9s_mb_2u(sch_1):page175_i300@pure_quanta.q_res(chips)',
 P_PATH='@s9s_mb_2u_lib.s9s_mb_2u(sch_1):page183_i300@pure_quanta.q_res(chips)',
 PATH='I300',
 DRAWING='@S9S_MB_2U_LIB.S9S_MB_2U(SCH_1):PAGE175',
 PHYS_PAGE='183',
 XY='(-1425,-850)',
 ROT='0',
 VER='1',
 PACK_TYPE='0402LF',
 CDS_LIB='pure_quanta',
 CDS_PART_NAME='Q_RES_0402LF-10K,1%,1/16W,CHIPA',
 WATTAGE='1/16W',
 TOLERANCE='1%',
 MATERIAL='CHIP',
 VALUE='10K',
 PRIM_FILE='./archive_libs/logical/q_res/chips/chips.prt';

PART_NAME
 R4101 'Q_RES_0402LF-10K,1%,1/16W,CHIPA':;

SECTION_NUMBER 1
 '@S9S_MB_2U_LIB.S9S_MB_2U(SCH_1):PAGE175_I299@PURE_QUANTA.Q_RES(CHIPS)':
 C_PATH='@s9s_mb_2u_lib.s9s_mb_2u(sch_1):page175_i299@pure_quanta.q_res(chips)',
 P_PATH='@s9s_mb_2u_lib.s9s_mb_2u(sch_1):page183_i299@pure_quanta.q_res(chips)',
 PATH='I299',
 DRAWING='@S9S_MB_2U_LIB.S9S_MB_2U(SCH_1):PAGE175',
 PHYS_PAGE='183',
 XY='(-1425,-900)',
 ROT='0',
 VER='1',
 PACK_TYPE='0402LF',
 CDS_LIB='pure_quanta',
 CDS_PART_NAME='Q_RES_0402LF-10K,1%,1/16W,CHIPA',
 WATTAGE='1/16W',
 TOLERANCE='1%',
 MATERIAL='CHIP',
 VALUE='10K',
 PRIM_FILE='./archive_libs/logical/q_res/chips/chips.prt';

PART_NAME
 R4102 'Q_RES_0402LF-10K,1%,1/16W,CHIPA':;

SECTION_NUMBER 1
 '@S9S_MB_2U_LIB.S9S_MB_2U(SCH_1):PAGE175_I298@PURE_QUANTA.Q_RES(CHIPS)':
 C_PATH='@s9s_mb_2u_lib.s9s_mb_2u(sch_1):page175_i298@pure_quanta.q_res(chips)',
 P_PATH='@s9s_mb_2u_lib.s9s_mb_2u(sch_1):page183_i298@pure_quanta.q_res(chips)',
 PATH='I298',
 DRAWING='@S9S_MB_2U_LIB.S9S_MB_2U(SCH_1):PAGE175',
 PHYS_PAGE='183',
 XY='(-1425,-950)',
 ROT='0',
 VER='1',
 PACK_TYPE='0402LF',
 CDS_LIB='pure_quanta',
 CDS_PART_NAME='Q_RES_0402LF-10K,1%,1/16W,CHIPA',
 WATTAGE='1/16W',
 TOLERANCE='1%',
 MATERIAL='CHIP',
 VALUE='10K',
 PRIM_FILE='./archive_libs/logical/q_res/chips/chips.prt';

PART_NAME
 R4103 'Q_RES_0402LF-10K,1%,1/16W,CHIPA':;

SECTION_NUMBER 1
 '@S9S_MB_2U_LIB.S9S_MB_2U(SCH_1):PAGE176_I186@PURE_QUANTA.Q_RES(CHIPS)':
 C_PATH='@s9s_mb_2u_lib.s9s_mb_2u(sch_1):page176_i186@pure_quanta.q_res(chips)',
 P_PATH='@s9s_mb_2u_lib.s9s_mb_2u(sch_1):page184_i186@pure_quanta.q_res(chips)',
 PATH='I186',
 DRAWING='@S9S_MB_2U_LIB.S9S_MB_2U(SCH_1):PAGE176',
 PHYS_PAGE='184',
 XY='(1925,725)',
 ROT='0',
 VER='1',
 PACK_TYPE='0402LF',
 CDS_LIB='pure_quanta',
 CDS_PART_NAME='Q_RES_0402LF-10K,1%,1/16W,CHIPA',
 WATTAGE='1/16W',
 TOLERANCE='1%',
 MATERIAL='CHIP',
 VALUE='10K',
 PRIM_FILE='./archive_libs/logical/q_res/chips/chips.prt';

PART_NAME
 R4104 'Q_RES_0402LF-10K,1%,1/16W,CHIPA':;

SECTION_NUMBER 1
 '@S9S_MB_2U_LIB.S9S_MB_2U(SCH_1):PAGE176_I185@PURE_QUANTA.Q_RES(CHIPS)':
 C_PATH='@s9s_mb_2u_lib.s9s_mb_2u(sch_1):page176_i185@pure_quanta.q_res(chips)',
 P_PATH='@s9s_mb_2u_lib.s9s_mb_2u(sch_1):page184_i185@pure_quanta.q_res(chips)',
 PATH='I185',
 DRAWING='@S9S_MB_2U_LIB.S9S_MB_2U(SCH_1):PAGE176',
 PHYS_PAGE='184',
 XY='(1925,625)',
 ROT='0',
 VER='1',
 PACK_TYPE='0402LF',
 CDS_LIB='pure_quanta',
 CDS_PART_NAME='Q_RES_0402LF-10K,1%,1/16W,CHIPA',
 WATTAGE='1/16W',
 TOLERANCE='1%',
 MATERIAL='CHIP',
 VALUE='10K',
 PRIM_FILE='./archive_libs/logical/q_res/chips/chips.prt';

PART_NAME
 R4105 'Q_RES_0402LF-10K,1%,1/16W,CHIPA':;

SECTION_NUMBER 1
 '@S9S_MB_2U_LIB.S9S_MB_2U(SCH_1):PAGE176_I183@PURE_QUANTA.Q_RES(CHIPS)':
 C_PATH='@s9s_mb_2u_lib.s9s_mb_2u(sch_1):page176_i183@pure_quanta.q_res(chips)',
 P_PATH='@s9s_mb_2u_lib.s9s_mb_2u(sch_1):page184_i183@pure_quanta.q_res(chips)',
 PATH='I183',
 DRAWING='@S9S_MB_2U_LIB.S9S_MB_2U(SCH_1):PAGE176',
 PHYS_PAGE='184',
 XY='(1925,525)',
 ROT='0',
 VER='1',
 PACK_TYPE='0402LF',
 CDS_LIB='pure_quanta',
 CDS_PART_NAME='Q_RES_0402LF-10K,1%,1/16W,CHIPA',
 WATTAGE='1/16W',
 TOLERANCE='1%',
 MATERIAL='CHIP',
 VALUE='10K',
 PRIM_FILE='./archive_libs/logical/q_res/chips/chips.prt';

PART_NAME
 R4106 'Q_RES_0402LF-10K,1%,1/16W,CHIPA':;

SECTION_NUMBER 1
 '@S9S_MB_2U_LIB.S9S_MB_2U(SCH_1):PAGE176_I184@PURE_QUANTA.Q_RES(CHIPS)':
 C_PATH='@s9s_mb_2u_lib.s9s_mb_2u(sch_1):page176_i184@pure_quanta.q_res(chips)',
 P_PATH='@s9s_mb_2u_lib.s9s_mb_2u(sch_1):page184_i184@pure_quanta.q_res(chips)',
 PATH='I184',
 DRAWING='@S9S_MB_2U_LIB.S9S_MB_2U(SCH_1):PAGE176',
 PHYS_PAGE='184',
 XY='(1925,425)',
 ROT='0',
 VER='1',
 PACK_TYPE='0402LF',
 CDS_LIB='pure_quanta',
 CDS_PART_NAME='Q_RES_0402LF-10K,1%,1/16W,CHIPA',
 WATTAGE='1/16W',
 TOLERANCE='1%',
 MATERIAL='CHIP',
 VALUE='10K',
 PRIM_FILE='./archive_libs/logical/q_res/chips/chips.prt';

PART_NAME
 R4107 'Q_RES_0402LF-10K,1%,1/16W,CHIPA':;

SECTION_NUMBER 1
 '@S9S_MB_2U_LIB.S9S_MB_2U(SCH_1):PAGE176_I197@PURE_QUANTA.Q_RES(CHIPS)':
 C_PATH='@s9s_mb_2u_lib.s9s_mb_2u(sch_1):page176_i197@pure_quanta.q_res(chips)',
 P_PATH='@s9s_mb_2u_lib.s9s_mb_2u(sch_1):page184_i197@pure_quanta.q_res(chips)',
 PATH='I197',
 DRAWING='@S9S_MB_2U_LIB.S9S_MB_2U(SCH_1):PAGE176',
 PHYS_PAGE='184',
 XY='(1925,325)',
 ROT='0',
 VER='1',
 PACK_TYPE='0402LF',
 CDS_LIB='pure_quanta',
 CDS_PART_NAME='Q_RES_0402LF-10K,1%,1/16W,CHIPA',
 WATTAGE='1/16W',
 TOLERANCE='1%',
 MATERIAL='CHIP',
 VALUE='10K',
 PRIM_FILE='./archive_libs/logical/q_res/chips/chips.prt';

PART_NAME
 R4108 'Q_RES_0402LF-10K,1%,1/16W,CHIPA':;

SECTION_NUMBER 1
 '@S9S_MB_2U_LIB.S9S_MB_2U(SCH_1):PAGE176_I196@PURE_QUANTA.Q_RES(CHIPS)':
 C_PATH='@s9s_mb_2u_lib.s9s_mb_2u(sch_1):page176_i196@pure_quanta.q_res(chips)',
 P_PATH='@s9s_mb_2u_lib.s9s_mb_2u(sch_1):page184_i196@pure_quanta.q_res(chips)',
 PATH='I196',
 DRAWING='@S9S_MB_2U_LIB.S9S_MB_2U(SCH_1):PAGE176',
 PHYS_PAGE='184',
 XY='(1925,225)',
 ROT='0',
 VER='1',
 PACK_TYPE='0402LF',
 CDS_LIB='pure_quanta',
 CDS_PART_NAME='Q_RES_0402LF-10K,1%,1/16W,CHIPA',
 WATTAGE='1/16W',
 TOLERANCE='1%',
 MATERIAL='CHIP',
 VALUE='10K',
 PRIM_FILE='./archive_libs/logical/q_res/chips/chips.prt';

PART_NAME
 R4109 'Q_RES_0402LF-10K,1%,1/16W,CHIPA':;

SECTION_NUMBER 1
 '@S9S_MB_2U_LIB.S9S_MB_2U(SCH_1):PAGE176_I195@PURE_QUANTA.Q_RES(CHIPS)':
 C_PATH='@s9s_mb_2u_lib.s9s_mb_2u(sch_1):page176_i195@pure_quanta.q_res(chips)',
 P_PATH='@s9s_mb_2u_lib.s9s_mb_2u(sch_1):page184_i195@pure_quanta.q_res(chips)',
 PATH='I195',
 DRAWING='@S9S_MB_2U_LIB.S9S_MB_2U(SCH_1):PAGE176',
 PHYS_PAGE='184',
 XY='(1925,125)',
 ROT='0',
 VER='1',
 PACK_TYPE='0402LF',
 CDS_LIB='pure_quanta',
 CDS_PART_NAME='Q_RES_0402LF-10K,1%,1/16W,CHIPA',
 WATTAGE='1/16W',
 TOLERANCE='1%',
 MATERIAL='CHIP',
 VALUE='10K',
 PRIM_FILE='./archive_libs/logical/q_res/chips/chips.prt';

PART_NAME
 R4110 'Q_RES_0402LF-10K,1%,1/16W,CHIPA':;

SECTION_NUMBER 1
 '@S9S_MB_2U_LIB.S9S_MB_2U(SCH_1):PAGE176_I202@PURE_QUANTA.Q_RES(CHIPS)':
 C_PATH='@s9s_mb_2u_lib.s9s_mb_2u(sch_1):page176_i202@pure_quanta.q_res(chips)',
 P_PATH='@s9s_mb_2u_lib.s9s_mb_2u(sch_1):page184_i202@pure_quanta.q_res(chips)',
 PATH='I202',
 DRAWING='@S9S_MB_2U_LIB.S9S_MB_2U(SCH_1):PAGE176',
 PHYS_PAGE='184',
 XY='(1925,25)',
 ROT='0',
 VER='1',
 PACK_TYPE='0402LF',
 CDS_LIB='pure_quanta',
 CDS_PART_NAME='Q_RES_0402LF-10K,1%,1/16W,CHIPA',
 WATTAGE='1/16W',
 TOLERANCE='1%',
 MATERIAL='CHIP',
 VALUE='10K',
 PRIM_FILE='./archive_libs/logical/q_res/chips/chips.prt';

PART_NAME
 R4111 'Q_RES_0402LF-10K,1%,1/16W,CHIPA':;

SECTION_NUMBER 1
 '@S9S_MB_2U_LIB.S9S_MB_2U(SCH_1):PAGE176_I204@PURE_QUANTA.Q_RES(CHIPS)':
 C_PATH='@s9s_mb_2u_lib.s9s_mb_2u(sch_1):page176_i204@pure_quanta.q_res(chips)',
 P_PATH='@s9s_mb_2u_lib.s9s_mb_2u(sch_1):page184_i204@pure_quanta.q_res(chips)',
 PATH='I204',
 DRAWING='@S9S_MB_2U_LIB.S9S_MB_2U(SCH_1):PAGE176',
 PHYS_PAGE='184',
 XY='(1925,-75)',
 ROT='0',
 VER='1',
 PACK_TYPE='0402LF',
 CDS_LIB='pure_quanta',
 CDS_PART_NAME='Q_RES_0402LF-10K,1%,1/16W,CHIPA',
 WATTAGE='1/16W',
 TOLERANCE='1%',
 MATERIAL='CHIP',
 VALUE='10K',
 PRIM_FILE='./archive_libs/logical/q_res/chips/chips.prt';

PART_NAME
 R4112 'Q_RES_0402LF-10K,1%,1/16W,CHIPA':;

SECTION_NUMBER 1
 '@S9S_MB_2U_LIB.S9S_MB_2U(SCH_1):PAGE176_I203@PURE_QUANTA.Q_RES(CHIPS)':
 C_PATH='@s9s_mb_2u_lib.s9s_mb_2u(sch_1):page176_i203@pure_quanta.q_res(chips)',
 P_PATH='@s9s_mb_2u_lib.s9s_mb_2u(sch_1):page184_i203@pure_quanta.q_res(chips)',
 PATH='I203',
 DRAWING='@S9S_MB_2U_LIB.S9S_MB_2U(SCH_1):PAGE176',
 PHYS_PAGE='184',
 XY='(1925,-175)',
 ROT='0',
 VER='1',
 PACK_TYPE='0402LF',
 CDS_LIB='pure_quanta',
 CDS_PART_NAME='Q_RES_0402LF-10K,1%,1/16W,CHIPA',
 WATTAGE='1/16W',
 TOLERANCE='1%',
 MATERIAL='CHIP',
 VALUE='10K',
 PRIM_FILE='./archive_libs/logical/q_res/chips/chips.prt';

PART_NAME
 R4113 'Q_RES_0402LF-10K,1%,1/16W,CHIPA':;

SECTION_NUMBER 1
 '@S9S_MB_2U_LIB.S9S_MB_2U(SCH_1):PAGE176_I206@PURE_QUANTA.Q_RES(CHIPS)':
 C_PATH='@s9s_mb_2u_lib.s9s_mb_2u(sch_1):page176_i206@pure_quanta.q_res(chips)',
 P_PATH='@s9s_mb_2u_lib.s9s_mb_2u(sch_1):page184_i206@pure_quanta.q_res(chips)',
 PATH='I206',
 DRAWING='@S9S_MB_2U_LIB.S9S_MB_2U(SCH_1):PAGE176',
 PHYS_PAGE='184',
 XY='(1925,-275)',
 ROT='0',
 VER='1',
 PACK_TYPE='0402LF',
 CDS_LIB='pure_quanta',
 CDS_PART_NAME='Q_RES_0402LF-10K,1%,1/16W,CHIPA',
 WATTAGE='1/16W',
 TOLERANCE='1%',
 MATERIAL='CHIP',
 VALUE='10K',
 PRIM_FILE='./archive_libs/logical/q_res/chips/chips.prt';

PART_NAME
 R4114 'Q_RES_0402LF-10K,1%,1/16W,CHIPA':;

SECTION_NUMBER 1
 '@S9S_MB_2U_LIB.S9S_MB_2U(SCH_1):PAGE176_I205@PURE_QUANTA.Q_RES(CHIPS)':
 C_PATH='@s9s_mb_2u_lib.s9s_mb_2u(sch_1):page176_i205@pure_quanta.q_res(chips)',
 P_PATH='@s9s_mb_2u_lib.s9s_mb_2u(sch_1):page184_i205@pure_quanta.q_res(chips)',
 PATH='I205',
 DRAWING='@S9S_MB_2U_LIB.S9S_MB_2U(SCH_1):PAGE176',
 PHYS_PAGE='184',
 XY='(1925,-375)',
 ROT='0',
 VER='1',
 PACK_TYPE='0402LF',
 CDS_LIB='pure_quanta',
 CDS_PART_NAME='Q_RES_0402LF-10K,1%,1/16W,CHIPA',
 WATTAGE='1/16W',
 TOLERANCE='1%',
 MATERIAL='CHIP',
 VALUE='10K',
 PRIM_FILE='./archive_libs/logical/q_res/chips/chips.prt';

PART_NAME
 R4115 'Q_RES_0402LF-10K,1%,1/16W,CHIPA':;

SECTION_NUMBER 1
 '@S9S_MB_2U_LIB.S9S_MB_2U(SCH_1):PAGE176_I201@PURE_QUANTA.Q_RES(CHIPS)':
 C_PATH='@s9s_mb_2u_lib.s9s_mb_2u(sch_1):page176_i201@pure_quanta.q_res(chips)',
 P_PATH='@s9s_mb_2u_lib.s9s_mb_2u(sch_1):page184_i201@pure_quanta.q_res(chips)',
 PATH='I201',
 DRAWING='@S9S_MB_2U_LIB.S9S_MB_2U(SCH_1):PAGE176',
 PHYS_PAGE='184',
 XY='(1925,-475)',
 ROT='0',
 VER='1',
 PACK_TYPE='0402LF',
 CDS_LIB='pure_quanta',
 CDS_PART_NAME='Q_RES_0402LF-10K,1%,1/16W,CHIPA',
 WATTAGE='1/16W',
 TOLERANCE='1%',
 MATERIAL='CHIP',
 VALUE='10K',
 PRIM_FILE='./archive_libs/logical/q_res/chips/chips.prt';

PART_NAME
 R4116 'Q_RES_0402LF-10K,1%,1/16W,CHIPA':;

SECTION_NUMBER 1
 '@S9S_MB_2U_LIB.S9S_MB_2U(SCH_1):PAGE176_I207@PURE_QUANTA.Q_RES(CHIPS)':
 C_PATH='@s9s_mb_2u_lib.s9s_mb_2u(sch_1):page176_i207@pure_quanta.q_res(chips)',
 P_PATH='@s9s_mb_2u_lib.s9s_mb_2u(sch_1):page184_i207@pure_quanta.q_res(chips)',
 PATH='I207',
 DRAWING='@S9S_MB_2U_LIB.S9S_MB_2U(SCH_1):PAGE176',
 PHYS_PAGE='184',
 XY='(1925,-575)',
 ROT='0',
 VER='1',
 PACK_TYPE='0402LF',
 CDS_LIB='pure_quanta',
 CDS_PART_NAME='Q_RES_0402LF-10K,1%,1/16W,CHIPA',
 WATTAGE='1/16W',
 TOLERANCE='1%',
 MATERIAL='CHIP',
 VALUE='10K',
 PRIM_FILE='./archive_libs/logical/q_res/chips/chips.prt';

PART_NAME
 R4117 'Q_RES_0402LF-10K,1%,1/16W,CHIPA':;

SECTION_NUMBER 1
 '@S9S_MB_2U_LIB.S9S_MB_2U(SCH_1):PAGE176_I209@PURE_QUANTA.Q_RES(CHIPS)':
 C_PATH='@s9s_mb_2u_lib.s9s_mb_2u(sch_1):page176_i209@pure_quanta.q_res(chips)',
 P_PATH='@s9s_mb_2u_lib.s9s_mb_2u(sch_1):page184_i209@pure_quanta.q_res(chips)',
 PATH='I209',
 DRAWING='@S9S_MB_2U_LIB.S9S_MB_2U(SCH_1):PAGE176',
 PHYS_PAGE='184',
 XY='(1925,-675)',
 ROT='0',
 VER='1',
 PACK_TYPE='0402LF',
 CDS_LIB='pure_quanta',
 CDS_PART_NAME='Q_RES_0402LF-10K,1%,1/16W,CHIPA',
 WATTAGE='1/16W',
 TOLERANCE='1%',
 MATERIAL='CHIP',
 VALUE='10K',
 PRIM_FILE='./archive_libs/logical/q_res/chips/chips.prt';

PART_NAME
 R4118 'Q_RES_0402LF-10,1%,1/16W,CHIP,A':;

SECTION_NUMBER 1
 '@S9S_MB_2U_LIB.S9S_MB_2U(SCH_1):PAGE190_I105@PURE_QUANTA.Q_RES(CHIPS)':
 C_PATH='@s9s_mb_2u_lib.s9s_mb_2u(sch_1):page190_i105@pure_quanta.q_res(chips)',
 P_PATH='@s9s_mb_2u_lib.s9s_mb_2u(sch_1):page202_i105@pure_quanta.q_res(chips)',
 PATH='I105',
 DRAWING='@S9S_MB_2U_LIB.S9S_MB_2U(SCH_1):PAGE190',
 PHYS_PAGE='202',
 XY='(-625,3800)',
 ROT='0',
 VER='1',
 PACK_TYPE='0402LF',
 LOCATION='R4118',
 CDS_LIB='pure_quanta',
 CDS_PART_NAME='Q_RES_0402LF-10,1%,1/16W,CHIP,A',
 WATTAGE='1/16W',
 TOLERANCE='1%',
 MATERIAL='CHIP',
 VALUE='10',
 PRIM_FILE='./archive_libs/logical/q_res/chips/chips.prt';

PART_NAME
 R4119 'Q_RES_0402LF-54.9K,1%,1/16W,EMA':;

SECTION_NUMBER 1
 '@S9S_MB_2U_LIB.S9S_MB_2U(SCH_1):PAGE143_I13@PURE_QUANTA.Q_RES(CHIPS)':
 C_PATH='@s9s_mb_2u_lib.s9s_mb_2u(sch_1):page143_i13@pure_quanta.q_res(chips)',
 P_PATH='@s9s_mb_2u_lib.s9s_mb_2u(sch_1):page146_i13@pure_quanta.q_res(chips)',
 PATH='I13',
 DRAWING='@S9S_MB_2U_LIB.S9S_MB_2U(SCH_1):PAGE143',
 PHYS_PAGE='146',
 XY='(-2300,3725)',
 ROT='0',
 VER='2',
 PACK_TYPE='0402LF',
 CDS_LIB='pure_quanta',
 CDS_PART_NAME='Q_RES_0402LF-54.9K,1%,1/16W,EMA',
 WATTAGE='1/16W',
 TOLERANCE='1%',
 MATERIAL='EMPTY',
 VALUE='54.9K',
 PRIM_FILE='./archive_libs/logical/q_res/chips/chips.prt';

PART_NAME
 R4120 'Q_RES_0402LF-100K,1%,1/16W,EMPA':;

SECTION_NUMBER 1
 '@S9S_MB_2U_LIB.S9S_MB_2U(SCH_1):PAGE143_I14@PURE_QUANTA.Q_RES(CHIPS)':
 C_PATH='@s9s_mb_2u_lib.s9s_mb_2u(sch_1):page143_i14@pure_quanta.q_res(chips)',
 P_PATH='@s9s_mb_2u_lib.s9s_mb_2u(sch_1):page146_i14@pure_quanta.q_res(chips)',
 PATH='I14',
 DRAWING='@S9S_MB_2U_LIB.S9S_MB_2U(SCH_1):PAGE143',
 PHYS_PAGE='146',
 XY='(-2275,3250)',
 ROT='0',
 VER='2',
 PACK_TYPE='0402LF',
 CDS_LIB='pure_quanta',
 CDS_PART_NAME='Q_RES_0402LF-100K,1%,1/16W,EMPA',
 WATTAGE='1/16W',
 TOLERANCE='1%',
 MATERIAL='EMPTY',
 VALUE='100K',
 PRIM_FILE='./archive_libs/logical/q_res/chips/chips.prt';

PART_NAME
 R4121 'Q_RES_0402LF-10K,1%,1/16W,CHIPA':;

SECTION_NUMBER 1
 '@S9S_MB_2U_LIB.S9S_MB_2U(SCH_1):PAGE143_I143@PURE_QUANTA.Q_RES(CHIPS)':
 C_PATH='@s9s_mb_2u_lib.s9s_mb_2u(sch_1):page143_i143@pure_quanta.q_res(chips)',
 P_PATH='@s9s_mb_2u_lib.s9s_mb_2u(sch_1):page146_i143@pure_quanta.q_res(chips)',
 PATH='I143',
 DRAWING='@S9S_MB_2U_LIB.S9S_MB_2U(SCH_1):PAGE143',
 PHYS_PAGE='146',
 XY='(-2300,900)',
 ROT='0',
 VER='2',
 PACK_TYPE='0402LF',
 LOCATION='R4121',
 CDS_LIB='pure_quanta',
 CDS_PART_NAME='Q_RES_0402LF-10K,1%,1/16W,CHIPA',
 WATTAGE='1/16W',
 TOLERANCE='1%',
 MATERIAL='CHIP',
 VALUE='10K',
 PRIM_FILE='./archive_libs/logical/q_res/chips/chips.prt';

PART_NAME
 R4122 'Q_RES_0402LF-100K,1%,1/16W,EMPA':;

SECTION_NUMBER 1
 '@S9S_MB_2U_LIB.S9S_MB_2U(SCH_1):PAGE143_I49@PURE_QUANTA.Q_RES(CHIPS)':
 C_PATH='@s9s_mb_2u_lib.s9s_mb_2u(sch_1):page143_i49@pure_quanta.q_res(chips)',
 P_PATH='@s9s_mb_2u_lib.s9s_mb_2u(sch_1):page146_i49@pure_quanta.q_res(chips)',
 PATH='I49',
 DRAWING='@S9S_MB_2U_LIB.S9S_MB_2U(SCH_1):PAGE143',
 PHYS_PAGE='146',
 XY='(-2275,425)',
 ROT='0',
 VER='2',
 PACK_TYPE='0402LF',
 CDS_LIB='pure_quanta',
 CDS_PART_NAME='Q_RES_0402LF-100K,1%,1/16W,EMPA',
 WATTAGE='1/16W',
 TOLERANCE='1%',
 MATERIAL='EMPTY',
 VALUE='100K',
 PRIM_FILE='./archive_libs/logical/q_res/chips/chips.prt';

PART_NAME
 R4123 'Q_RES_0402LF-54.9K,1%,1/16W,EMA':;

SECTION_NUMBER 1
 '@S9S_MB_2U_LIB.S9S_MB_2U(SCH_1):PAGE143_I31@PURE_QUANTA.Q_RES(CHIPS)':
 C_PATH='@s9s_mb_2u_lib.s9s_mb_2u(sch_1):page143_i31@pure_quanta.q_res(chips)',
 P_PATH='@s9s_mb_2u_lib.s9s_mb_2u(sch_1):page146_i31@pure_quanta.q_res(chips)',
 PATH='I31',
 DRAWING='@S9S_MB_2U_LIB.S9S_MB_2U(SCH_1):PAGE143',
 PHYS_PAGE='146',
 XY='(-2275,2350)',
 ROT='0',
 VER='2',
 PACK_TYPE='0402LF',
 CDS_LIB='pure_quanta',
 CDS_PART_NAME='Q_RES_0402LF-54.9K,1%,1/16W,EMA',
 WATTAGE='1/16W',
 TOLERANCE='1%',
 MATERIAL='EMPTY',
 VALUE='54.9K',
 PRIM_FILE='./archive_libs/logical/q_res/chips/chips.prt';

PART_NAME
 R4124 'Q_RES_0402LF-100K,1%,1/16W,EMPA':;

SECTION_NUMBER 1
 '@S9S_MB_2U_LIB.S9S_MB_2U(SCH_1):PAGE143_I32@PURE_QUANTA.Q_RES(CHIPS)':
 C_PATH='@s9s_mb_2u_lib.s9s_mb_2u(sch_1):page143_i32@pure_quanta.q_res(chips)',
 P_PATH='@s9s_mb_2u_lib.s9s_mb_2u(sch_1):page146_i32@pure_quanta.q_res(chips)',
 PATH='I32',
 DRAWING='@S9S_MB_2U_LIB.S9S_MB_2U(SCH_1):PAGE143',
 PHYS_PAGE='146',
 XY='(-2250,1875)',
 ROT='0',
 VER='2',
 PACK_TYPE='0402LF',
 CDS_LIB='pure_quanta',
 CDS_PART_NAME='Q_RES_0402LF-100K,1%,1/16W,EMPA',
 WATTAGE='1/16W',
 TOLERANCE='1%',
 MATERIAL='EMPTY',
 VALUE='100K',
 PRIM_FILE='./archive_libs/logical/q_res/chips/chips.prt';

PART_NAME
 R4125 'Q_RES_0402LF-4.7K,5%,1/16W,CHIA':;

SECTION_NUMBER 1
 '@S9S_MB_2U_LIB.S9S_MB_2U(SCH_1):PAGE143_I9@PURE_QUANTA.Q_RES(CHIPS)':
 C_PATH='@s9s_mb_2u_lib.s9s_mb_2u(sch_1):page143_i9@pure_quanta.q_res(chips)',
 P_PATH='@s9s_mb_2u_lib.s9s_mb_2u(sch_1):page146_i9@pure_quanta.q_res(chips)',
 PATH='I9',
 DRAWING='@S9S_MB_2U_LIB.S9S_MB_2U(SCH_1):PAGE143',
 PHYS_PAGE='146',
 XY='(-1125,4100)',
 ROT='0',
 VER='2',
 PACK_TYPE='0402LF',
 CDS_LIB='pure_quanta',
 CDS_PART_NAME='Q_RES_0402LF-4.7K,5%,1/16W,CHIA',
 WATTAGE='1/16W',
 TOLERANCE='5%',
 MATERIAL='CHIP',
 VALUE='4.7K',
 PRIM_FILE='./archive_libs/logical/q_res/chips/chips.prt';

PART_NAME
 R4126 'Q_RES_0402LF-4.7K,5%,1/16W,CHIA':;

SECTION_NUMBER 1
 '@S9S_MB_2U_LIB.S9S_MB_2U(SCH_1):PAGE143_I43@PURE_QUANTA.Q_RES(CHIPS)':
 C_PATH='@s9s_mb_2u_lib.s9s_mb_2u(sch_1):page143_i43@pure_quanta.q_res(chips)',
 P_PATH='@s9s_mb_2u_lib.s9s_mb_2u(sch_1):page146_i43@pure_quanta.q_res(chips)',
 PATH='I43',
 DRAWING='@S9S_MB_2U_LIB.S9S_MB_2U(SCH_1):PAGE143',
 PHYS_PAGE='146',
 XY='(-1125,1275)',
 ROT='0',
 VER='2',
 PACK_TYPE='0402LF',
 CDS_LIB='pure_quanta',
 CDS_PART_NAME='Q_RES_0402LF-4.7K,5%,1/16W,CHIA',
 WATTAGE='1/16W',
 TOLERANCE='5%',
 MATERIAL='CHIP',
 VALUE='4.7K',
 PRIM_FILE='./archive_libs/logical/q_res/chips/chips.prt';

PART_NAME
 R4127 'Q_RES_0402LF-4.7K,5%,1/16W,CHIA':;

SECTION_NUMBER 1
 '@S9S_MB_2U_LIB.S9S_MB_2U(SCH_1):PAGE143_I27@PURE_QUANTA.Q_RES(CHIPS)':
 C_PATH='@s9s_mb_2u_lib.s9s_mb_2u(sch_1):page143_i27@pure_quanta.q_res(chips)',
 P_PATH='@s9s_mb_2u_lib.s9s_mb_2u(sch_1):page146_i27@pure_quanta.q_res(chips)',
 PATH='I27',
 DRAWING='@S9S_MB_2U_LIB.S9S_MB_2U(SCH_1):PAGE143',
 PHYS_PAGE='146',
 XY='(-1100,2725)',
 ROT='0',
 VER='2',
 PACK_TYPE='0402LF',
 CDS_LIB='pure_quanta',
 CDS_PART_NAME='Q_RES_0402LF-4.7K,5%,1/16W,CHIA',
 WATTAGE='1/16W',
 TOLERANCE='5%',
 MATERIAL='CHIP',
 VALUE='4.7K',
 PRIM_FILE='./archive_libs/logical/q_res/chips/chips.prt';

PART_NAME
 R4128 'Q_RES_0402LF-4.7K,5%,1/16W,CHIA':;

SECTION_NUMBER 1
 '@S9S_MB_2U_LIB.S9S_MB_2U(SCH_1):PAGE143_I5@PURE_QUANTA.Q_RES(CHIPS)':
 C_PATH='@s9s_mb_2u_lib.s9s_mb_2u(sch_1):page143_i5@pure_quanta.q_res(chips)',
 P_PATH='@s9s_mb_2u_lib.s9s_mb_2u(sch_1):page146_i5@pure_quanta.q_res(chips)',
 PATH='I5',
 DRAWING='@S9S_MB_2U_LIB.S9S_MB_2U(SCH_1):PAGE143',
 PHYS_PAGE='146',
 XY='(25,4225)',
 ROT='0',
 VER='2',
 PACK_TYPE='0402LF',
 CDS_LIB='pure_quanta',
 CDS_PART_NAME='Q_RES_0402LF-4.7K,5%,1/16W,CHIA',
 WATTAGE='1/16W',
 TOLERANCE='5%',
 MATERIAL='CHIP',
 VALUE='4.7K',
 PRIM_FILE='./archive_libs/logical/q_res/chips/chips.prt';

PART_NAME
 R4129 'Q_RES_0402LF-4.7K,5%,1/16W,CHIA':;

SECTION_NUMBER 1
 '@S9S_MB_2U_LIB.S9S_MB_2U(SCH_1):PAGE143_I36@PURE_QUANTA.Q_RES(CHIPS)':
 C_PATH='@s9s_mb_2u_lib.s9s_mb_2u(sch_1):page143_i36@pure_quanta.q_res(chips)',
 P_PATH='@s9s_mb_2u_lib.s9s_mb_2u(sch_1):page146_i36@pure_quanta.q_res(chips)',
 PATH='I36',
 DRAWING='@S9S_MB_2U_LIB.S9S_MB_2U(SCH_1):PAGE143',
 PHYS_PAGE='146',
 XY='(25,1400)',
 ROT='0',
 VER='2',
 PACK_TYPE='0402LF',
 CDS_LIB='pure_quanta',
 CDS_PART_NAME='Q_RES_0402LF-4.7K,5%,1/16W,CHIA',
 WATTAGE='1/16W',
 TOLERANCE='5%',
 MATERIAL='CHIP',
 VALUE='4.7K',
 PRIM_FILE='./archive_libs/logical/q_res/chips/chips.prt';

PART_NAME
 R4130 'Q_RES_0402LF-4.7K,5%,1/16W,CHIA':;

SECTION_NUMBER 1
 '@S9S_MB_2U_LIB.S9S_MB_2U(SCH_1):PAGE143_I21@PURE_QUANTA.Q_RES(CHIPS)':
 C_PATH='@s9s_mb_2u_lib.s9s_mb_2u(sch_1):page143_i21@pure_quanta.q_res(chips)',
 P_PATH='@s9s_mb_2u_lib.s9s_mb_2u(sch_1):page146_i21@pure_quanta.q_res(chips)',
 PATH='I21',
 DRAWING='@S9S_MB_2U_LIB.S9S_MB_2U(SCH_1):PAGE143',
 PHYS_PAGE='146',
 XY='(50,2850)',
 ROT='0',
 VER='2',
 PACK_TYPE='0402LF',
 CDS_LIB='pure_quanta',
 CDS_PART_NAME='Q_RES_0402LF-4.7K,5%,1/16W,CHIA',
 WATTAGE='1/16W',
 TOLERANCE='5%',
 MATERIAL='CHIP',
 VALUE='4.7K',
 PRIM_FILE='./archive_libs/logical/q_res/chips/chips.prt';

PART_NAME
 R4131 'Q_RES_0402LF-54.9K,1%,1/16W,EMA':;

SECTION_NUMBER 1
 '@S9S_MB_2U_LIB.S9S_MB_2U(SCH_1):PAGE143_I85@PURE_QUANTA.Q_RES(CHIPS)':
 C_PATH='@s9s_mb_2u_lib.s9s_mb_2u(sch_1):page143_i85@pure_quanta.q_res(chips)',
 P_PATH='@s9s_mb_2u_lib.s9s_mb_2u(sch_1):page146_i85@pure_quanta.q_res(chips)',
 PATH='I85',
 DRAWING='@S9S_MB_2U_LIB.S9S_MB_2U(SCH_1):PAGE143',
 PHYS_PAGE='146',
 XY='(2325,4025)',
 ROT='0',
 VER='2',
 PACK_TYPE='0402LF',
 CDS_LIB='pure_quanta',
 CDS_PART_NAME='Q_RES_0402LF-54.9K,1%,1/16W,EMA',
 WATTAGE='1/16W',
 TOLERANCE='1%',
 MATERIAL='EMPTY',
 VALUE='54.9K',
 PRIM_FILE='./archive_libs/logical/q_res/chips/chips.prt';

PART_NAME
 R4132 'Q_RES_0402LF-100K,1%,1/16W,EMPA':;

SECTION_NUMBER 1
 '@S9S_MB_2U_LIB.S9S_MB_2U(SCH_1):PAGE143_I86@PURE_QUANTA.Q_RES(CHIPS)':
 C_PATH='@s9s_mb_2u_lib.s9s_mb_2u(sch_1):page143_i86@pure_quanta.q_res(chips)',
 P_PATH='@s9s_mb_2u_lib.s9s_mb_2u(sch_1):page146_i86@pure_quanta.q_res(chips)',
 PATH='I86',
 DRAWING='@S9S_MB_2U_LIB.S9S_MB_2U(SCH_1):PAGE143',
 PHYS_PAGE='146',
 XY='(2350,3550)',
 ROT='0',
 VER='2',
 PACK_TYPE='0402LF',
 CDS_LIB='pure_quanta',
 CDS_PART_NAME='Q_RES_0402LF-100K,1%,1/16W,EMPA',
 WATTAGE='1/16W',
 TOLERANCE='1%',
 MATERIAL='EMPTY',
 VALUE='100K',
 PRIM_FILE='./archive_libs/logical/q_res/chips/chips.prt';

PART_NAME
 R4133 'Q_RES_0402LF-54.9K,1%,1/16W,EMA':;

SECTION_NUMBER 1
 '@S9S_MB_2U_LIB.S9S_MB_2U(SCH_1):PAGE143_I95@PURE_QUANTA.Q_RES(CHIPS)':
 C_PATH='@s9s_mb_2u_lib.s9s_mb_2u(sch_1):page143_i95@pure_quanta.q_res(chips)',
 P_PATH='@s9s_mb_2u_lib.s9s_mb_2u(sch_1):page146_i95@pure_quanta.q_res(chips)',
 PATH='I95',
 DRAWING='@S9S_MB_2U_LIB.S9S_MB_2U(SCH_1):PAGE143',
 PHYS_PAGE='146',
 XY='(2325,1200)',
 ROT='0',
 VER='2',
 PACK_TYPE='0402LF',
 CDS_LIB='pure_quanta',
 CDS_PART_NAME='Q_RES_0402LF-54.9K,1%,1/16W,EMA',
 WATTAGE='1/16W',
 TOLERANCE='1%',
 MATERIAL='EMPTY',
 VALUE='54.9K',
 PRIM_FILE='./archive_libs/logical/q_res/chips/chips.prt';

PART_NAME
 R4134 'Q_RES_0402LF-100K,1%,1/16W,EMPA':;

SECTION_NUMBER 1
 '@S9S_MB_2U_LIB.S9S_MB_2U(SCH_1):PAGE143_I96@PURE_QUANTA.Q_RES(CHIPS)':
 C_PATH='@s9s_mb_2u_lib.s9s_mb_2u(sch_1):page143_i96@pure_quanta.q_res(chips)',
 P_PATH='@s9s_mb_2u_lib.s9s_mb_2u(sch_1):page146_i96@pure_quanta.q_res(chips)',
 PATH='I96',
 DRAWING='@S9S_MB_2U_LIB.S9S_MB_2U(SCH_1):PAGE143',
 PHYS_PAGE='146',
 XY='(2350,725)',
 ROT='0',
 VER='2',
 PACK_TYPE='0402LF',
 CDS_LIB='pure_quanta',
 CDS_PART_NAME='Q_RES_0402LF-100K,1%,1/16W,EMPA',
 WATTAGE='1/16W',
 TOLERANCE='1%',
 MATERIAL='EMPTY',
 VALUE='100K',
 PRIM_FILE='./archive_libs/logical/q_res/chips/chips.prt';

PART_NAME
 R4135 'Q_RES_0402LF-10K,1%,1/16W,CHIPA':;

SECTION_NUMBER 1
 '@S9S_MB_2U_LIB.S9S_MB_2U(SCH_1):PAGE143_I144@PURE_QUANTA.Q_RES(CHIPS)':
 C_PATH='@s9s_mb_2u_lib.s9s_mb_2u(sch_1):page143_i144@pure_quanta.q_res(chips)',
 P_PATH='@s9s_mb_2u_lib.s9s_mb_2u(sch_1):page146_i144@pure_quanta.q_res(chips)',
 PATH='I144',
 DRAWING='@S9S_MB_2U_LIB.S9S_MB_2U(SCH_1):PAGE143',
 PHYS_PAGE='146',
 XY='(2350,2650)',
 ROT='0',
 VER='2',
 PACK_TYPE='0402LF',
 LOCATION='R4135',
 CDS_LIB='pure_quanta',
 CDS_PART_NAME='Q_RES_0402LF-10K,1%,1/16W,CHIPA',
 WATTAGE='1/16W',
 TOLERANCE='1%',
 MATERIAL='CHIP',
 VALUE='10K',
 PRIM_FILE='./archive_libs/logical/q_res/chips/chips.prt';

PART_NAME
 R4136 'Q_RES_0402LF-100K,1%,1/16W,EMPA':;

SECTION_NUMBER 1
 '@S9S_MB_2U_LIB.S9S_MB_2U(SCH_1):PAGE143_I91@PURE_QUANTA.Q_RES(CHIPS)':
 C_PATH='@s9s_mb_2u_lib.s9s_mb_2u(sch_1):page143_i91@pure_quanta.q_res(chips)',
 P_PATH='@s9s_mb_2u_lib.s9s_mb_2u(sch_1):page146_i91@pure_quanta.q_res(chips)',
 PATH='I91',
 DRAWING='@S9S_MB_2U_LIB.S9S_MB_2U(SCH_1):PAGE143',
 PHYS_PAGE='146',
 XY='(2375,2175)',
 ROT='0',
 VER='2',
 PACK_TYPE='0402LF',
 CDS_LIB='pure_quanta',
 CDS_PART_NAME='Q_RES_0402LF-100K,1%,1/16W,EMPA',
 WATTAGE='1/16W',
 TOLERANCE='1%',
 MATERIAL='EMPTY',
 VALUE='100K',
 PRIM_FILE='./archive_libs/logical/q_res/chips/chips.prt';

PART_NAME
 R4137 'Q_RES_0402LF-4.7K,5%,1/16W,CHIA':;

SECTION_NUMBER 1
 '@S9S_MB_2U_LIB.S9S_MB_2U(SCH_1):PAGE143_I72@PURE_QUANTA.Q_RES(CHIPS)':
 C_PATH='@s9s_mb_2u_lib.s9s_mb_2u(sch_1):page143_i72@pure_quanta.q_res(chips)',
 P_PATH='@s9s_mb_2u_lib.s9s_mb_2u(sch_1):page146_i72@pure_quanta.q_res(chips)',
 PATH='I72',
 DRAWING='@S9S_MB_2U_LIB.S9S_MB_2U(SCH_1):PAGE143',
 PHYS_PAGE='146',
 XY='(3500,4400)',
 ROT='0',
 VER='2',
 PACK_TYPE='0402LF',
 CDS_LIB='pure_quanta',
 CDS_PART_NAME='Q_RES_0402LF-4.7K,5%,1/16W,CHIA',
 WATTAGE='1/16W',
 TOLERANCE='5%',
 MATERIAL='CHIP',
 VALUE='4.7K',
 PRIM_FILE='./archive_libs/logical/q_res/chips/chips.prt';

PART_NAME
 R4138 'Q_RES_0402LF-4.7K,5%,1/16W,CHIA':;

SECTION_NUMBER 1
 '@S9S_MB_2U_LIB.S9S_MB_2U(SCH_1):PAGE143_I81@PURE_QUANTA.Q_RES(CHIPS)':
 C_PATH='@s9s_mb_2u_lib.s9s_mb_2u(sch_1):page143_i81@pure_quanta.q_res(chips)',
 P_PATH='@s9s_mb_2u_lib.s9s_mb_2u(sch_1):page146_i81@pure_quanta.q_res(chips)',
 PATH='I81',
 DRAWING='@S9S_MB_2U_LIB.S9S_MB_2U(SCH_1):PAGE143',
 PHYS_PAGE='146',
 XY='(3500,1575)',
 ROT='0',
 VER='2',
 PACK_TYPE='0402LF',
 CDS_LIB='pure_quanta',
 CDS_PART_NAME='Q_RES_0402LF-4.7K,5%,1/16W,CHIA',
 WATTAGE='1/16W',
 TOLERANCE='5%',
 MATERIAL='CHIP',
 VALUE='4.7K',
 PRIM_FILE='./archive_libs/logical/q_res/chips/chips.prt';

PART_NAME
 R4139 'Q_RES_0402LF-4.7K,5%,1/16W,CHIA':;

SECTION_NUMBER 1
 '@S9S_MB_2U_LIB.S9S_MB_2U(SCH_1):PAGE143_I76@PURE_QUANTA.Q_RES(CHIPS)':
 C_PATH='@s9s_mb_2u_lib.s9s_mb_2u(sch_1):page143_i76@pure_quanta.q_res(chips)',
 P_PATH='@s9s_mb_2u_lib.s9s_mb_2u(sch_1):page146_i76@pure_quanta.q_res(chips)',
 PATH='I76',
 DRAWING='@S9S_MB_2U_LIB.S9S_MB_2U(SCH_1):PAGE143',
 PHYS_PAGE='146',
 XY='(3525,3025)',
 ROT='0',
 VER='2',
 PACK_TYPE='0402LF',
 CDS_LIB='pure_quanta',
 CDS_PART_NAME='Q_RES_0402LF-4.7K,5%,1/16W,CHIA',
 WATTAGE='1/16W',
 TOLERANCE='5%',
 MATERIAL='CHIP',
 VALUE='4.7K',
 PRIM_FILE='./archive_libs/logical/q_res/chips/chips.prt';

PART_NAME
 R4140 'Q_RES_0402LF-4.7K,5%,1/16W,CHIA':;

SECTION_NUMBER 1
 '@S9S_MB_2U_LIB.S9S_MB_2U(SCH_1):PAGE143_I52@PURE_QUANTA.Q_RES(CHIPS)':
 C_PATH='@s9s_mb_2u_lib.s9s_mb_2u(sch_1):page143_i52@pure_quanta.q_res(chips)',
 P_PATH='@s9s_mb_2u_lib.s9s_mb_2u(sch_1):page146_i52@pure_quanta.q_res(chips)',
 PATH='I52',
 DRAWING='@S9S_MB_2U_LIB.S9S_MB_2U(SCH_1):PAGE143',
 PHYS_PAGE='146',
 XY='(4650,4525)',
 ROT='0',
 VER='2',
 PACK_TYPE='0402LF',
 CDS_LIB='pure_quanta',
 CDS_PART_NAME='Q_RES_0402LF-4.7K,5%,1/16W,CHIA',
 WATTAGE='1/16W',
 TOLERANCE='5%',
 MATERIAL='CHIP',
 VALUE='4.7K',
 PRIM_FILE='./archive_libs/logical/q_res/chips/chips.prt';

PART_NAME
 R4141 'Q_RES_0402LF-4.7K,5%,1/16W,CHIA':;

SECTION_NUMBER 1
 '@S9S_MB_2U_LIB.S9S_MB_2U(SCH_1):PAGE143_I64@PURE_QUANTA.Q_RES(CHIPS)':
 C_PATH='@s9s_mb_2u_lib.s9s_mb_2u(sch_1):page143_i64@pure_quanta.q_res(chips)',
 P_PATH='@s9s_mb_2u_lib.s9s_mb_2u(sch_1):page146_i64@pure_quanta.q_res(chips)',
 PATH='I64',
 DRAWING='@S9S_MB_2U_LIB.S9S_MB_2U(SCH_1):PAGE143',
 PHYS_PAGE='146',
 XY='(4650,1700)',
 ROT='0',
 VER='2',
 PACK_TYPE='0402LF',
 CDS_LIB='pure_quanta',
 CDS_PART_NAME='Q_RES_0402LF-4.7K,5%,1/16W,CHIA',
 WATTAGE='1/16W',
 TOLERANCE='5%',
 MATERIAL='CHIP',
 VALUE='4.7K',
 PRIM_FILE='./archive_libs/logical/q_res/chips/chips.prt';

PART_NAME
 R4142 'Q_RES_0402LF-4.7K,5%,1/16W,CHIA':;

SECTION_NUMBER 1
 '@S9S_MB_2U_LIB.S9S_MB_2U(SCH_1):PAGE143_I60@PURE_QUANTA.Q_RES(CHIPS)':
 C_PATH='@s9s_mb_2u_lib.s9s_mb_2u(sch_1):page143_i60@pure_quanta.q_res(chips)',
 P_PATH='@s9s_mb_2u_lib.s9s_mb_2u(sch_1):page146_i60@pure_quanta.q_res(chips)',
 PATH='I60',
 DRAWING='@S9S_MB_2U_LIB.S9S_MB_2U(SCH_1):PAGE143',
 PHYS_PAGE='146',
 XY='(4675,3150)',
 ROT='0',
 VER='2',
 PACK_TYPE='0402LF',
 CDS_LIB='pure_quanta',
 CDS_PART_NAME='Q_RES_0402LF-4.7K,5%,1/16W,CHIA',
 WATTAGE='1/16W',
 TOLERANCE='5%',
 MATERIAL='CHIP',
 VALUE='4.7K',
 PRIM_FILE='./archive_libs/logical/q_res/chips/chips.prt';

PART_NAME
 R4143 'Q_RES_0402LF-33.2,1%,1/16W,CHIA':;

SECTION_NUMBER 1
 '@S9S_MB_2U_LIB.S9S_MB_2U(SCH_1):PAGE312_I89@PURE_QUANTA.Q_RES(CHIPS)':
 C_PATH='@s9s_mb_2u_lib.s9s_mb_2u(sch_1):page312_i89@pure_quanta.q_res(chips)',
 P_PATH='@s9s_mb_2u_lib.s9s_mb_2u(sch_1):page215_i89@pure_quanta.q_res(chips)',
 PATH='I89',
 DRAWING='@S9S_MB_2U_LIB.S9S_MB_2U(SCH_1):PAGE312',
 PHYS_PAGE='215',
 XY='(-4550,525)',
 ROT='0',
 VER='1',
 PACK_TYPE='0402LF',
 CDS_LIB='pure_quanta',
 CDS_PART_NAME='Q_RES_0402LF-33.2,1%,1/16W,CHIA',
 WATTAGE='1/16W',
 TOLERANCE='1%',
 MATERIAL='CHIP',
 VALUE='33.2',
 PRIM_FILE='./archive_libs/logical/q_res/chips/chips.prt';

PART_NAME
 R4144 'Q_RES_0402LF-33.2,1%,1/16W,CHIA':;

SECTION_NUMBER 1
 '@S9S_MB_2U_LIB.S9S_MB_2U(SCH_1):PAGE312_I93@PURE_QUANTA.Q_RES(CHIPS)':
 C_PATH='@s9s_mb_2u_lib.s9s_mb_2u(sch_1):page312_i93@pure_quanta.q_res(chips)',
 P_PATH='@s9s_mb_2u_lib.s9s_mb_2u(sch_1):page215_i93@pure_quanta.q_res(chips)',
 PATH='I93',
 DRAWING='@S9S_MB_2U_LIB.S9S_MB_2U(SCH_1):PAGE312',
 PHYS_PAGE='215',
 XY='(-4550,350)',
 ROT='0',
 VER='1',
 PACK_TYPE='0402LF',
 CDS_LIB='pure_quanta',
 CDS_PART_NAME='Q_RES_0402LF-33.2,1%,1/16W,CHIA',
 WATTAGE='1/16W',
 TOLERANCE='1%',
 MATERIAL='CHIP',
 VALUE='33.2',
 PRIM_FILE='./archive_libs/logical/q_res/chips/chips.prt';

PART_NAME
 R4145 'Q_RES_0402LF-33.2,1%,1/16W,CHIA':;

SECTION_NUMBER 1
 '@S9S_MB_2U_LIB.S9S_MB_2U(SCH_1):PAGE312_I97@PURE_QUANTA.Q_RES(CHIPS)':
 C_PATH='@s9s_mb_2u_lib.s9s_mb_2u(sch_1):page312_i97@pure_quanta.q_res(chips)',
 P_PATH='@s9s_mb_2u_lib.s9s_mb_2u(sch_1):page215_i97@pure_quanta.q_res(chips)',
 PATH='I97',
 DRAWING='@S9S_MB_2U_LIB.S9S_MB_2U(SCH_1):PAGE312',
 PHYS_PAGE='215',
 XY='(-4550,200)',
 ROT='0',
 VER='1',
 PACK_TYPE='0402LF',
 CDS_LIB='pure_quanta',
 CDS_PART_NAME='Q_RES_0402LF-33.2,1%,1/16W,CHIA',
 WATTAGE='1/16W',
 TOLERANCE='1%',
 MATERIAL='CHIP',
 VALUE='33.2',
 PRIM_FILE='./archive_libs/logical/q_res/chips/chips.prt';

PART_NAME
 R4146 'Q_RES_0402LF-33.2,1%,1/16W,CHIA':;

SECTION_NUMBER 1
 '@S9S_MB_2U_LIB.S9S_MB_2U(SCH_1):PAGE312_I98@PURE_QUANTA.Q_RES(CHIPS)':
 C_PATH='@s9s_mb_2u_lib.s9s_mb_2u(sch_1):page312_i98@pure_quanta.q_res(chips)',
 P_PATH='@s9s_mb_2u_lib.s9s_mb_2u(sch_1):page215_i98@pure_quanta.q_res(chips)',
 PATH='I98',
 DRAWING='@S9S_MB_2U_LIB.S9S_MB_2U(SCH_1):PAGE312',
 PHYS_PAGE='215',
 XY='(-4550,25)',
 ROT='0',
 VER='1',
 PACK_TYPE='0402LF',
 CDS_LIB='pure_quanta',
 CDS_PART_NAME='Q_RES_0402LF-33.2,1%,1/16W,CHIA',
 WATTAGE='1/16W',
 TOLERANCE='1%',
 MATERIAL='CHIP',
 VALUE='33.2',
 PRIM_FILE='./archive_libs/logical/q_res/chips/chips.prt';

PART_NAME
 R4147 'Q_RES_0402LF-33.2,1%,1/16W,CHIA':;

SECTION_NUMBER 1
 '@S9S_MB_2U_LIB.S9S_MB_2U(SCH_1):PAGE312_I104@PURE_QUANTA.Q_RES(CHIPS)':
 C_PATH='@s9s_mb_2u_lib.s9s_mb_2u(sch_1):page312_i104@pure_quanta.q_res(chips)',
 P_PATH='@s9s_mb_2u_lib.s9s_mb_2u(sch_1):page215_i104@pure_quanta.q_res(chips)',
 PATH='I104',
 DRAWING='@S9S_MB_2U_LIB.S9S_MB_2U(SCH_1):PAGE312',
 PHYS_PAGE='215',
 XY='(-4550,-125)',
 ROT='0',
 VER='1',
 PACK_TYPE='0402LF',
 CDS_LIB='pure_quanta',
 CDS_PART_NAME='Q_RES_0402LF-33.2,1%,1/16W,CHIA',
 WATTAGE='1/16W',
 TOLERANCE='1%',
 MATERIAL='CHIP',
 VALUE='33.2',
 PRIM_FILE='./archive_libs/logical/q_res/chips/chips.prt';

PART_NAME
 R4148 'Q_RES_0402LF-33.2,1%,1/16W,CHIA':;

SECTION_NUMBER 1
 '@S9S_MB_2U_LIB.S9S_MB_2U(SCH_1):PAGE312_I103@PURE_QUANTA.Q_RES(CHIPS)':
 C_PATH='@s9s_mb_2u_lib.s9s_mb_2u(sch_1):page312_i103@pure_quanta.q_res(chips)',
 P_PATH='@s9s_mb_2u_lib.s9s_mb_2u(sch_1):page215_i103@pure_quanta.q_res(chips)',
 PATH='I103',
 DRAWING='@S9S_MB_2U_LIB.S9S_MB_2U(SCH_1):PAGE312',
 PHYS_PAGE='215',
 XY='(-4550,-300)',
 ROT='0',
 VER='1',
 PACK_TYPE='0402LF',
 CDS_LIB='pure_quanta',
 CDS_PART_NAME='Q_RES_0402LF-33.2,1%,1/16W,CHIA',
 WATTAGE='1/16W',
 TOLERANCE='1%',
 MATERIAL='CHIP',
 VALUE='33.2',
 PRIM_FILE='./archive_libs/logical/q_res/chips/chips.prt';

PART_NAME
 R4149 'Q_RES_0402LF-33.2,1%,1/16W,CHIA':;

SECTION_NUMBER 1
 '@S9S_MB_2U_LIB.S9S_MB_2U(SCH_1):PAGE228_I272@PURE_QUANTA.Q_RES(CHIPS)':
 C_PATH='@s9s_mb_2u_lib.s9s_mb_2u(sch_1):page228_i272@pure_quanta.q_res(chips)',
 P_PATH='@s9s_mb_2u_lib.s9s_mb_2u(sch_1):page241_i272@pure_quanta.q_res(chips)',
 PATH='I272',
 DRAWING='@S9S_MB_2U_LIB.S9S_MB_2U(SCH_1):PAGE228',
 PHYS_PAGE='241',
 XY='(-350,1025)',
 ROT='0',
 VER='1',
 PACK_TYPE='0402LF',
 CDS_LIB='pure_quanta',
 CDS_PART_NAME='Q_RES_0402LF-33.2,1%,1/16W,CHIA',
 WATTAGE='1/16W',
 TOLERANCE='1%',
 MATERIAL='CHIP',
 VALUE='33.2',
 PRIM_FILE='./archive_libs/logical/q_res/chips/chips.prt';

PART_NAME
 R4150 'Q_RES_0402LF-33.2,1%,1/16W,CHIA':;

SECTION_NUMBER 1
 '@S9S_MB_2U_LIB.S9S_MB_2U(SCH_1):PAGE228_I271@PURE_QUANTA.Q_RES(CHIPS)':
 C_PATH='@s9s_mb_2u_lib.s9s_mb_2u(sch_1):page228_i271@pure_quanta.q_res(chips)',
 P_PATH='@s9s_mb_2u_lib.s9s_mb_2u(sch_1):page241_i271@pure_quanta.q_res(chips)',
 PATH='I271',
 DRAWING='@S9S_MB_2U_LIB.S9S_MB_2U(SCH_1):PAGE228',
 PHYS_PAGE='241',
 XY='(-350,975)',
 ROT='0',
 VER='1',
 PACK_TYPE='0402LF',
 CDS_LIB='pure_quanta',
 CDS_PART_NAME='Q_RES_0402LF-33.2,1%,1/16W,CHIA',
 WATTAGE='1/16W',
 TOLERANCE='1%',
 MATERIAL='CHIP',
 VALUE='33.2',
 PRIM_FILE='./archive_libs/logical/q_res/chips/chips.prt';

PART_NAME
 R4151 'Q_RES_0402LF-33.2,1%,1/16W,CHIA':;

SECTION_NUMBER 1
 '@S9S_MB_2U_LIB.S9S_MB_2U(SCH_1):PAGE228_I274@PURE_QUANTA.Q_RES(CHIPS)':
 C_PATH='@s9s_mb_2u_lib.s9s_mb_2u(sch_1):page228_i274@pure_quanta.q_res(chips)',
 P_PATH='@s9s_mb_2u_lib.s9s_mb_2u(sch_1):page241_i274@pure_quanta.q_res(chips)',
 PATH='I274',
 DRAWING='@S9S_MB_2U_LIB.S9S_MB_2U(SCH_1):PAGE228',
 PHYS_PAGE='241',
 XY='(-350,750)',
 ROT='0',
 VER='1',
 PACK_TYPE='0402LF',
 CDS_LIB='pure_quanta',
 CDS_PART_NAME='Q_RES_0402LF-33.2,1%,1/16W,CHIA',
 WATTAGE='1/16W',
 TOLERANCE='1%',
 MATERIAL='CHIP',
 VALUE='33.2',
 PRIM_FILE='./archive_libs/logical/q_res/chips/chips.prt';

PART_NAME
 R4152 'Q_RES_0402LF-33.2,1%,1/16W,CHIA':;

SECTION_NUMBER 1
 '@S9S_MB_2U_LIB.S9S_MB_2U(SCH_1):PAGE228_I273@PURE_QUANTA.Q_RES(CHIPS)':
 C_PATH='@s9s_mb_2u_lib.s9s_mb_2u(sch_1):page228_i273@pure_quanta.q_res(chips)',
 P_PATH='@s9s_mb_2u_lib.s9s_mb_2u(sch_1):page241_i273@pure_quanta.q_res(chips)',
 PATH='I273',
 DRAWING='@S9S_MB_2U_LIB.S9S_MB_2U(SCH_1):PAGE228',
 PHYS_PAGE='241',
 XY='(-350,700)',
 ROT='0',
 VER='1',
 PACK_TYPE='0402LF',
 CDS_LIB='pure_quanta',
 CDS_PART_NAME='Q_RES_0402LF-33.2,1%,1/16W,CHIA',
 WATTAGE='1/16W',
 TOLERANCE='1%',
 MATERIAL='CHIP',
 VALUE='33.2',
 PRIM_FILE='./archive_libs/logical/q_res/chips/chips.prt';

PART_NAME
 R4153 'Q_RES_0402LF-10K,1%,1/16W,CHIPA':;

SECTION_NUMBER 1
 '@S9S_MB_2U_LIB.S9S_MB_2U(SCH_1):PAGE143_I145@PURE_QUANTA.Q_RES(CHIPS)':
 C_PATH='@s9s_mb_2u_lib.s9s_mb_2u(sch_1):page143_i145@pure_quanta.q_res(chips)',
 P_PATH='@s9s_mb_2u_lib.s9s_mb_2u(sch_1):page146_i145@pure_quanta.q_res(chips)',
 PATH='I145',
 DRAWING='@S9S_MB_2U_LIB.S9S_MB_2U(SCH_1):PAGE143',
 PHYS_PAGE='146',
 XY='(-2225,-650)',
 ROT='0',
 VER='2',
 PACK_TYPE='0402LF',
 LOCATION='R4153',
 CDS_LIB='pure_quanta',
 CDS_PART_NAME='Q_RES_0402LF-10K,1%,1/16W,CHIPA',
 WATTAGE='1/16W',
 TOLERANCE='1%',
 MATERIAL='CHIP',
 VALUE='10K',
 PRIM_FILE='./archive_libs/logical/q_res/chips/chips.prt';

PART_NAME
 R4154 'Q_RES_0402LF-100K,1%,1/16W,EMPA':;

SECTION_NUMBER 1
 '@S9S_MB_2U_LIB.S9S_MB_2U(SCH_1):PAGE143_I113@PURE_QUANTA.Q_RES(CHIPS)':
 C_PATH='@s9s_mb_2u_lib.s9s_mb_2u(sch_1):page143_i113@pure_quanta.q_res(chips)',
 P_PATH='@s9s_mb_2u_lib.s9s_mb_2u(sch_1):page146_i113@pure_quanta.q_res(chips)',
 PATH='I113',
 DRAWING='@S9S_MB_2U_LIB.S9S_MB_2U(SCH_1):PAGE143',
 PHYS_PAGE='146',
 XY='(-2200,-1125)',
 ROT='0',
 VER='2',
 PACK_TYPE='0402LF',
 CDS_LIB='pure_quanta',
 CDS_PART_NAME='Q_RES_0402LF-100K,1%,1/16W,EMPA',
 WATTAGE='1/16W',
 TOLERANCE='1%',
 MATERIAL='EMPTY',
 VALUE='100K',
 PRIM_FILE='./archive_libs/logical/q_res/chips/chips.prt';

PART_NAME
 R4155 'Q_RES_0402LF-4.7K,5%,1/16W,CHIA':;

SECTION_NUMBER 1
 '@S9S_MB_2U_LIB.S9S_MB_2U(SCH_1):PAGE143_I100@PURE_QUANTA.Q_RES(CHIPS)':
 C_PATH='@s9s_mb_2u_lib.s9s_mb_2u(sch_1):page143_i100@pure_quanta.q_res(chips)',
 P_PATH='@s9s_mb_2u_lib.s9s_mb_2u(sch_1):page146_i100@pure_quanta.q_res(chips)',
 PATH='I100',
 DRAWING='@S9S_MB_2U_LIB.S9S_MB_2U(SCH_1):PAGE143',
 PHYS_PAGE='146',
 XY='(-1050,-275)',
 ROT='0',
 VER='2',
 PACK_TYPE='0402LF',
 CDS_LIB='pure_quanta',
 CDS_PART_NAME='Q_RES_0402LF-4.7K,5%,1/16W,CHIA',
 WATTAGE='1/16W',
 TOLERANCE='5%',
 MATERIAL='CHIP',
 VALUE='4.7K',
 PRIM_FILE='./archive_libs/logical/q_res/chips/chips.prt';

PART_NAME
 R4156 'Q_RES_0402LF-4.7K,5%,1/16W,CHIA':;

SECTION_NUMBER 1
 '@S9S_MB_2U_LIB.S9S_MB_2U(SCH_1):PAGE143_I101@PURE_QUANTA.Q_RES(CHIPS)':
 C_PATH='@s9s_mb_2u_lib.s9s_mb_2u(sch_1):page143_i101@pure_quanta.q_res(chips)',
 P_PATH='@s9s_mb_2u_lib.s9s_mb_2u(sch_1):page146_i101@pure_quanta.q_res(chips)',
 PATH='I101',
 DRAWING='@S9S_MB_2U_LIB.S9S_MB_2U(SCH_1):PAGE143',
 PHYS_PAGE='146',
 XY='(100,-150)',
 ROT='0',
 VER='2',
 PACK_TYPE='0402LF',
 CDS_LIB='pure_quanta',
 CDS_PART_NAME='Q_RES_0402LF-4.7K,5%,1/16W,CHIA',
 WATTAGE='1/16W',
 TOLERANCE='5%',
 MATERIAL='CHIP',
 VALUE='4.7K',
 PRIM_FILE='./archive_libs/logical/q_res/chips/chips.prt';

PART_NAME
 R4157 'Q_RES_0402LF-33.2,1%,1/16W,CHIA':;

SECTION_NUMBER 1
 '@S9S_MB_2U_LIB.S9S_MB_2U(SCH_1):PAGE312_I114@PURE_QUANTA.Q_RES(CHIPS)':
 C_PATH='@s9s_mb_2u_lib.s9s_mb_2u(sch_1):page312_i114@pure_quanta.q_res(chips)',
 P_PATH='@s9s_mb_2u_lib.s9s_mb_2u(sch_1):page215_i114@pure_quanta.q_res(chips)',
 PATH='I114',
 DRAWING='@S9S_MB_2U_LIB.S9S_MB_2U(SCH_1):PAGE312',
 PHYS_PAGE='215',
 XY='(-4550,-475)',
 ROT='0',
 VER='1',
 PACK_TYPE='0402LF',
 CDS_LIB='pure_quanta',
 CDS_PART_NAME='Q_RES_0402LF-33.2,1%,1/16W,CHIA',
 WATTAGE='1/16W',
 TOLERANCE='1%',
 MATERIAL='CHIP',
 VALUE='33.2',
 PRIM_FILE='./archive_libs/logical/q_res/chips/chips.prt';

PART_NAME
 R4158 'Q_RES_0402LF-54.9K,1%,1/16W,EMA':;

SECTION_NUMBER 1
 '@S9S_MB_2U_LIB.S9S_MB_2U(SCH_1):PAGE139_I14@PURE_QUANTA.Q_RES(CHIPS)':
 C_PATH='@s9s_mb_2u_lib.s9s_mb_2u(sch_1):page139_i14@pure_quanta.q_res(chips)',
 P_PATH='@s9s_mb_2u_lib.s9s_mb_2u(sch_1):page145_i14@pure_quanta.q_res(chips)',
 PATH='I14',
 DRAWING='@S9S_MB_2U_LIB.S9S_MB_2U(SCH_1):PAGE139',
 PHYS_PAGE='145',
 XY='(-2000,5200)',
 ROT='0',
 VER='2',
 PACK_TYPE='0402LF',
 CDS_LIB='pure_quanta',
 CDS_PART_NAME='Q_RES_0402LF-54.9K,1%,1/16W,EMA',
 WATTAGE='1/16W',
 TOLERANCE='1%',
 MATERIAL='EMPTY',
 VALUE='54.9K',
 PRIM_FILE='./archive_libs/logical/q_res/chips/chips.prt';

PART_NAME
 R4159 'Q_RES_0402LF-100K,1%,1/16W,EMPA':;

SECTION_NUMBER 1
 '@S9S_MB_2U_LIB.S9S_MB_2U(SCH_1):PAGE139_I13@PURE_QUANTA.Q_RES(CHIPS)':
 C_PATH='@s9s_mb_2u_lib.s9s_mb_2u(sch_1):page139_i13@pure_quanta.q_res(chips)',
 P_PATH='@s9s_mb_2u_lib.s9s_mb_2u(sch_1):page145_i13@pure_quanta.q_res(chips)',
 PATH='I13',
 DRAWING='@S9S_MB_2U_LIB.S9S_MB_2U(SCH_1):PAGE139',
 PHYS_PAGE='145',
 XY='(-1975,4725)',
 ROT='0',
 VER='2',
 PACK_TYPE='0402LF',
 CDS_LIB='pure_quanta',
 CDS_PART_NAME='Q_RES_0402LF-100K,1%,1/16W,EMPA',
 WATTAGE='1/16W',
 TOLERANCE='1%',
 MATERIAL='EMPTY',
 VALUE='100K',
 PRIM_FILE='./archive_libs/logical/q_res/chips/chips.prt';

PART_NAME
 R4160 'Q_RES_0402LF-54.9K,1%,1/16W,EMA':;

SECTION_NUMBER 1
 '@S9S_MB_2U_LIB.S9S_MB_2U(SCH_1):PAGE139_I4@PURE_QUANTA.Q_RES(CHIPS)':
 C_PATH='@s9s_mb_2u_lib.s9s_mb_2u(sch_1):page139_i4@pure_quanta.q_res(chips)',
 P_PATH='@s9s_mb_2u_lib.s9s_mb_2u(sch_1):page145_i4@pure_quanta.q_res(chips)',
 PATH='I4',
 DRAWING='@S9S_MB_2U_LIB.S9S_MB_2U(SCH_1):PAGE139',
 PHYS_PAGE='145',
 XY='(-2000,2375)',
 ROT='0',
 VER='2',
 PACK_TYPE='0402LF',
 CDS_LIB='pure_quanta',
 CDS_PART_NAME='Q_RES_0402LF-54.9K,1%,1/16W,EMA',
 WATTAGE='1/16W',
 TOLERANCE='1%',
 MATERIAL='EMPTY',
 VALUE='54.9K',
 PRIM_FILE='./archive_libs/logical/q_res/chips/chips.prt';

PART_NAME
 R4161 'Q_RES_0402LF-100K,1%,1/16W,EMPA':;

SECTION_NUMBER 1
 '@S9S_MB_2U_LIB.S9S_MB_2U(SCH_1):PAGE139_I2@PURE_QUANTA.Q_RES(CHIPS)':
 C_PATH='@s9s_mb_2u_lib.s9s_mb_2u(sch_1):page139_i2@pure_quanta.q_res(chips)',
 P_PATH='@s9s_mb_2u_lib.s9s_mb_2u(sch_1):page145_i2@pure_quanta.q_res(chips)',
 PATH='I2',
 DRAWING='@S9S_MB_2U_LIB.S9S_MB_2U(SCH_1):PAGE139',
 PHYS_PAGE='145',
 XY='(-1975,1900)',
 ROT='0',
 VER='2',
 PACK_TYPE='0402LF',
 CDS_LIB='pure_quanta',
 CDS_PART_NAME='Q_RES_0402LF-100K,1%,1/16W,EMPA',
 WATTAGE='1/16W',
 TOLERANCE='1%',
 MATERIAL='EMPTY',
 VALUE='100K',
 PRIM_FILE='./archive_libs/logical/q_res/chips/chips.prt';

PART_NAME
 R4162 'Q_RES_0402LF-54.9K,1%,1/16W,EMA':;

SECTION_NUMBER 1
 '@S9S_MB_2U_LIB.S9S_MB_2U(SCH_1):PAGE139_I9@PURE_QUANTA.Q_RES(CHIPS)':
 C_PATH='@s9s_mb_2u_lib.s9s_mb_2u(sch_1):page139_i9@pure_quanta.q_res(chips)',
 P_PATH='@s9s_mb_2u_lib.s9s_mb_2u(sch_1):page145_i9@pure_quanta.q_res(chips)',
 PATH='I9',
 DRAWING='@S9S_MB_2U_LIB.S9S_MB_2U(SCH_1):PAGE139',
 PHYS_PAGE='145',
 XY='(-1975,3825)',
 ROT='0',
 VER='2',
 PACK_TYPE='0402LF',
 CDS_LIB='pure_quanta',
 CDS_PART_NAME='Q_RES_0402LF-54.9K,1%,1/16W,EMA',
 WATTAGE='1/16W',
 TOLERANCE='1%',
 MATERIAL='EMPTY',
 VALUE='54.9K',
 PRIM_FILE='./archive_libs/logical/q_res/chips/chips.prt';

PART_NAME
 R4163 'Q_RES_0402LF-100K,1%,1/16W,EMPA':;

SECTION_NUMBER 1
 '@S9S_MB_2U_LIB.S9S_MB_2U(SCH_1):PAGE139_I8@PURE_QUANTA.Q_RES(CHIPS)':
 C_PATH='@s9s_mb_2u_lib.s9s_mb_2u(sch_1):page139_i8@pure_quanta.q_res(chips)',
 P_PATH='@s9s_mb_2u_lib.s9s_mb_2u(sch_1):page145_i8@pure_quanta.q_res(chips)',
 PATH='I8',
 DRAWING='@S9S_MB_2U_LIB.S9S_MB_2U(SCH_1):PAGE139',
 PHYS_PAGE='145',
 XY='(-1950,3350)',
 ROT='0',
 VER='2',
 PACK_TYPE='0402LF',
 CDS_LIB='pure_quanta',
 CDS_PART_NAME='Q_RES_0402LF-100K,1%,1/16W,EMPA',
 WATTAGE='1/16W',
 TOLERANCE='1%',
 MATERIAL='EMPTY',
 VALUE='100K',
 PRIM_FILE='./archive_libs/logical/q_res/chips/chips.prt';

PART_NAME
 R4164 'Q_RES_0402LF-4.7K,5%,1/16W,CHIA':;

SECTION_NUMBER 1
 '@S9S_MB_2U_LIB.S9S_MB_2U(SCH_1):PAGE139_I27@PURE_QUANTA.Q_RES(CHIPS)':
 C_PATH='@s9s_mb_2u_lib.s9s_mb_2u(sch_1):page139_i27@pure_quanta.q_res(chips)',
 P_PATH='@s9s_mb_2u_lib.s9s_mb_2u(sch_1):page145_i27@pure_quanta.q_res(chips)',
 PATH='I27',
 DRAWING='@S9S_MB_2U_LIB.S9S_MB_2U(SCH_1):PAGE139',
 PHYS_PAGE='145',
 XY='(-825,5575)',
 ROT='0',
 VER='2',
 PACK_TYPE='0402LF',
 CDS_LIB='pure_quanta',
 CDS_PART_NAME='Q_RES_0402LF-4.7K,5%,1/16W,CHIA',
 WATTAGE='1/16W',
 TOLERANCE='5%',
 MATERIAL='CHIP',
 VALUE='4.7K',
 PRIM_FILE='./archive_libs/logical/q_res/chips/chips.prt';

PART_NAME
 R4165 'Q_RES_0402LF-4.7K,5%,1/16W,CHIA':;

SECTION_NUMBER 1
 '@S9S_MB_2U_LIB.S9S_MB_2U(SCH_1):PAGE139_I18@PURE_QUANTA.Q_RES(CHIPS)':
 C_PATH='@s9s_mb_2u_lib.s9s_mb_2u(sch_1):page139_i18@pure_quanta.q_res(chips)',
 P_PATH='@s9s_mb_2u_lib.s9s_mb_2u(sch_1):page145_i18@pure_quanta.q_res(chips)',
 PATH='I18',
 DRAWING='@S9S_MB_2U_LIB.S9S_MB_2U(SCH_1):PAGE139',
 PHYS_PAGE='145',
 XY='(-825,2750)',
 ROT='0',
 VER='2',
 PACK_TYPE='0402LF',
 CDS_LIB='pure_quanta',
 CDS_PART_NAME='Q_RES_0402LF-4.7K,5%,1/16W,CHIA',
 WATTAGE='1/16W',
 TOLERANCE='5%',
 MATERIAL='CHIP',
 VALUE='4.7K',
 PRIM_FILE='./archive_libs/logical/q_res/chips/chips.prt';

PART_NAME
 R4166 'Q_RES_0402LF-4.7K,5%,1/16W,CHIA':;

SECTION_NUMBER 1
 '@S9S_MB_2U_LIB.S9S_MB_2U(SCH_1):PAGE139_I23@PURE_QUANTA.Q_RES(CHIPS)':
 C_PATH='@s9s_mb_2u_lib.s9s_mb_2u(sch_1):page139_i23@pure_quanta.q_res(chips)',
 P_PATH='@s9s_mb_2u_lib.s9s_mb_2u(sch_1):page145_i23@pure_quanta.q_res(chips)',
 PATH='I23',
 DRAWING='@S9S_MB_2U_LIB.S9S_MB_2U(SCH_1):PAGE139',
 PHYS_PAGE='145',
 XY='(-800,4200)',
 ROT='0',
 VER='2',
 PACK_TYPE='0402LF',
 CDS_LIB='pure_quanta',
 CDS_PART_NAME='Q_RES_0402LF-4.7K,5%,1/16W,CHIA',
 WATTAGE='1/16W',
 TOLERANCE='5%',
 MATERIAL='CHIP',
 VALUE='4.7K',
 PRIM_FILE='./archive_libs/logical/q_res/chips/chips.prt';

PART_NAME
 R4167 'Q_RES_0402LF-4.7K,5%,1/16W,CHIA':;

SECTION_NUMBER 1
 '@S9S_MB_2U_LIB.S9S_MB_2U(SCH_1):PAGE139_I47@PURE_QUANTA.Q_RES(CHIPS)':
 C_PATH='@s9s_mb_2u_lib.s9s_mb_2u(sch_1):page139_i47@pure_quanta.q_res(chips)',
 P_PATH='@s9s_mb_2u_lib.s9s_mb_2u(sch_1):page145_i47@pure_quanta.q_res(chips)',
 PATH='I47',
 DRAWING='@S9S_MB_2U_LIB.S9S_MB_2U(SCH_1):PAGE139',
 PHYS_PAGE='145',
 XY='(325,5700)',
 ROT='0',
 VER='2',
 PACK_TYPE='0402LF',
 CDS_LIB='pure_quanta',
 CDS_PART_NAME='Q_RES_0402LF-4.7K,5%,1/16W,CHIA',
 WATTAGE='1/16W',
 TOLERANCE='5%',
 MATERIAL='CHIP',
 VALUE='4.7K',
 PRIM_FILE='./archive_libs/logical/q_res/chips/chips.prt';

PART_NAME
 R4168 'Q_RES_0402LF-4.7K,5%,1/16W,CHIA':;

SECTION_NUMBER 1
 '@S9S_MB_2U_LIB.S9S_MB_2U(SCH_1):PAGE139_I35@PURE_QUANTA.Q_RES(CHIPS)':
 C_PATH='@s9s_mb_2u_lib.s9s_mb_2u(sch_1):page139_i35@pure_quanta.q_res(chips)',
 P_PATH='@s9s_mb_2u_lib.s9s_mb_2u(sch_1):page145_i35@pure_quanta.q_res(chips)',
 PATH='I35',
 DRAWING='@S9S_MB_2U_LIB.S9S_MB_2U(SCH_1):PAGE139',
 PHYS_PAGE='145',
 XY='(325,2875)',
 ROT='0',
 VER='2',
 PACK_TYPE='0402LF',
 CDS_LIB='pure_quanta',
 CDS_PART_NAME='Q_RES_0402LF-4.7K,5%,1/16W,CHIA',
 WATTAGE='1/16W',
 TOLERANCE='5%',
 MATERIAL='CHIP',
 VALUE='4.7K',
 PRIM_FILE='./archive_libs/logical/q_res/chips/chips.prt';

PART_NAME
 R4169 'Q_RES_0402LF-4.7K,5%,1/16W,CHIA':;

SECTION_NUMBER 1
 '@S9S_MB_2U_LIB.S9S_MB_2U(SCH_1):PAGE139_I39@PURE_QUANTA.Q_RES(CHIPS)':
 C_PATH='@s9s_mb_2u_lib.s9s_mb_2u(sch_1):page139_i39@pure_quanta.q_res(chips)',
 P_PATH='@s9s_mb_2u_lib.s9s_mb_2u(sch_1):page145_i39@pure_quanta.q_res(chips)',
 PATH='I39',
 DRAWING='@S9S_MB_2U_LIB.S9S_MB_2U(SCH_1):PAGE139',
 PHYS_PAGE='145',
 XY='(350,4325)',
 ROT='0',
 VER='2',
 PACK_TYPE='0402LF',
 CDS_LIB='pure_quanta',
 CDS_PART_NAME='Q_RES_0402LF-4.7K,5%,1/16W,CHIA',
 WATTAGE='1/16W',
 TOLERANCE='5%',
 MATERIAL='CHIP',
 VALUE='4.7K',
 PRIM_FILE='./archive_libs/logical/q_res/chips/chips.prt';

PART_NAME
 R4170 'Q_RES_0402LF-33.2,1%,1/16W,CHIA':;

SECTION_NUMBER 1
 '@S9S_MB_2U_LIB.S9S_MB_2U(SCH_1):PAGE312_I120@PURE_QUANTA.Q_RES(CHIPS)':
 C_PATH='@s9s_mb_2u_lib.s9s_mb_2u(sch_1):page312_i120@pure_quanta.q_res(chips)',
 P_PATH='@s9s_mb_2u_lib.s9s_mb_2u(sch_1):page215_i120@pure_quanta.q_res(chips)',
 PATH='I120',
 DRAWING='@S9S_MB_2U_LIB.S9S_MB_2U(SCH_1):PAGE312',
 PHYS_PAGE='215',
 XY='(-4550,-600)',
 ROT='0',
 VER='1',
 PACK_TYPE='0402LF',
 CDS_LIB='pure_quanta',
 CDS_PART_NAME='Q_RES_0402LF-33.2,1%,1/16W,CHIA',
 WATTAGE='1/16W',
 TOLERANCE='1%',
 MATERIAL='CHIP',
 VALUE='33.2',
 PRIM_FILE='./archive_libs/logical/q_res/chips/chips.prt';

PART_NAME
 R4171 'Q_RES_0402LF-33.2,1%,1/16W,CHIA':;

SECTION_NUMBER 1
 '@S9S_MB_2U_LIB.S9S_MB_2U(SCH_1):PAGE312_I121@PURE_QUANTA.Q_RES(CHIPS)':
 C_PATH='@s9s_mb_2u_lib.s9s_mb_2u(sch_1):page312_i121@pure_quanta.q_res(chips)',
 P_PATH='@s9s_mb_2u_lib.s9s_mb_2u(sch_1):page215_i121@pure_quanta.q_res(chips)',
 PATH='I121',
 DRAWING='@S9S_MB_2U_LIB.S9S_MB_2U(SCH_1):PAGE312',
 PHYS_PAGE='215',
 XY='(-4550,-775)',
 ROT='0',
 VER='1',
 PACK_TYPE='0402LF',
 CDS_LIB='pure_quanta',
 CDS_PART_NAME='Q_RES_0402LF-33.2,1%,1/16W,CHIA',
 WATTAGE='1/16W',
 TOLERANCE='1%',
 MATERIAL='CHIP',
 VALUE='33.2',
 PRIM_FILE='./archive_libs/logical/q_res/chips/chips.prt';

PART_NAME
 R4172 'Q_RES_0402LF-33.2,1%,1/16W,CHIA':;

SECTION_NUMBER 1
 '@S9S_MB_2U_LIB.S9S_MB_2U(SCH_1):PAGE312_I122@PURE_QUANTA.Q_RES(CHIPS)':
 C_PATH='@s9s_mb_2u_lib.s9s_mb_2u(sch_1):page312_i122@pure_quanta.q_res(chips)',
 P_PATH='@s9s_mb_2u_lib.s9s_mb_2u(sch_1):page215_i122@pure_quanta.q_res(chips)',
 PATH='I122',
 DRAWING='@S9S_MB_2U_LIB.S9S_MB_2U(SCH_1):PAGE312',
 PHYS_PAGE='215',
 XY='(-4550,-950)',
 ROT='0',
 VER='1',
 PACK_TYPE='0402LF',
 CDS_LIB='pure_quanta',
 CDS_PART_NAME='Q_RES_0402LF-33.2,1%,1/16W,CHIA',
 WATTAGE='1/16W',
 TOLERANCE='1%',
 MATERIAL='CHIP',
 VALUE='33.2',
 PRIM_FILE='./archive_libs/logical/q_res/chips/chips.prt';

PART_NAME
 R4173 'Q_RES_0402LF-100K,1%,1/16W,EMPA':;

SECTION_NUMBER 1
 '@S9S_MB_2U_LIB.S9S_MB_2U(SCH_1):PAGE140_I202@PURE_QUANTA.Q_RES(CHIPS)':
 C_PATH='@s9s_mb_2u_lib.s9s_mb_2u(sch_1):page140_i202@pure_quanta.q_res(chips)',
 P_PATH='@s9s_mb_2u_lib.s9s_mb_2u(sch_1):page151_i202@pure_quanta.q_res(chips)',
 PATH='I202',
 DRAWING='@S9S_MB_2U_LIB.S9S_MB_2U(SCH_1):PAGE140',
 PHYS_PAGE='151',
 XY='(400,-1575)',
 ROT='0',
 VER='2',
 PACK_TYPE='0402LF',
 LOCATION='R4173',
 CDS_LIB='pure_quanta',
 CDS_PART_NAME='Q_RES_0402LF-100K,1%,1/16W,EMPA',
 WATTAGE='1/16W',
 TOLERANCE='1%',
 MATERIAL='EMPTY',
 VALUE='100K',
 PRIM_FILE='./archive_libs/logical/q_res/chips/chips.prt';

PART_NAME
 R4174 'Q_RES_0402LF-33.2,1%,1/16W,CHIA':;

SECTION_NUMBER 1
 '@S9S_MB_2U_LIB.S9S_MB_2U(SCH_1):PAGE312_I134@PURE_QUANTA.Q_RES(CHIPS)':
 C_PATH='@s9s_mb_2u_lib.s9s_mb_2u(sch_1):page312_i134@pure_quanta.q_res(chips)',
 P_PATH='@s9s_mb_2u_lib.s9s_mb_2u(sch_1):page215_i134@pure_quanta.q_res(chips)',
 PATH='I134',
 DRAWING='@S9S_MB_2U_LIB.S9S_MB_2U(SCH_1):PAGE312',
 PHYS_PAGE='215',
 XY='(-575,875)',
 ROT='0',
 VER='1',
 PACK_TYPE='0402LF',
 CDS_LIB='pure_quanta',
 CDS_PART_NAME='Q_RES_0402LF-33.2,1%,1/16W,CHIA',
 WATTAGE='1/16W',
 TOLERANCE='1%',
 MATERIAL='CHIP',
 VALUE='33.2',
 PRIM_FILE='./archive_libs/logical/q_res/chips/chips.prt';

PART_NAME
 R4175 'Q_RES_0402LF-33.2,1%,1/16W,CHIA':;

SECTION_NUMBER 1
 '@S9S_MB_2U_LIB.S9S_MB_2U(SCH_1):PAGE312_I135@PURE_QUANTA.Q_RES(CHIPS)':
 C_PATH='@s9s_mb_2u_lib.s9s_mb_2u(sch_1):page312_i135@pure_quanta.q_res(chips)',
 P_PATH='@s9s_mb_2u_lib.s9s_mb_2u(sch_1):page215_i135@pure_quanta.q_res(chips)',
 PATH='I135',
 DRAWING='@S9S_MB_2U_LIB.S9S_MB_2U(SCH_1):PAGE312',
 PHYS_PAGE='215',
 XY='(-575,700)',
 ROT='0',
 VER='1',
 PACK_TYPE='0402LF',
 CDS_LIB='pure_quanta',
 CDS_PART_NAME='Q_RES_0402LF-33.2,1%,1/16W,CHIA',
 WATTAGE='1/16W',
 TOLERANCE='1%',
 MATERIAL='CHIP',
 VALUE='33.2',
 PRIM_FILE='./archive_libs/logical/q_res/chips/chips.prt';

PART_NAME
 R4176 'Q_RES_0402LF-10K,1%,1/16W,CHIPA':;

SECTION_NUMBER 1
 '@S9S_MB_2U_LIB.S9S_MB_2U(SCH_1):PAGE243_I16@PURE_QUANTA.Q_RES(CHIPS)':
 C_PATH='@s9s_mb_2u_lib.s9s_mb_2u(sch_1):page243_i16@pure_quanta.q_res(chips)',
 P_PATH='@s9s_mb_2u_lib.s9s_mb_2u(sch_1):page257_i16@pure_quanta.q_res(chips)',
 PATH='I16',
 DRAWING='@S9S_MB_2U_LIB.S9S_MB_2U(SCH_1):PAGE243',
 PHYS_PAGE='257',
 XY='(-8500,13250)',
 ROT='0',
 VER='2',
 PACK_TYPE='0402LF',
 CDS_LIB='pure_quanta',
 CDS_PART_NAME='Q_RES_0402LF-10K,1%,1/16W,CHIPA',
 WATTAGE='1/16W',
 TOLERANCE='1%',
 MATERIAL='CHIP',
 VALUE='10K',
 PRIM_FILE='./archive_libs/logical/q_res/chips/chips.prt';

PART_NAME
 R4177 'Q_RES_0402LF-0,5%,1/16W,CHIP,CA':;

SECTION_NUMBER 1
 '@S9S_MB_2U_LIB.S9S_MB_2U(SCH_1):PAGE243_I19@PURE_QUANTA.Q_RES(CHIPS)':
 C_PATH='@s9s_mb_2u_lib.s9s_mb_2u(sch_1):page243_i19@pure_quanta.q_res(chips)',
 P_PATH='@s9s_mb_2u_lib.s9s_mb_2u(sch_1):page257_i19@pure_quanta.q_res(chips)',
 PATH='I19',
 DRAWING='@S9S_MB_2U_LIB.S9S_MB_2U(SCH_1):PAGE243',
 PHYS_PAGE='257',
 XY='(-7375,12700)',
 ROT='0',
 VER='1',
 PACK_TYPE='0402LF',
 CDS_LIB='pure_quanta',
 CDS_PART_NAME='Q_RES_0402LF-0,5%,1/16W,CHIP,CA',
 WATTAGE='1/16W',
 TOLERANCE='5%',
 MATERIAL='CHIP',
 VALUE='0',
 PRIM_FILE='./archive_libs/logical/q_res/chips/chips.prt';

PART_NAME
 R4178 'Q_RES_0402LF-33.2,1%,1/16W,CHIA':;

SECTION_NUMBER 1
 '@S9S_MB_2U_LIB.S9S_MB_2U(SCH_1):PAGE161_I114@PURE_QUANTA.Q_RES(CHIPS)':
 C_PATH='@s9s_mb_2u_lib.s9s_mb_2u(sch_1):page161_i114@pure_quanta.q_res(chips)',
 P_PATH='@s9s_mb_2u_lib.s9s_mb_2u(sch_1):page170_i114@pure_quanta.q_res(chips)',
 PATH='I114',
 DRAWING='@S9S_MB_2U_LIB.S9S_MB_2U(SCH_1):PAGE161',
 PHYS_PAGE='170',
 XY='(275,-1500)',
 ROT='0',
 VER='1',
 PACK_TYPE='0402LF',
 CDS_LIB='pure_quanta',
 CDS_PART_NAME='Q_RES_0402LF-33.2,1%,1/16W,CHIA',
 WATTAGE='1/16W',
 TOLERANCE='1%',
 MATERIAL='CHIP',
 VALUE='33.2',
 PRIM_FILE='./archive_libs/logical/q_res/chips/chips.prt';

PART_NAME
 R4179 'Q_RES_0402LF-33.2,1%,1/16W,CHIA':;

SECTION_NUMBER 1
 '@S9S_MB_2U_LIB.S9S_MB_2U(SCH_1):PAGE161_I109@PURE_QUANTA.Q_RES(CHIPS)':
 C_PATH='@s9s_mb_2u_lib.s9s_mb_2u(sch_1):page161_i109@pure_quanta.q_res(chips)',
 P_PATH='@s9s_mb_2u_lib.s9s_mb_2u(sch_1):page170_i109@pure_quanta.q_res(chips)',
 PATH='I109',
 DRAWING='@S9S_MB_2U_LIB.S9S_MB_2U(SCH_1):PAGE161',
 PHYS_PAGE='170',
 XY='(300,-25)',
 ROT='0',
 VER='1',
 PACK_TYPE='0402LF',
 CDS_LIB='pure_quanta',
 CDS_PART_NAME='Q_RES_0402LF-33.2,1%,1/16W,CHIA',
 WATTAGE='1/16W',
 TOLERANCE='1%',
 MATERIAL='CHIP',
 VALUE='33.2',
 PRIM_FILE='./archive_libs/logical/q_res/chips/chips.prt';

PART_NAME
 R4180 'Q_RES_0402LF-33.2,1%,1/16W,CHIA':;

SECTION_NUMBER 1
 '@S9S_MB_2U_LIB.S9S_MB_2U(SCH_1):PAGE161_I77@PURE_QUANTA.Q_RES(CHIPS)':
 C_PATH='@s9s_mb_2u_lib.s9s_mb_2u(sch_1):page161_i77@pure_quanta.q_res(chips)',
 P_PATH='@s9s_mb_2u_lib.s9s_mb_2u(sch_1):page170_i77@pure_quanta.q_res(chips)',
 PATH='I77',
 DRAWING='@S9S_MB_2U_LIB.S9S_MB_2U(SCH_1):PAGE161',
 PHYS_PAGE='170',
 XY='(350,1450)',
 ROT='0',
 VER='1',
 PACK_TYPE='0402LF',
 CDS_LIB='pure_quanta',
 CDS_PART_NAME='Q_RES_0402LF-33.2,1%,1/16W,CHIA',
 WATTAGE='1/16W',
 TOLERANCE='1%',
 MATERIAL='CHIP',
 VALUE='33.2',
 PRIM_FILE='./archive_libs/logical/q_res/chips/chips.prt';

PART_NAME
 R4181 'Q_RES_0402LF-33.2,1%,1/16W,CHIA':;

SECTION_NUMBER 1
 '@S9S_MB_2U_LIB.S9S_MB_2U(SCH_1):PAGE161_I116@PURE_QUANTA.Q_RES(CHIPS)':
 C_PATH='@s9s_mb_2u_lib.s9s_mb_2u(sch_1):page161_i116@pure_quanta.q_res(chips)',
 P_PATH='@s9s_mb_2u_lib.s9s_mb_2u(sch_1):page170_i116@pure_quanta.q_res(chips)',
 PATH='I116',
 DRAWING='@S9S_MB_2U_LIB.S9S_MB_2U(SCH_1):PAGE161',
 PHYS_PAGE='170',
 XY='(275,-1350)',
 ROT='0',
 VER='1',
 PACK_TYPE='0402LF',
 CDS_LIB='pure_quanta',
 CDS_PART_NAME='Q_RES_0402LF-33.2,1%,1/16W,CHIA',
 WATTAGE='1/16W',
 TOLERANCE='1%',
 MATERIAL='CHIP',
 VALUE='33.2',
 PRIM_FILE='./archive_libs/logical/q_res/chips/chips.prt';

PART_NAME
 R4182 'Q_RES_0402LF-33.2,1%,1/16W,CHIA':;

SECTION_NUMBER 1
 '@S9S_MB_2U_LIB.S9S_MB_2U(SCH_1):PAGE161_I107@PURE_QUANTA.Q_RES(CHIPS)':
 C_PATH='@s9s_mb_2u_lib.s9s_mb_2u(sch_1):page161_i107@pure_quanta.q_res(chips)',
 P_PATH='@s9s_mb_2u_lib.s9s_mb_2u(sch_1):page170_i107@pure_quanta.q_res(chips)',
 PATH='I107',
 DRAWING='@S9S_MB_2U_LIB.S9S_MB_2U(SCH_1):PAGE161',
 PHYS_PAGE='170',
 XY='(300,125)',
 ROT='0',
 VER='1',
 PACK_TYPE='0402LF',
 CDS_LIB='pure_quanta',
 CDS_PART_NAME='Q_RES_0402LF-33.2,1%,1/16W,CHIA',
 WATTAGE='1/16W',
 TOLERANCE='1%',
 MATERIAL='CHIP',
 VALUE='33.2',
 PRIM_FILE='./archive_libs/logical/q_res/chips/chips.prt';

PART_NAME
 R4183 'Q_RES_0402LF-33.2,1%,1/16W,CHIA':;

SECTION_NUMBER 1
 '@S9S_MB_2U_LIB.S9S_MB_2U(SCH_1):PAGE161_I78@PURE_QUANTA.Q_RES(CHIPS)':
 C_PATH='@s9s_mb_2u_lib.s9s_mb_2u(sch_1):page161_i78@pure_quanta.q_res(chips)',
 P_PATH='@s9s_mb_2u_lib.s9s_mb_2u(sch_1):page170_i78@pure_quanta.q_res(chips)',
 PATH='I78',
 DRAWING='@S9S_MB_2U_LIB.S9S_MB_2U(SCH_1):PAGE161',
 PHYS_PAGE='170',
 XY='(350,1600)',
 ROT='0',
 VER='1',
 PACK_TYPE='0402LF',
 CDS_LIB='pure_quanta',
 CDS_PART_NAME='Q_RES_0402LF-33.2,1%,1/16W,CHIA',
 WATTAGE='1/16W',
 TOLERANCE='1%',
 MATERIAL='CHIP',
 VALUE='33.2',
 PRIM_FILE='./archive_libs/logical/q_res/chips/chips.prt';

PART_NAME
 R4184 'Q_RES_0402LF-1K,1%,1/16W,EMPTYA':;

SECTION_NUMBER 1
 '@S9S_MB_2U_LIB.S9S_MB_2U(SCH_1):PAGE161_I142@PURE_QUANTA.Q_RES(CHIPS)':
 C_PATH='@s9s_mb_2u_lib.s9s_mb_2u(sch_1):page161_i142@pure_quanta.q_res(chips)',
 P_PATH='@s9s_mb_2u_lib.s9s_mb_2u(sch_1):page170_i142@pure_quanta.q_res(chips)',
 PATH='I142',
 DRAWING='@S9S_MB_2U_LIB.S9S_MB_2U(SCH_1):PAGE161',
 PHYS_PAGE='170',
 XY='(3825,-2825)',
 ROT='0',
 VER='2',
 PACK_TYPE='0402LF',
 CDS_LIB='pure_quanta',
 CDS_PART_NAME='Q_RES_0402LF-1K,1%,1/16W,EMPTYA',
 WATTAGE='1/16W',
 TOLERANCE='1%',
 MATERIAL='EMPTY',
 VALUE='1K',
 PRIM_FILE='./archive_libs/logical/q_res/chips/chips.prt';

PART_NAME
 R4185 'Q_RES_0402LF-1K,1%,1/16W,CHIP,A':;

SECTION_NUMBER 1
 '@S9S_MB_2U_LIB.S9S_MB_2U(SCH_1):PAGE161_I141@PURE_QUANTA.Q_RES(CHIPS)':
 C_PATH='@s9s_mb_2u_lib.s9s_mb_2u(sch_1):page161_i141@pure_quanta.q_res(chips)',
 P_PATH='@s9s_mb_2u_lib.s9s_mb_2u(sch_1):page170_i141@pure_quanta.q_res(chips)',
 PATH='I141',
 DRAWING='@S9S_MB_2U_LIB.S9S_MB_2U(SCH_1):PAGE161',
 PHYS_PAGE='170',
 XY='(3825,-3425)',
 ROT='0',
 VER='2',
 PACK_TYPE='0402LF',
 CDS_LIB='pure_quanta',
 CDS_PART_NAME='Q_RES_0402LF-1K,1%,1/16W,CHIP,A',
 WATTAGE='1/16W',
 TOLERANCE='1%',
 MATERIAL='CHIP',
 VALUE='1K',
 PRIM_FILE='./archive_libs/logical/q_res/chips/chips.prt';

PART_NAME
 R4186 'Q_RES_0402LF-1K,1%,1/16W,EMPTYA':;

SECTION_NUMBER 1
 '@S9S_MB_2U_LIB.S9S_MB_2U(SCH_1):PAGE161_I122@PURE_QUANTA.Q_RES(CHIPS)':
 C_PATH='@s9s_mb_2u_lib.s9s_mb_2u(sch_1):page161_i122@pure_quanta.q_res(chips)',
 P_PATH='@s9s_mb_2u_lib.s9s_mb_2u(sch_1):page170_i122@pure_quanta.q_res(chips)',
 PATH='I122',
 DRAWING='@S9S_MB_2U_LIB.S9S_MB_2U(SCH_1):PAGE161',
 PHYS_PAGE='170',
 XY='(3875,-1350)',
 ROT='0',
 VER='2',
 PACK_TYPE='0402LF',
 CDS_LIB='pure_quanta',
 CDS_PART_NAME='Q_RES_0402LF-1K,1%,1/16W,EMPTYA',
 WATTAGE='1/16W',
 TOLERANCE='1%',
 MATERIAL='EMPTY',
 VALUE='1K',
 PRIM_FILE='./archive_libs/logical/q_res/chips/chips.prt';

PART_NAME
 R4187 'Q_RES_0402LF-1K,1%,1/16W,CHIP,A':;

SECTION_NUMBER 1
 '@S9S_MB_2U_LIB.S9S_MB_2U(SCH_1):PAGE161_I121@PURE_QUANTA.Q_RES(CHIPS)':
 C_PATH='@s9s_mb_2u_lib.s9s_mb_2u(sch_1):page161_i121@pure_quanta.q_res(chips)',
 P_PATH='@s9s_mb_2u_lib.s9s_mb_2u(sch_1):page170_i121@pure_quanta.q_res(chips)',
 PATH='I121',
 DRAWING='@S9S_MB_2U_LIB.S9S_MB_2U(SCH_1):PAGE161',
 PHYS_PAGE='170',
 XY='(3875,-1950)',
 ROT='0',
 VER='2',
 PACK_TYPE='0402LF',
 CDS_LIB='pure_quanta',
 CDS_PART_NAME='Q_RES_0402LF-1K,1%,1/16W,CHIP,A',
 WATTAGE='1/16W',
 TOLERANCE='1%',
 MATERIAL='CHIP',
 VALUE='1K',
 PRIM_FILE='./archive_libs/logical/q_res/chips/chips.prt';

PART_NAME
 R4188 'Q_RES_0402LF-1K,1%,1/16W,EMPTYA':;

SECTION_NUMBER 1
 '@S9S_MB_2U_LIB.S9S_MB_2U(SCH_1):PAGE161_I101@PURE_QUANTA.Q_RES(CHIPS)':
 C_PATH='@s9s_mb_2u_lib.s9s_mb_2u(sch_1):page161_i101@pure_quanta.q_res(chips)',
 P_PATH='@s9s_mb_2u_lib.s9s_mb_2u(sch_1):page170_i101@pure_quanta.q_res(chips)',
 PATH='I101',
 DRAWING='@S9S_MB_2U_LIB.S9S_MB_2U(SCH_1):PAGE161',
 PHYS_PAGE='170',
 XY='(3900,125)',
 ROT='0',
 VER='2',
 PACK_TYPE='0402LF',
 CDS_LIB='pure_quanta',
 CDS_PART_NAME='Q_RES_0402LF-1K,1%,1/16W,EMPTYA',
 WATTAGE='1/16W',
 TOLERANCE='1%',
 MATERIAL='EMPTY',
 VALUE='1K',
 PRIM_FILE='./archive_libs/logical/q_res/chips/chips.prt';

PART_NAME
 R4189 'Q_RES_0402LF-1K,1%,1/16W,CHIP,A':;

SECTION_NUMBER 1
 '@S9S_MB_2U_LIB.S9S_MB_2U(SCH_1):PAGE161_I102@PURE_QUANTA.Q_RES(CHIPS)':
 C_PATH='@s9s_mb_2u_lib.s9s_mb_2u(sch_1):page161_i102@pure_quanta.q_res(chips)',
 P_PATH='@s9s_mb_2u_lib.s9s_mb_2u(sch_1):page170_i102@pure_quanta.q_res(chips)',
 PATH='I102',
 DRAWING='@S9S_MB_2U_LIB.S9S_MB_2U(SCH_1):PAGE161',
 PHYS_PAGE='170',
 XY='(3900,-475)',
 ROT='0',
 VER='2',
 PACK_TYPE='0402LF',
 CDS_LIB='pure_quanta',
 CDS_PART_NAME='Q_RES_0402LF-1K,1%,1/16W,CHIP,A',
 WATTAGE='1/16W',
 TOLERANCE='1%',
 MATERIAL='CHIP',
 VALUE='1K',
 PRIM_FILE='./archive_libs/logical/q_res/chips/chips.prt';

PART_NAME
 R4190 'Q_RES_0402LF-1K,1%,1/16W,EMPTYA':;

SECTION_NUMBER 1
 '@S9S_MB_2U_LIB.S9S_MB_2U(SCH_1):PAGE161_I91@PURE_QUANTA.Q_RES(CHIPS)':
 C_PATH='@s9s_mb_2u_lib.s9s_mb_2u(sch_1):page161_i91@pure_quanta.q_res(chips)',
 P_PATH='@s9s_mb_2u_lib.s9s_mb_2u(sch_1):page170_i91@pure_quanta.q_res(chips)',
 PATH='I91',
 DRAWING='@S9S_MB_2U_LIB.S9S_MB_2U(SCH_1):PAGE161',
 PHYS_PAGE='170',
 XY='(3950,1600)',
 ROT='0',
 VER='2',
 PACK_TYPE='0402LF',
 CDS_LIB='pure_quanta',
 CDS_PART_NAME='Q_RES_0402LF-1K,1%,1/16W,EMPTYA',
 WATTAGE='1/16W',
 TOLERANCE='1%',
 MATERIAL='EMPTY',
 VALUE='1K',
 PRIM_FILE='./archive_libs/logical/q_res/chips/chips.prt';

PART_NAME
 R4191 'Q_RES_0402LF-1K,1%,1/16W,CHIP,A':;

SECTION_NUMBER 1
 '@S9S_MB_2U_LIB.S9S_MB_2U(SCH_1):PAGE161_I89@PURE_QUANTA.Q_RES(CHIPS)':
 C_PATH='@s9s_mb_2u_lib.s9s_mb_2u(sch_1):page161_i89@pure_quanta.q_res(chips)',
 P_PATH='@s9s_mb_2u_lib.s9s_mb_2u(sch_1):page170_i89@pure_quanta.q_res(chips)',
 PATH='I89',
 DRAWING='@S9S_MB_2U_LIB.S9S_MB_2U(SCH_1):PAGE161',
 PHYS_PAGE='170',
 XY='(3950,1000)',
 ROT='0',
 VER='2',
 PACK_TYPE='0402LF',
 CDS_LIB='pure_quanta',
 CDS_PART_NAME='Q_RES_0402LF-1K,1%,1/16W,CHIP,A',
 WATTAGE='1/16W',
 TOLERANCE='1%',
 MATERIAL='CHIP',
 VALUE='1K',
 PRIM_FILE='./archive_libs/logical/q_res/chips/chips.prt';

PART_NAME
 R4192 'Q_RES_0402LF-1K,1%,1/16W,EMPTYA':;

SECTION_NUMBER 1
 '@S9S_MB_2U_LIB.S9S_MB_2U(SCH_1):PAGE161_I148@PURE_QUANTA.Q_RES(CHIPS)':
 C_PATH='@s9s_mb_2u_lib.s9s_mb_2u(sch_1):page161_i148@pure_quanta.q_res(chips)',
 P_PATH='@s9s_mb_2u_lib.s9s_mb_2u(sch_1):page170_i148@pure_quanta.q_res(chips)',
 PATH='I148',
 DRAWING='@S9S_MB_2U_LIB.S9S_MB_2U(SCH_1):PAGE161',
 PHYS_PAGE='170',
 XY='(4075,-2825)',
 ROT='0',
 VER='2',
 PACK_TYPE='0402LF',
 CDS_LIB='pure_quanta',
 CDS_PART_NAME='Q_RES_0402LF-1K,1%,1/16W,EMPTYA',
 WATTAGE='1/16W',
 TOLERANCE='1%',
 MATERIAL='EMPTY',
 VALUE='1K',
 PRIM_FILE='./archive_libs/logical/q_res/chips/chips.prt';

PART_NAME
 R4193 'Q_RES_0402LF-1K,1%,1/16W,CHIP,A':;

SECTION_NUMBER 1
 '@S9S_MB_2U_LIB.S9S_MB_2U(SCH_1):PAGE161_I145@PURE_QUANTA.Q_RES(CHIPS)':
 C_PATH='@s9s_mb_2u_lib.s9s_mb_2u(sch_1):page161_i145@pure_quanta.q_res(chips)',
 P_PATH='@s9s_mb_2u_lib.s9s_mb_2u(sch_1):page170_i145@pure_quanta.q_res(chips)',
 PATH='I145',
 DRAWING='@S9S_MB_2U_LIB.S9S_MB_2U(SCH_1):PAGE161',
 PHYS_PAGE='170',
 XY='(4075,-3425)',
 ROT='0',
 VER='2',
 PACK_TYPE='0402LF',
 CDS_LIB='pure_quanta',
 CDS_PART_NAME='Q_RES_0402LF-1K,1%,1/16W,CHIP,A',
 WATTAGE='1/16W',
 TOLERANCE='1%',
 MATERIAL='CHIP',
 VALUE='1K',
 PRIM_FILE='./archive_libs/logical/q_res/chips/chips.prt';

PART_NAME
 R4194 'Q_RES_0402LF-1K,1%,1/16W,EMPTYA':;

SECTION_NUMBER 1
 '@S9S_MB_2U_LIB.S9S_MB_2U(SCH_1):PAGE161_I128@PURE_QUANTA.Q_RES(CHIPS)':
 C_PATH='@s9s_mb_2u_lib.s9s_mb_2u(sch_1):page161_i128@pure_quanta.q_res(chips)',
 P_PATH='@s9s_mb_2u_lib.s9s_mb_2u(sch_1):page170_i128@pure_quanta.q_res(chips)',
 PATH='I128',
 DRAWING='@S9S_MB_2U_LIB.S9S_MB_2U(SCH_1):PAGE161',
 PHYS_PAGE='170',
 XY='(4125,-1350)',
 ROT='0',
 VER='2',
 PACK_TYPE='0402LF',
 CDS_LIB='pure_quanta',
 CDS_PART_NAME='Q_RES_0402LF-1K,1%,1/16W,EMPTYA',
 WATTAGE='1/16W',
 TOLERANCE='1%',
 MATERIAL='EMPTY',
 VALUE='1K',
 PRIM_FILE='./archive_libs/logical/q_res/chips/chips.prt';

PART_NAME
 R4195 'Q_RES_0402LF-1K,1%,1/16W,CHIP,A':;

SECTION_NUMBER 1
 '@S9S_MB_2U_LIB.S9S_MB_2U(SCH_1):PAGE161_I125@PURE_QUANTA.Q_RES(CHIPS)':
 C_PATH='@s9s_mb_2u_lib.s9s_mb_2u(sch_1):page161_i125@pure_quanta.q_res(chips)',
 P_PATH='@s9s_mb_2u_lib.s9s_mb_2u(sch_1):page170_i125@pure_quanta.q_res(chips)',
 PATH='I125',
 DRAWING='@S9S_MB_2U_LIB.S9S_MB_2U(SCH_1):PAGE161',
 PHYS_PAGE='170',
 XY='(4125,-1950)',
 ROT='0',
 VER='2',
 PACK_TYPE='0402LF',
 CDS_LIB='pure_quanta',
 CDS_PART_NAME='Q_RES_0402LF-1K,1%,1/16W,CHIP,A',
 WATTAGE='1/16W',
 TOLERANCE='1%',
 MATERIAL='CHIP',
 VALUE='1K',
 PRIM_FILE='./archive_libs/logical/q_res/chips/chips.prt';

PART_NAME
 R4196 'Q_RES_0402LF-1K,1%,1/16W,EMPTYA':;

SECTION_NUMBER 1
 '@S9S_MB_2U_LIB.S9S_MB_2U(SCH_1):PAGE161_I95@PURE_QUANTA.Q_RES(CHIPS)':
 C_PATH='@s9s_mb_2u_lib.s9s_mb_2u(sch_1):page161_i95@pure_quanta.q_res(chips)',
 P_PATH='@s9s_mb_2u_lib.s9s_mb_2u(sch_1):page170_i95@pure_quanta.q_res(chips)',
 PATH='I95',
 DRAWING='@S9S_MB_2U_LIB.S9S_MB_2U(SCH_1):PAGE161',
 PHYS_PAGE='170',
 XY='(4150,125)',
 ROT='0',
 VER='2',
 PACK_TYPE='0402LF',
 CDS_LIB='pure_quanta',
 CDS_PART_NAME='Q_RES_0402LF-1K,1%,1/16W,EMPTYA',
 WATTAGE='1/16W',
 TOLERANCE='1%',
 MATERIAL='EMPTY',
 VALUE='1K',
 PRIM_FILE='./archive_libs/logical/q_res/chips/chips.prt';

PART_NAME
 R4197 'Q_RES_0402LF-1K,1%,1/16W,CHIP,A':;

SECTION_NUMBER 1
 '@S9S_MB_2U_LIB.S9S_MB_2U(SCH_1):PAGE161_I98@PURE_QUANTA.Q_RES(CHIPS)':
 C_PATH='@s9s_mb_2u_lib.s9s_mb_2u(sch_1):page161_i98@pure_quanta.q_res(chips)',
 P_PATH='@s9s_mb_2u_lib.s9s_mb_2u(sch_1):page170_i98@pure_quanta.q_res(chips)',
 PATH='I98',
 DRAWING='@S9S_MB_2U_LIB.S9S_MB_2U(SCH_1):PAGE161',
 PHYS_PAGE='170',
 XY='(4150,-475)',
 ROT='0',
 VER='2',
 PACK_TYPE='0402LF',
 CDS_LIB='pure_quanta',
 CDS_PART_NAME='Q_RES_0402LF-1K,1%,1/16W,CHIP,A',
 WATTAGE='1/16W',
 TOLERANCE='1%',
 MATERIAL='CHIP',
 VALUE='1K',
 PRIM_FILE='./archive_libs/logical/q_res/chips/chips.prt';

PART_NAME
 R4198 'Q_RES_0402LF-1K,1%,1/16W,EMPTYA':;

SECTION_NUMBER 1
 '@S9S_MB_2U_LIB.S9S_MB_2U(SCH_1):PAGE161_I82@PURE_QUANTA.Q_RES(CHIPS)':
 C_PATH='@s9s_mb_2u_lib.s9s_mb_2u(sch_1):page161_i82@pure_quanta.q_res(chips)',
 P_PATH='@s9s_mb_2u_lib.s9s_mb_2u(sch_1):page170_i82@pure_quanta.q_res(chips)',
 PATH='I82',
 DRAWING='@S9S_MB_2U_LIB.S9S_MB_2U(SCH_1):PAGE161',
 PHYS_PAGE='170',
 XY='(4200,1600)',
 ROT='0',
 VER='2',
 PACK_TYPE='0402LF',
 CDS_LIB='pure_quanta',
 CDS_PART_NAME='Q_RES_0402LF-1K,1%,1/16W,EMPTYA',
 WATTAGE='1/16W',
 TOLERANCE='1%',
 MATERIAL='EMPTY',
 VALUE='1K',
 PRIM_FILE='./archive_libs/logical/q_res/chips/chips.prt';

PART_NAME
 R4199 'Q_RES_0402LF-1K,1%,1/16W,CHIP,A':;

SECTION_NUMBER 1
 '@S9S_MB_2U_LIB.S9S_MB_2U(SCH_1):PAGE161_I81@PURE_QUANTA.Q_RES(CHIPS)':
 C_PATH='@s9s_mb_2u_lib.s9s_mb_2u(sch_1):page161_i81@pure_quanta.q_res(chips)',
 P_PATH='@s9s_mb_2u_lib.s9s_mb_2u(sch_1):page170_i81@pure_quanta.q_res(chips)',
 PATH='I81',
 DRAWING='@S9S_MB_2U_LIB.S9S_MB_2U(SCH_1):PAGE161',
 PHYS_PAGE='170',
 XY='(4200,1000)',
 ROT='0',
 VER='2',
 PACK_TYPE='0402LF',
 CDS_LIB='pure_quanta',
 CDS_PART_NAME='Q_RES_0402LF-1K,1%,1/16W,CHIP,A',
 WATTAGE='1/16W',
 TOLERANCE='1%',
 MATERIAL='CHIP',
 VALUE='1K',
 PRIM_FILE='./archive_libs/logical/q_res/chips/chips.prt';

PART_NAME
 R4200 'Q_RES_0402LF-1K,1%,1/16W,EMPTYA':;

SECTION_NUMBER 1
 '@S9S_MB_2U_LIB.S9S_MB_2U(SCH_1):PAGE161_I149@PURE_QUANTA.Q_RES(CHIPS)':
 C_PATH='@s9s_mb_2u_lib.s9s_mb_2u(sch_1):page161_i149@pure_quanta.q_res(chips)',
 P_PATH='@s9s_mb_2u_lib.s9s_mb_2u(sch_1):page170_i149@pure_quanta.q_res(chips)',
 PATH='I149',
 DRAWING='@S9S_MB_2U_LIB.S9S_MB_2U(SCH_1):PAGE161',
 PHYS_PAGE='170',
 XY='(4325,-2825)',
 ROT='0',
 VER='2',
 PACK_TYPE='0402LF',
 CDS_LIB='pure_quanta',
 CDS_PART_NAME='Q_RES_0402LF-1K,1%,1/16W,EMPTYA',
 WATTAGE='1/16W',
 TOLERANCE='1%',
 MATERIAL='EMPTY',
 VALUE='1K',
 PRIM_FILE='./archive_libs/logical/q_res/chips/chips.prt';

PART_NAME
 R4201 'Q_RES_0402LF-1K,1%,1/16W,CHIP,A':;

SECTION_NUMBER 1
 '@S9S_MB_2U_LIB.S9S_MB_2U(SCH_1):PAGE161_I147@PURE_QUANTA.Q_RES(CHIPS)':
 C_PATH='@s9s_mb_2u_lib.s9s_mb_2u(sch_1):page161_i147@pure_quanta.q_res(chips)',
 P_PATH='@s9s_mb_2u_lib.s9s_mb_2u(sch_1):page170_i147@pure_quanta.q_res(chips)',
 PATH='I147',
 DRAWING='@S9S_MB_2U_LIB.S9S_MB_2U(SCH_1):PAGE161',
 PHYS_PAGE='170',
 XY='(4325,-3425)',
 ROT='0',
 VER='2',
 PACK_TYPE='0402LF',
 CDS_LIB='pure_quanta',
 CDS_PART_NAME='Q_RES_0402LF-1K,1%,1/16W,CHIP,A',
 WATTAGE='1/16W',
 TOLERANCE='1%',
 MATERIAL='CHIP',
 VALUE='1K',
 PRIM_FILE='./archive_libs/logical/q_res/chips/chips.prt';

PART_NAME
 R4202 'Q_RES_0402LF-1K,1%,1/16W,EMPTYA':;

SECTION_NUMBER 1
 '@S9S_MB_2U_LIB.S9S_MB_2U(SCH_1):PAGE161_I129@PURE_QUANTA.Q_RES(CHIPS)':
 C_PATH='@s9s_mb_2u_lib.s9s_mb_2u(sch_1):page161_i129@pure_quanta.q_res(chips)',
 P_PATH='@s9s_mb_2u_lib.s9s_mb_2u(sch_1):page170_i129@pure_quanta.q_res(chips)',
 PATH='I129',
 DRAWING='@S9S_MB_2U_LIB.S9S_MB_2U(SCH_1):PAGE161',
 PHYS_PAGE='170',
 XY='(4375,-1350)',
 ROT='0',
 VER='2',
 PACK_TYPE='0402LF',
 CDS_LIB='pure_quanta',
 CDS_PART_NAME='Q_RES_0402LF-1K,1%,1/16W,EMPTYA',
 WATTAGE='1/16W',
 TOLERANCE='1%',
 MATERIAL='EMPTY',
 VALUE='1K',
 PRIM_FILE='./archive_libs/logical/q_res/chips/chips.prt';

PART_NAME
 R4203 'Q_RES_0402LF-1K,1%,1/16W,CHIP,A':;

SECTION_NUMBER 1
 '@S9S_MB_2U_LIB.S9S_MB_2U(SCH_1):PAGE161_I127@PURE_QUANTA.Q_RES(CHIPS)':
 C_PATH='@s9s_mb_2u_lib.s9s_mb_2u(sch_1):page161_i127@pure_quanta.q_res(chips)',
 P_PATH='@s9s_mb_2u_lib.s9s_mb_2u(sch_1):page170_i127@pure_quanta.q_res(chips)',
 PATH='I127',
 DRAWING='@S9S_MB_2U_LIB.S9S_MB_2U(SCH_1):PAGE161',
 PHYS_PAGE='170',
 XY='(4375,-1950)',
 ROT='0',
 VER='2',
 PACK_TYPE='0402LF',
 CDS_LIB='pure_quanta',
 CDS_PART_NAME='Q_RES_0402LF-1K,1%,1/16W,CHIP,A',
 WATTAGE='1/16W',
 TOLERANCE='1%',
 MATERIAL='CHIP',
 VALUE='1K',
 PRIM_FILE='./archive_libs/logical/q_res/chips/chips.prt';

PART_NAME
 R4204 'Q_RES_0402LF-1K,1%,1/16W,EMPTYA':;

SECTION_NUMBER 1
 '@S9S_MB_2U_LIB.S9S_MB_2U(SCH_1):PAGE161_I94@PURE_QUANTA.Q_RES(CHIPS)':
 C_PATH='@s9s_mb_2u_lib.s9s_mb_2u(sch_1):page161_i94@pure_quanta.q_res(chips)',
 P_PATH='@s9s_mb_2u_lib.s9s_mb_2u(sch_1):page170_i94@pure_quanta.q_res(chips)',
 PATH='I94',
 DRAWING='@S9S_MB_2U_LIB.S9S_MB_2U(SCH_1):PAGE161',
 PHYS_PAGE='170',
 XY='(4400,125)',
 ROT='0',
 VER='2',
 PACK_TYPE='0402LF',
 CDS_LIB='pure_quanta',
 CDS_PART_NAME='Q_RES_0402LF-1K,1%,1/16W,EMPTYA',
 WATTAGE='1/16W',
 TOLERANCE='1%',
 MATERIAL='EMPTY',
 VALUE='1K',
 PRIM_FILE='./archive_libs/logical/q_res/chips/chips.prt';

PART_NAME
 R4205 'Q_RES_0402LF-1K,1%,1/16W,CHIP,A':;

SECTION_NUMBER 1
 '@S9S_MB_2U_LIB.S9S_MB_2U(SCH_1):PAGE161_I96@PURE_QUANTA.Q_RES(CHIPS)':
 C_PATH='@s9s_mb_2u_lib.s9s_mb_2u(sch_1):page161_i96@pure_quanta.q_res(chips)',
 P_PATH='@s9s_mb_2u_lib.s9s_mb_2u(sch_1):page170_i96@pure_quanta.q_res(chips)',
 PATH='I96',
 DRAWING='@S9S_MB_2U_LIB.S9S_MB_2U(SCH_1):PAGE161',
 PHYS_PAGE='170',
 XY='(4400,-475)',
 ROT='0',
 VER='2',
 PACK_TYPE='0402LF',
 CDS_LIB='pure_quanta',
 CDS_PART_NAME='Q_RES_0402LF-1K,1%,1/16W,CHIP,A',
 WATTAGE='1/16W',
 TOLERANCE='1%',
 MATERIAL='CHIP',
 VALUE='1K',
 PRIM_FILE='./archive_libs/logical/q_res/chips/chips.prt';

PART_NAME
 R4206 'Q_RES_0402LF-1K,1%,1/16W,EMPTYA':;

SECTION_NUMBER 1
 '@S9S_MB_2U_LIB.S9S_MB_2U(SCH_1):PAGE161_I86@PURE_QUANTA.Q_RES(CHIPS)':
 C_PATH='@s9s_mb_2u_lib.s9s_mb_2u(sch_1):page161_i86@pure_quanta.q_res(chips)',
 P_PATH='@s9s_mb_2u_lib.s9s_mb_2u(sch_1):page170_i86@pure_quanta.q_res(chips)',
 PATH='I86',
 DRAWING='@S9S_MB_2U_LIB.S9S_MB_2U(SCH_1):PAGE161',
 PHYS_PAGE='170',
 XY='(4450,1600)',
 ROT='0',
 VER='2',
 PACK_TYPE='0402LF',
 CDS_LIB='pure_quanta',
 CDS_PART_NAME='Q_RES_0402LF-1K,1%,1/16W,EMPTYA',
 WATTAGE='1/16W',
 TOLERANCE='1%',
 MATERIAL='EMPTY',
 VALUE='1K',
 PRIM_FILE='./archive_libs/logical/q_res/chips/chips.prt';

PART_NAME
 R4207 'Q_RES_0402LF-1K,1%,1/16W,CHIP,A':;

SECTION_NUMBER 1
 '@S9S_MB_2U_LIB.S9S_MB_2U(SCH_1):PAGE161_I85@PURE_QUANTA.Q_RES(CHIPS)':
 C_PATH='@s9s_mb_2u_lib.s9s_mb_2u(sch_1):page161_i85@pure_quanta.q_res(chips)',
 P_PATH='@s9s_mb_2u_lib.s9s_mb_2u(sch_1):page170_i85@pure_quanta.q_res(chips)',
 PATH='I85',
 DRAWING='@S9S_MB_2U_LIB.S9S_MB_2U(SCH_1):PAGE161',
 PHYS_PAGE='170',
 XY='(4450,1000)',
 ROT='0',
 VER='2',
 PACK_TYPE='0402LF',
 CDS_LIB='pure_quanta',
 CDS_PART_NAME='Q_RES_0402LF-1K,1%,1/16W,CHIP,A',
 WATTAGE='1/16W',
 TOLERANCE='1%',
 MATERIAL='CHIP',
 VALUE='1K',
 PRIM_FILE='./archive_libs/logical/q_res/chips/chips.prt';

PART_NAME
 R4208 'Q_RES_0402LF-200K,1%,1/16W,EMPA':;

SECTION_NUMBER 1
 '@S9S_MB_2U_LIB.S9S_MB_2U(SCH_1):PAGE161_I171@PURE_QUANTA.Q_RES(CHIPS)':
 C_PATH='@s9s_mb_2u_lib.s9s_mb_2u(sch_1):page161_i171@pure_quanta.q_res(chips)',
 P_PATH='@s9s_mb_2u_lib.s9s_mb_2u(sch_1):page170_i171@pure_quanta.q_res(chips)',
 PATH='I171',
 DRAWING='@S9S_MB_2U_LIB.S9S_MB_2U(SCH_1):PAGE161',
 PHYS_PAGE='170',
 XY='(-350,-2625)',
 ROT='0',
 VER='2',
 PACK_TYPE='0402LF',
 LOCATION='R4208',
 CDS_LIB='pure_quanta',
 CDS_PART_NAME='Q_RES_0402LF-200K,1%,1/16W,EMPA',
 WATTAGE='1/16W',
 TOLERANCE='1%',
 MATERIAL='EMPTY',
 VALUE='200K',
 PRIM_FILE='./archive_libs/logical/q_res/chips/chips.prt';

PART_NAME
 R4209 'Q_RES_0402LF-200K,1%,1/16W,EMPA':;

SECTION_NUMBER 1
 '@S9S_MB_2U_LIB.S9S_MB_2U(SCH_1):PAGE161_I169@PURE_QUANTA.Q_RES(CHIPS)':
 C_PATH='@s9s_mb_2u_lib.s9s_mb_2u(sch_1):page161_i169@pure_quanta.q_res(chips)',
 P_PATH='@s9s_mb_2u_lib.s9s_mb_2u(sch_1):page170_i169@pure_quanta.q_res(chips)',
 PATH='I169',
 DRAWING='@S9S_MB_2U_LIB.S9S_MB_2U(SCH_1):PAGE161',
 PHYS_PAGE='170',
 XY='(-250,325)',
 ROT='0',
 VER='2',
 PACK_TYPE='0402LF',
 LOCATION='R4209',
 CDS_LIB='pure_quanta',
 CDS_PART_NAME='Q_RES_0402LF-200K,1%,1/16W,EMPA',
 WATTAGE='1/16W',
 TOLERANCE='1%',
 MATERIAL='EMPTY',
 VALUE='200K',
 PRIM_FILE='./archive_libs/logical/q_res/chips/chips.prt';

PART_NAME
 R4210 'Q_RES_0402LF-200K,1%,1/16W,EMPA':;

SECTION_NUMBER 1
 '@S9S_MB_2U_LIB.S9S_MB_2U(SCH_1):PAGE161_I170@PURE_QUANTA.Q_RES(CHIPS)':
 C_PATH='@s9s_mb_2u_lib.s9s_mb_2u(sch_1):page161_i170@pure_quanta.q_res(chips)',
 P_PATH='@s9s_mb_2u_lib.s9s_mb_2u(sch_1):page170_i170@pure_quanta.q_res(chips)',
 PATH='I170',
 DRAWING='@S9S_MB_2U_LIB.S9S_MB_2U(SCH_1):PAGE161',
 PHYS_PAGE='170',
 XY='(-250,-1175)',
 ROT='0',
 VER='2',
 PACK_TYPE='0402LF',
 LOCATION='R4210',
 CDS_LIB='pure_quanta',
 CDS_PART_NAME='Q_RES_0402LF-200K,1%,1/16W,EMPA',
 WATTAGE='1/16W',
 TOLERANCE='1%',
 MATERIAL='EMPTY',
 VALUE='200K',
 PRIM_FILE='./archive_libs/logical/q_res/chips/chips.prt';

PART_NAME
 R4211 'Q_RES_0402LF-200K,1%,1/16W,CHIA':;

SECTION_NUMBER 1
 '@S9S_MB_2U_LIB.S9S_MB_2U(SCH_1):PAGE161_I168@PURE_QUANTA.Q_RES(CHIPS)':
 C_PATH='@s9s_mb_2u_lib.s9s_mb_2u(sch_1):page161_i168@pure_quanta.q_res(chips)',
 P_PATH='@s9s_mb_2u_lib.s9s_mb_2u(sch_1):page170_i168@pure_quanta.q_res(chips)',
 PATH='I168',
 DRAWING='@S9S_MB_2U_LIB.S9S_MB_2U(SCH_1):PAGE161',
 PHYS_PAGE='170',
 XY='(-200,1800)',
 ROT='0',
 VER='2',
 PACK_TYPE='0402LF',
 LOCATION='R4211',
 CDS_LIB='pure_quanta',
 CDS_PART_NAME='Q_RES_0402LF-200K,1%,1/16W,CHIA',
 WATTAGE='1/16W',
 TOLERANCE='1%',
 MATERIAL='CHIP',
 VALUE='200K',
 PRIM_FILE='./archive_libs/logical/q_res/chips/chips.prt';

PART_NAME
 R4212 'Q_RES_0402LF-0,5%,1/16W,CHIP,CA':;

SECTION_NUMBER 1
 '@S9S_MB_2U_LIB.S9S_MB_2U(SCH_1):PAGE161_I135@PURE_QUANTA.Q_RES(CHIPS)':
 C_PATH='@s9s_mb_2u_lib.s9s_mb_2u(sch_1):page161_i135@pure_quanta.q_res(chips)',
 P_PATH='@s9s_mb_2u_lib.s9s_mb_2u(sch_1):page170_i135@pure_quanta.q_res(chips)',
 PATH='I135',
 DRAWING='@S9S_MB_2U_LIB.S9S_MB_2U(SCH_1):PAGE161',
 PHYS_PAGE='170',
 XY='(225,-3125)',
 ROT='0',
 VER='1',
 PACK_TYPE='0402LF',
 CDS_LIB='pure_quanta',
 CDS_PART_NAME='Q_RES_0402LF-0,5%,1/16W,CHIP,CA',
 WATTAGE='1/16W',
 TOLERANCE='5%',
 MATERIAL='CHIP',
 VALUE='0',
 PRIM_FILE='./archive_libs/logical/q_res/chips/chips.prt';

PART_NAME
 R4213 'Q_RES_0402LF-0,5%,1/16W,CHIP,CA':;

SECTION_NUMBER 1
 '@S9S_MB_2U_LIB.S9S_MB_2U(SCH_1):PAGE161_I115@PURE_QUANTA.Q_RES(CHIPS)':
 C_PATH='@s9s_mb_2u_lib.s9s_mb_2u(sch_1):page161_i115@pure_quanta.q_res(chips)',
 P_PATH='@s9s_mb_2u_lib.s9s_mb_2u(sch_1):page170_i115@pure_quanta.q_res(chips)',
 PATH='I115',
 DRAWING='@S9S_MB_2U_LIB.S9S_MB_2U(SCH_1):PAGE161',
 PHYS_PAGE='170',
 XY='(275,-1650)',
 ROT='0',
 VER='1',
 PACK_TYPE='0402LF',
 CDS_LIB='pure_quanta',
 CDS_PART_NAME='Q_RES_0402LF-0,5%,1/16W,CHIP,CA',
 WATTAGE='1/16W',
 TOLERANCE='5%',
 MATERIAL='CHIP',
 VALUE='0',
 PRIM_FILE='./archive_libs/logical/q_res/chips/chips.prt';

PART_NAME
 R4214 'Q_RES_0402LF-0,5%,1/16W,CHIP,CA':;

SECTION_NUMBER 1
 '@S9S_MB_2U_LIB.S9S_MB_2U(SCH_1):PAGE161_I108@PURE_QUANTA.Q_RES(CHIPS)':
 C_PATH='@s9s_mb_2u_lib.s9s_mb_2u(sch_1):page161_i108@pure_quanta.q_res(chips)',
 P_PATH='@s9s_mb_2u_lib.s9s_mb_2u(sch_1):page170_i108@pure_quanta.q_res(chips)',
 PATH='I108',
 DRAWING='@S9S_MB_2U_LIB.S9S_MB_2U(SCH_1):PAGE161',
 PHYS_PAGE='170',
 XY='(300,-175)',
 ROT='0',
 VER='1',
 PACK_TYPE='0402LF',
 CDS_LIB='pure_quanta',
 CDS_PART_NAME='Q_RES_0402LF-0,5%,1/16W,CHIP,CA',
 WATTAGE='1/16W',
 TOLERANCE='5%',
 MATERIAL='CHIP',
 VALUE='0',
 PRIM_FILE='./archive_libs/logical/q_res/chips/chips.prt';

PART_NAME
 R4215 'Q_RES_0402LF-0,5%,1/16W,CHIP,CA':;

SECTION_NUMBER 1
 '@S9S_MB_2U_LIB.S9S_MB_2U(SCH_1):PAGE161_I79@PURE_QUANTA.Q_RES(CHIPS)':
 C_PATH='@s9s_mb_2u_lib.s9s_mb_2u(sch_1):page161_i79@pure_quanta.q_res(chips)',
 P_PATH='@s9s_mb_2u_lib.s9s_mb_2u(sch_1):page170_i79@pure_quanta.q_res(chips)',
 PATH='I79',
 DRAWING='@S9S_MB_2U_LIB.S9S_MB_2U(SCH_1):PAGE161',
 PHYS_PAGE='170',
 XY='(350,1300)',
 ROT='0',
 VER='1',
 PACK_TYPE='0402LF',
 CDS_LIB='pure_quanta',
 CDS_PART_NAME='Q_RES_0402LF-0,5%,1/16W,CHIP,CA',
 WATTAGE='1/16W',
 TOLERANCE='5%',
 MATERIAL='CHIP',
 VALUE='0',
 PRIM_FILE='./archive_libs/logical/q_res/chips/chips.prt';

PART_NAME
 R4216 'Q_RES_0402LF-0,5%,1/16W,CHIP,CA':;

SECTION_NUMBER 1
 '@S9S_MB_2U_LIB.S9S_MB_2U(SCH_1):PAGE252_I56@PURE_QUANTA.Q_RES(CHIPS)':
 C_PATH='@s9s_mb_2u_lib.s9s_mb_2u(sch_1):page252_i56@pure_quanta.q_res(chips)',
 P_PATH='@s9s_mb_2u_lib.s9s_mb_2u(sch_1):page266_i56@pure_quanta.q_res(chips)',
 PATH='I56',
 DRAWING='@S9S_MB_2U_LIB.S9S_MB_2U(SCH_1):PAGE252',
 PHYS_PAGE='266',
 XY='(-4950,2150)',
 ROT='0',
 VER='1',
 PACK_TYPE='0402LF',
 CDS_LIB='pure_quanta',
 CDS_PART_NAME='Q_RES_0402LF-0,5%,1/16W,CHIP,CA',
 WATTAGE='1/16W',
 TOLERANCE='5%',
 MATERIAL='CHIP',
 VALUE='0',
 PRIM_FILE='./archive_libs/logical/q_res/chips/chips.prt';

PART_NAME
 R4259 'Q_RES_0402LF-33.2,1%,1/16W,CHIA':;

SECTION_NUMBER 1
 '@S9S_MB_2U_LIB.S9S_MB_2U(SCH_1):PAGE313_I147@PURE_QUANTA.Q_RES(CHIPS)':
 C_PATH='@s9s_mb_2u_lib.s9s_mb_2u(sch_1):page313_i147@pure_quanta.q_res(chips)',
 P_PATH='@s9s_mb_2u_lib.s9s_mb_2u(sch_1):page214_i147@pure_quanta.q_res(chips)',
 PATH='I147',
 DRAWING='@S9S_MB_2U_LIB.S9S_MB_2U(SCH_1):PAGE313',
 PHYS_PAGE='214',
 XY='(2675,-2650)',
 ROT='0',
 VER='1',
 PACK_TYPE='0402LF',
 CDS_LIB='pure_quanta',
 CDS_PART_NAME='Q_RES_0402LF-33.2,1%,1/16W,CHIA',
 WATTAGE='1/16W',
 TOLERANCE='1%',
 MATERIAL='CHIP',
 VALUE='33.2',
 PRIM_FILE='./archive_libs/logical/q_res/chips/chips.prt';

PART_NAME
 R4260 'Q_RES_0402LF-240,1%,1/16W,EMPTA':;

SECTION_NUMBER 1
 '@S9S_MB_2U_LIB.S9S_MB_2U(SCH_1):PAGE119_I219@PURE_QUANTA.Q_RES(CHIPS)':
 C_PATH='@s9s_mb_2u_lib.s9s_mb_2u(sch_1):page119_i219@pure_quanta.q_res(chips)',
 P_PATH='@s9s_mb_2u_lib.s9s_mb_2u(sch_1):page119_i219@pure_quanta.q_res(chips)',
 PATH='I219',
 DRAWING='@S9S_MB_2U_LIB.S9S_MB_2U(SCH_1):PAGE119',
 PHYS_PAGE='119',
 XY='(5050,-950)',
 ROT='5',
 VER='1',
 PACK_TYPE='0402LF',
 CDS_LIB='pure_quanta',
 CDS_PART_NAME='Q_RES_0402LF-240,1%,1/16W,EMPTA',
 WATTAGE='1/16W',
 TOLERANCE='1%',
 MATERIAL='EMPTY',
 VALUE='240',
 PRIM_FILE='./archive_libs/logical/q_res/chips/chips.prt';

PART_NAME
 R4261 'Q_RES_0402LF-240,1%,1/16W,EMPTA':;

SECTION_NUMBER 1
 '@S9S_MB_2U_LIB.S9S_MB_2U(SCH_1):PAGE119_I220@PURE_QUANTA.Q_RES(CHIPS)':
 C_PATH='@s9s_mb_2u_lib.s9s_mb_2u(sch_1):page119_i220@pure_quanta.q_res(chips)',
 P_PATH='@s9s_mb_2u_lib.s9s_mb_2u(sch_1):page119_i220@pure_quanta.q_res(chips)',
 PATH='I220',
 DRAWING='@S9S_MB_2U_LIB.S9S_MB_2U(SCH_1):PAGE119',
 PHYS_PAGE='119',
 XY='(5050,-1275)',
 ROT='5',
 VER='1',
 PACK_TYPE='0402LF',
 CDS_LIB='pure_quanta',
 CDS_PART_NAME='Q_RES_0402LF-240,1%,1/16W,EMPTA',
 WATTAGE='1/16W',
 TOLERANCE='1%',
 MATERIAL='EMPTY',
 VALUE='240',
 PRIM_FILE='./archive_libs/logical/q_res/chips/chips.prt';

PART_NAME
 R4262 'Q_RES_0402LF-240,1%,1/16W,EMPTA':;

SECTION_NUMBER 1
 '@S9S_MB_2U_LIB.S9S_MB_2U(SCH_1):PAGE119_I215@PURE_QUANTA.Q_RES(CHIPS)':
 C_PATH='@s9s_mb_2u_lib.s9s_mb_2u(sch_1):page119_i215@pure_quanta.q_res(chips)',
 P_PATH='@s9s_mb_2u_lib.s9s_mb_2u(sch_1):page119_i215@pure_quanta.q_res(chips)',
 PATH='I215',
 DRAWING='@S9S_MB_2U_LIB.S9S_MB_2U(SCH_1):PAGE119',
 PHYS_PAGE='119',
 XY='(5075,3350)',
 ROT='5',
 VER='1',
 PACK_TYPE='0402LF',
 CDS_LIB='pure_quanta',
 CDS_PART_NAME='Q_RES_0402LF-240,1%,1/16W,EMPTA',
 WATTAGE='1/16W',
 TOLERANCE='1%',
 MATERIAL='EMPTY',
 VALUE='240',
 PRIM_FILE='./archive_libs/logical/q_res/chips/chips.prt';

PART_NAME
 R4263 'Q_RES_0402LF-240,1%,1/16W,EMPTA':;

SECTION_NUMBER 1
 '@S9S_MB_2U_LIB.S9S_MB_2U(SCH_1):PAGE119_I216@PURE_QUANTA.Q_RES(CHIPS)':
 C_PATH='@s9s_mb_2u_lib.s9s_mb_2u(sch_1):page119_i216@pure_quanta.q_res(chips)',
 P_PATH='@s9s_mb_2u_lib.s9s_mb_2u(sch_1):page119_i216@pure_quanta.q_res(chips)',
 PATH='I216',
 DRAWING='@S9S_MB_2U_LIB.S9S_MB_2U(SCH_1):PAGE119',
 PHYS_PAGE='119',
 XY='(5075,3025)',
 ROT='5',
 VER='1',
 PACK_TYPE='0402LF',
 CDS_LIB='pure_quanta',
 CDS_PART_NAME='Q_RES_0402LF-240,1%,1/16W,EMPTA',
 WATTAGE='1/16W',
 TOLERANCE='1%',
 MATERIAL='EMPTY',
 VALUE='240',
 PRIM_FILE='./archive_libs/logical/q_res/chips/chips.prt';

PART_NAME
 R4264 'Q_RES_0402LF-4.7K,5%,1/16W,CHIA':;

SECTION_NUMBER 1
 '@S9S_MB_2U_LIB.S9S_MB_2U(SCH_1):PAGE230_I47@PURE_QUANTA.Q_RES(CHIPS)':
 C_PATH='@s9s_mb_2u_lib.s9s_mb_2u(sch_1):page230_i47@pure_quanta.q_res(chips)',
 P_PATH='@s9s_mb_2u_lib.s9s_mb_2u(sch_1):page246_i47@pure_quanta.q_res(chips)',
 PATH='I47',
 DRAWING='@S9S_MB_2U_LIB.S9S_MB_2U(SCH_1):PAGE230',
 PHYS_PAGE='246',
 XY='(2150,525)',
 ROT='0',
 VER='2',
 PACK_TYPE='0402LF',
 CDS_LIB='pure_quanta',
 CDS_PART_NAME='Q_RES_0402LF-4.7K,5%,1/16W,CHIA',
 WATTAGE='1/16W',
 TOLERANCE='5%',
 MATERIAL='CHIP',
 VALUE='4.7K',
 PRIM_FILE='./archive_libs/logical/q_res/chips/chips.prt';

PART_NAME
 R4265 'Q_RES_0402LF-4.7K,5%,1/16W,EMPA':;

SECTION_NUMBER 1
 '@S9S_MB_2U_LIB.S9S_MB_2U(SCH_1):PAGE230_I43@PURE_QUANTA.Q_RES(CHIPS)':
 C_PATH='@s9s_mb_2u_lib.s9s_mb_2u(sch_1):page230_i43@pure_quanta.q_res(chips)',
 P_PATH='@s9s_mb_2u_lib.s9s_mb_2u(sch_1):page246_i43@pure_quanta.q_res(chips)',
 PATH='I43',
 DRAWING='@S9S_MB_2U_LIB.S9S_MB_2U(SCH_1):PAGE230',
 PHYS_PAGE='246',
 XY='(2175,-25)',
 ROT='0',
 VER='2',
 PACK_TYPE='0402LF',
 CDS_LIB='pure_quanta',
 CDS_PART_NAME='Q_RES_0402LF-4.7K,5%,1/16W,EMPA',
 WATTAGE='1/16W',
 TOLERANCE='5%',
 MATERIAL='EMPTY',
 VALUE='4.7K',
 PRIM_FILE='./archive_libs/logical/q_res/chips/chips.prt';

PART_NAME
 R4266 'Q_RES_0402LF-33.2,1%,1/16W,CHIA':;

SECTION_NUMBER 1
 '@S9S_MB_2U_LIB.S9S_MB_2U(SCH_1):PAGE230_I48@PURE_QUANTA.Q_RES(CHIPS)':
 C_PATH='@s9s_mb_2u_lib.s9s_mb_2u(sch_1):page230_i48@pure_quanta.q_res(chips)',
 P_PATH='@s9s_mb_2u_lib.s9s_mb_2u(sch_1):page246_i48@pure_quanta.q_res(chips)',
 PATH='I48',
 DRAWING='@S9S_MB_2U_LIB.S9S_MB_2U(SCH_1):PAGE230',
 PHYS_PAGE='246',
 XY='(2400,275)',
 ROT='0',
 VER='1',
 PACK_TYPE='0402LF',
 CDS_LIB='pure_quanta',
 CDS_PART_NAME='Q_RES_0402LF-33.2,1%,1/16W,CHIA',
 WATTAGE='1/16W',
 TOLERANCE='1%',
 MATERIAL='CHIP',
 VALUE='33.2',
 PRIM_FILE='./archive_libs/logical/q_res/chips/chips.prt';

PART_NAME
 R4267 'Q_RES_0402LF-33.2,1%,1/16W,CHIA':;

SECTION_NUMBER 1
 '@S9S_MB_2U_LIB.S9S_MB_2U(SCH_1):PAGE211_I129@PURE_QUANTA.Q_RES(CHIPS)':
 C_PATH='@s9s_mb_2u_lib.s9s_mb_2u(sch_1):page211_i129@pure_quanta.q_res(chips)',
 P_PATH='@s9s_mb_2u_lib.s9s_mb_2u(sch_1):page222_i129@pure_quanta.q_res(chips)',
 PATH='I129',
 DRAWING='@S9S_MB_2U_LIB.S9S_MB_2U(SCH_1):PAGE211',
 PHYS_PAGE='222',
 XY='(-1650,150)',
 ROT='0',
 VER='1',
 PACK_TYPE='0402LF',
 CDS_LIB='pure_quanta',
 CDS_PART_NAME='Q_RES_0402LF-33.2,1%,1/16W,CHIA',
 WATTAGE='1/16W',
 TOLERANCE='1%',
 MATERIAL='CHIP',
 VALUE='33.2',
 PRIM_FILE='./archive_libs/logical/q_res/chips/chips.prt';

PART_NAME
 R4268 'Q_RES_0402LF-0,5%,1/16W,CHIP,CA':;

SECTION_NUMBER 1
 '@S9S_MB_2U_LIB.S9S_MB_2U(SCH_1):PAGE230_I41@PURE_QUANTA.Q_RES(CHIPS)':
 C_PATH='@s9s_mb_2u_lib.s9s_mb_2u(sch_1):page230_i41@pure_quanta.q_res(chips)',
 P_PATH='@s9s_mb_2u_lib.s9s_mb_2u(sch_1):page246_i41@pure_quanta.q_res(chips)',
 PATH='I41',
 DRAWING='@S9S_MB_2U_LIB.S9S_MB_2U(SCH_1):PAGE230',
 PHYS_PAGE='246',
 XY='(-1125,275)',
 ROT='0',
 VER='1',
 PACK_TYPE='0402LF',
 CDS_LIB='pure_quanta',
 CDS_PART_NAME='Q_RES_0402LF-0,5%,1/16W,CHIP,CA',
 WATTAGE='1/16W',
 TOLERANCE='5%',
 MATERIAL='CHIP',
 VALUE='0',
 PRIM_FILE='./archive_libs/logical/q_res/chips/chips.prt';

PART_NAME
 R4269 'Q_RES_0402LF-2.2K,5%,1/16W,EMPA':;

SECTION_NUMBER 1
 '@S9S_MB_2U_LIB.S9S_MB_2U(SCH_1):PAGE221_I102@PURE_QUANTA.Q_RES(CHIPS)':
 C_PATH='@s9s_mb_2u_lib.s9s_mb_2u(sch_1):page221_i102@pure_quanta.q_res(chips)',
 P_PATH='@s9s_mb_2u_lib.s9s_mb_2u(sch_1):page233_i102@pure_quanta.q_res(chips)',
 PATH='I102',
 DRAWING='@S9S_MB_2U_LIB.S9S_MB_2U(SCH_1):PAGE221',
 PHYS_PAGE='233',
 XY='(1975,-425)',
 ROT='0',
 VER='1',
 PACK_TYPE='0402LF',
 CDS_LIB='pure_quanta',
 CDS_PART_NAME='Q_RES_0402LF-2.2K,5%,1/16W,EMPA',
 WATTAGE='1/16W',
 TOLERANCE='5%',
 MATERIAL='EMPTY',
 VALUE='2.2K',
 PRIM_FILE='./archive_libs/logical/q_res/chips/chips.prt';

PART_NAME
 R4270 'Q_RES_0402LF-2.2K,5%,1/16W,EMPA':;

SECTION_NUMBER 1
 '@S9S_MB_2U_LIB.S9S_MB_2U(SCH_1):PAGE221_I99@PURE_QUANTA.Q_RES(CHIPS)':
 C_PATH='@s9s_mb_2u_lib.s9s_mb_2u(sch_1):page221_i99@pure_quanta.q_res(chips)',
 P_PATH='@s9s_mb_2u_lib.s9s_mb_2u(sch_1):page233_i99@pure_quanta.q_res(chips)',
 PATH='I99',
 DRAWING='@S9S_MB_2U_LIB.S9S_MB_2U(SCH_1):PAGE221',
 PHYS_PAGE='233',
 XY='(1975,-475)',
 ROT='0',
 VER='1',
 PACK_TYPE='0402LF',
 CDS_LIB='pure_quanta',
 CDS_PART_NAME='Q_RES_0402LF-2.2K,5%,1/16W,EMPA',
 WATTAGE='1/16W',
 TOLERANCE='5%',
 MATERIAL='EMPTY',
 VALUE='2.2K',
 PRIM_FILE='./archive_libs/logical/q_res/chips/chips.prt';

PART_NAME
 R4273 'Q_RES_0402LF-1K,1%,1/16W,EMPTYA':;

SECTION_NUMBER 1
 '@S9S_MB_2U_LIB.S9S_MB_2U(SCH_1):PAGE162_I12@PURE_QUANTA.Q_RES(CHIPS)':
 C_PATH='@s9s_mb_2u_lib.s9s_mb_2u(sch_1):page162_i12@pure_quanta.q_res(chips)',
 P_PATH='@s9s_mb_2u_lib.s9s_mb_2u(sch_1):page169_i12@pure_quanta.q_res(chips)',
 PATH='I12',
 DRAWING='@S9S_MB_2U_LIB.S9S_MB_2U(SCH_1):PAGE162',
 PHYS_PAGE='169',
 XY='(-5350,1625)',
 ROT='0',
 VER='2',
 PACK_TYPE='0402LF',
 CDS_LIB='pure_quanta',
 CDS_PART_NAME='Q_RES_0402LF-1K,1%,1/16W,EMPTYA',
 WATTAGE='1/16W',
 TOLERANCE='1%',
 MATERIAL='EMPTY',
 VALUE='1K',
 PRIM_FILE='./archive_libs/logical/q_res/chips/chips.prt';

PART_NAME
 R4274 'Q_RES_0402LF-1K,1%,1/16W,EMPTYA':;

SECTION_NUMBER 1
 '@S9S_MB_2U_LIB.S9S_MB_2U(SCH_1):PAGE162_I11@PURE_QUANTA.Q_RES(CHIPS)':
 C_PATH='@s9s_mb_2u_lib.s9s_mb_2u(sch_1):page162_i11@pure_quanta.q_res(chips)',
 P_PATH='@s9s_mb_2u_lib.s9s_mb_2u(sch_1):page169_i11@pure_quanta.q_res(chips)',
 PATH='I11',
 DRAWING='@S9S_MB_2U_LIB.S9S_MB_2U(SCH_1):PAGE162',
 PHYS_PAGE='169',
 XY='(-5350,1100)',
 ROT='0',
 VER='2',
 PACK_TYPE='0402LF',
 CDS_LIB='pure_quanta',
 CDS_PART_NAME='Q_RES_0402LF-1K,1%,1/16W,EMPTYA',
 WATTAGE='1/16W',
 TOLERANCE='1%',
 MATERIAL='EMPTY',
 VALUE='1K',
 PRIM_FILE='./archive_libs/logical/q_res/chips/chips.prt';

PART_NAME
 R4275 'Q_RES_0402LF-1K,1%,1/16W,EMPTYA':;

SECTION_NUMBER 1
 '@S9S_MB_2U_LIB.S9S_MB_2U(SCH_1):PAGE162_I3@PURE_QUANTA.Q_RES(CHIPS)':
 C_PATH='@s9s_mb_2u_lib.s9s_mb_2u(sch_1):page162_i3@pure_quanta.q_res(chips)',
 P_PATH='@s9s_mb_2u_lib.s9s_mb_2u(sch_1):page169_i3@pure_quanta.q_res(chips)',
 PATH='I3',
 DRAWING='@S9S_MB_2U_LIB.S9S_MB_2U(SCH_1):PAGE162',
 PHYS_PAGE='169',
 XY='(-5025,-125)',
 ROT='0',
 VER='2',
 PACK_TYPE='0402LF',
 CDS_LIB='pure_quanta',
 CDS_PART_NAME='Q_RES_0402LF-1K,1%,1/16W,EMPTYA',
 WATTAGE='1/16W',
 TOLERANCE='1%',
 MATERIAL='EMPTY',
 VALUE='1K',
 PRIM_FILE='./archive_libs/logical/q_res/chips/chips.prt';

PART_NAME
 R4276 'Q_RES_0402LF-68K,1%,1/16W,CHIPA':;

SECTION_NUMBER 1
 '@S9S_MB_2U_LIB.S9S_MB_2U(SCH_1):PAGE162_I2@PURE_QUANTA.Q_RES(CHIPS)':
 C_PATH='@s9s_mb_2u_lib.s9s_mb_2u(sch_1):page162_i2@pure_quanta.q_res(chips)',
 P_PATH='@s9s_mb_2u_lib.s9s_mb_2u(sch_1):page169_i2@pure_quanta.q_res(chips)',
 PATH='I2',
 DRAWING='@S9S_MB_2U_LIB.S9S_MB_2U(SCH_1):PAGE162',
 PHYS_PAGE='169',
 XY='(-5025,-650)',
 ROT='0',
 VER='2',
 PACK_TYPE='0402LF',
 LOCATION='R4276',
 CDS_LIB='pure_quanta',
 CDS_PART_NAME='Q_RES_0402LF-68K,1%,1/16W,CHIPA',
 WATTAGE='1/16W',
 TOLERANCE='1%',
 MATERIAL='CHIP',
 VALUE='68K',
 PRIM_FILE='./archive_libs/logical/q_res/chips/chips.prt';

PART_NAME
 R4279 'Q_RES_0402LF-1K,1%,1/16W,EMPTYA':;

SECTION_NUMBER 1
 '@S9S_MB_2U_LIB.S9S_MB_2U(SCH_1):PAGE162_I18@PURE_QUANTA.Q_RES(CHIPS)':
 C_PATH='@s9s_mb_2u_lib.s9s_mb_2u(sch_1):page162_i18@pure_quanta.q_res(chips)',
 P_PATH='@s9s_mb_2u_lib.s9s_mb_2u(sch_1):page169_i18@pure_quanta.q_res(chips)',
 PATH='I18',
 DRAWING='@S9S_MB_2U_LIB.S9S_MB_2U(SCH_1):PAGE162',
 PHYS_PAGE='169',
 XY='(-4475,1625)',
 ROT='0',
 VER='2',
 PACK_TYPE='0402LF',
 CDS_LIB='pure_quanta',
 CDS_PART_NAME='Q_RES_0402LF-1K,1%,1/16W,EMPTYA',
 WATTAGE='1/16W',
 TOLERANCE='1%',
 MATERIAL='EMPTY',
 VALUE='1K',
 PRIM_FILE='./archive_libs/logical/q_res/chips/chips.prt';

PART_NAME
 R4280 'Q_RES_0402LF-1K,1%,1/16W,EMPTYA':;

SECTION_NUMBER 1
 '@S9S_MB_2U_LIB.S9S_MB_2U(SCH_1):PAGE162_I17@PURE_QUANTA.Q_RES(CHIPS)':
 C_PATH='@s9s_mb_2u_lib.s9s_mb_2u(sch_1):page162_i17@pure_quanta.q_res(chips)',
 P_PATH='@s9s_mb_2u_lib.s9s_mb_2u(sch_1):page169_i17@pure_quanta.q_res(chips)',
 PATH='I17',
 DRAWING='@S9S_MB_2U_LIB.S9S_MB_2U(SCH_1):PAGE162',
 PHYS_PAGE='169',
 XY='(-4475,1050)',
 ROT='0',
 VER='2',
 PACK_TYPE='0402LF',
 CDS_LIB='pure_quanta',
 CDS_PART_NAME='Q_RES_0402LF-1K,1%,1/16W,EMPTYA',
 WATTAGE='1/16W',
 TOLERANCE='1%',
 MATERIAL='EMPTY',
 VALUE='1K',
 PRIM_FILE='./archive_libs/logical/q_res/chips/chips.prt';

PART_NAME
 R4281 'Q_RES_0402LF-1K,1%,1/16W,EMPTYA':;

SECTION_NUMBER 1
 '@S9S_MB_2U_LIB.S9S_MB_2U(SCH_1):PAGE162_I7@PURE_QUANTA.Q_RES(CHIPS)':
 C_PATH='@s9s_mb_2u_lib.s9s_mb_2u(sch_1):page162_i7@pure_quanta.q_res(chips)',
 P_PATH='@s9s_mb_2u_lib.s9s_mb_2u(sch_1):page169_i7@pure_quanta.q_res(chips)',
 PATH='I7',
 DRAWING='@S9S_MB_2U_LIB.S9S_MB_2U(SCH_1):PAGE162',
 PHYS_PAGE='169',
 XY='(-4150,-125)',
 ROT='0',
 VER='2',
 PACK_TYPE='0402LF',
 CDS_LIB='pure_quanta',
 CDS_PART_NAME='Q_RES_0402LF-1K,1%,1/16W,EMPTYA',
 WATTAGE='1/16W',
 TOLERANCE='1%',
 MATERIAL='EMPTY',
 VALUE='1K',
 PRIM_FILE='./archive_libs/logical/q_res/chips/chips.prt';

PART_NAME
 R4282 'Q_RES_0402LF-68K,1%,1/16W,CHIPA':;

SECTION_NUMBER 1
 '@S9S_MB_2U_LIB.S9S_MB_2U(SCH_1):PAGE162_I6@PURE_QUANTA.Q_RES(CHIPS)':
 C_PATH='@s9s_mb_2u_lib.s9s_mb_2u(sch_1):page162_i6@pure_quanta.q_res(chips)',
 P_PATH='@s9s_mb_2u_lib.s9s_mb_2u(sch_1):page169_i6@pure_quanta.q_res(chips)',
 PATH='I6',
 DRAWING='@S9S_MB_2U_LIB.S9S_MB_2U(SCH_1):PAGE162',
 PHYS_PAGE='169',
 XY='(-4150,-700)',
 ROT='0',
 VER='2',
 PACK_TYPE='0402LF',
 LOCATION='R4282',
 CDS_LIB='pure_quanta',
 CDS_PART_NAME='Q_RES_0402LF-68K,1%,1/16W,CHIPA',
 WATTAGE='1/16W',
 TOLERANCE='1%',
 MATERIAL='CHIP',
 VALUE='68K',
 PRIM_FILE='./archive_libs/logical/q_res/chips/chips.prt';

PART_NAME
 R4284 'Q_RES_0402LF-1K,1%,1/16W,EMPTYA':;

SECTION_NUMBER 1
 '@S9S_MB_2U_LIB.S9S_MB_2U(SCH_1):PAGE162_I41@PURE_QUANTA.Q_RES(CHIPS)':
 C_PATH='@s9s_mb_2u_lib.s9s_mb_2u(sch_1):page162_i41@pure_quanta.q_res(chips)',
 P_PATH='@s9s_mb_2u_lib.s9s_mb_2u(sch_1):page169_i41@pure_quanta.q_res(chips)',
 PATH='I41',
 DRAWING='@S9S_MB_2U_LIB.S9S_MB_2U(SCH_1):PAGE162',
 PHYS_PAGE='169',
 XY='(-750,1600)',
 ROT='0',
 VER='2',
 PACK_TYPE='0402LF',
 CDS_LIB='pure_quanta',
 CDS_PART_NAME='Q_RES_0402LF-1K,1%,1/16W,EMPTYA',
 WATTAGE='1/16W',
 TOLERANCE='1%',
 MATERIAL='EMPTY',
 VALUE='1K',
 PRIM_FILE='./archive_libs/logical/q_res/chips/chips.prt';

PART_NAME
 R4285 'Q_RES_0402LF-1K,1%,1/16W,EMPTYA':;

SECTION_NUMBER 1
 '@S9S_MB_2U_LIB.S9S_MB_2U(SCH_1):PAGE162_I40@PURE_QUANTA.Q_RES(CHIPS)':
 C_PATH='@s9s_mb_2u_lib.s9s_mb_2u(sch_1):page162_i40@pure_quanta.q_res(chips)',
 P_PATH='@s9s_mb_2u_lib.s9s_mb_2u(sch_1):page169_i40@pure_quanta.q_res(chips)',
 PATH='I40',
 DRAWING='@S9S_MB_2U_LIB.S9S_MB_2U(SCH_1):PAGE162',
 PHYS_PAGE='169',
 XY='(-750,1075)',
 ROT='0',
 VER='2',
 PACK_TYPE='0402LF',
 CDS_LIB='pure_quanta',
 CDS_PART_NAME='Q_RES_0402LF-1K,1%,1/16W,EMPTYA',
 WATTAGE='1/16W',
 TOLERANCE='1%',
 MATERIAL='EMPTY',
 VALUE='1K',
 PRIM_FILE='./archive_libs/logical/q_res/chips/chips.prt';

PART_NAME
 R4287 'Q_RES_0402LF-1K,1%,1/16W,EMPTYA':;

SECTION_NUMBER 1
 '@S9S_MB_2U_LIB.S9S_MB_2U(SCH_1):PAGE162_I49@PURE_QUANTA.Q_RES(CHIPS)':
 C_PATH='@s9s_mb_2u_lib.s9s_mb_2u(sch_1):page162_i49@pure_quanta.q_res(chips)',
 P_PATH='@s9s_mb_2u_lib.s9s_mb_2u(sch_1):page169_i49@pure_quanta.q_res(chips)',
 PATH='I49',
 DRAWING='@S9S_MB_2U_LIB.S9S_MB_2U(SCH_1):PAGE162',
 PHYS_PAGE='169',
 XY='(125,1600)',
 ROT='0',
 VER='2',
 PACK_TYPE='0402LF',
 CDS_LIB='pure_quanta',
 CDS_PART_NAME='Q_RES_0402LF-1K,1%,1/16W,EMPTYA',
 WATTAGE='1/16W',
 TOLERANCE='1%',
 MATERIAL='EMPTY',
 VALUE='1K',
 PRIM_FILE='./archive_libs/logical/q_res/chips/chips.prt';

PART_NAME
 R4288 'Q_RES_0402LF-1K,1%,1/16W,EMPTYA':;

SECTION_NUMBER 1
 '@S9S_MB_2U_LIB.S9S_MB_2U(SCH_1):PAGE162_I48@PURE_QUANTA.Q_RES(CHIPS)':
 C_PATH='@s9s_mb_2u_lib.s9s_mb_2u(sch_1):page162_i48@pure_quanta.q_res(chips)',
 P_PATH='@s9s_mb_2u_lib.s9s_mb_2u(sch_1):page169_i48@pure_quanta.q_res(chips)',
 PATH='I48',
 DRAWING='@S9S_MB_2U_LIB.S9S_MB_2U(SCH_1):PAGE162',
 PHYS_PAGE='169',
 XY='(125,1025)',
 ROT='0',
 VER='2',
 PACK_TYPE='0402LF',
 CDS_LIB='pure_quanta',
 CDS_PART_NAME='Q_RES_0402LF-1K,1%,1/16W,EMPTYA',
 WATTAGE='1/16W',
 TOLERANCE='1%',
 MATERIAL='EMPTY',
 VALUE='1K',
 PRIM_FILE='./archive_libs/logical/q_res/chips/chips.prt';

PART_NAME
 R4289 'Q_RES_0402LF-4.7K,1%,1/16W,EMPA':;

SECTION_NUMBER 1
 '@S9S_MB_2U_LIB.S9S_MB_2U(SCH_1):PAGE162_I69@PURE_QUANTA.Q_RES(CHIPS)':
 C_PATH='@s9s_mb_2u_lib.s9s_mb_2u(sch_1):page162_i69@pure_quanta.q_res(chips)',
 P_PATH='@s9s_mb_2u_lib.s9s_mb_2u(sch_1):page169_i69@pure_quanta.q_res(chips)',
 PATH='I69',
 DRAWING='@S9S_MB_2U_LIB.S9S_MB_2U(SCH_1):PAGE162',
 PHYS_PAGE='169',
 XY='(2000,4175)',
 ROT='0',
 VER='2',
 PACK_TYPE='0402LF',
 CDS_LIB='pure_quanta',
 CDS_PART_NAME='Q_RES_0402LF-4.7K,1%,1/16W,EMPA',
 WATTAGE='1/16W',
 TOLERANCE='1%',
 MATERIAL='EMPTY',
 VALUE='4.7K',
 PRIM_FILE='./archive_libs/logical/q_res/chips/chips.prt';

PART_NAME
 R4290 'Q_RES_0402LF-4.7K,1%,1/16W,EMPA':;

SECTION_NUMBER 1
 '@S9S_MB_2U_LIB.S9S_MB_2U(SCH_1):PAGE162_I68@PURE_QUANTA.Q_RES(CHIPS)':
 C_PATH='@s9s_mb_2u_lib.s9s_mb_2u(sch_1):page162_i68@pure_quanta.q_res(chips)',
 P_PATH='@s9s_mb_2u_lib.s9s_mb_2u(sch_1):page169_i68@pure_quanta.q_res(chips)',
 PATH='I68',
 DRAWING='@S9S_MB_2U_LIB.S9S_MB_2U(SCH_1):PAGE162',
 PHYS_PAGE='169',
 XY='(2000,3650)',
 ROT='0',
 VER='2',
 PACK_TYPE='0402LF',
 CDS_LIB='pure_quanta',
 CDS_PART_NAME='Q_RES_0402LF-4.7K,1%,1/16W,EMPA',
 WATTAGE='1/16W',
 TOLERANCE='1%',
 MATERIAL='EMPTY',
 VALUE='4.7K',
 PRIM_FILE='./archive_libs/logical/q_res/chips/chips.prt';

PART_NAME
 R4291 'Q_RES_0402LF-4.7K,1%,1/16W,EMPA':;

SECTION_NUMBER 1
 '@S9S_MB_2U_LIB.S9S_MB_2U(SCH_1):PAGE162_I65@PURE_QUANTA.Q_RES(CHIPS)':
 C_PATH='@s9s_mb_2u_lib.s9s_mb_2u(sch_1):page162_i65@pure_quanta.q_res(chips)',
 P_PATH='@s9s_mb_2u_lib.s9s_mb_2u(sch_1):page169_i65@pure_quanta.q_res(chips)',
 PATH='I65',
 DRAWING='@S9S_MB_2U_LIB.S9S_MB_2U(SCH_1):PAGE162',
 PHYS_PAGE='169',
 XY='(2000,2800)',
 ROT='0',
 VER='2',
 PACK_TYPE='0402LF',
 CDS_LIB='pure_quanta',
 CDS_PART_NAME='Q_RES_0402LF-4.7K,1%,1/16W,EMPA',
 WATTAGE='1/16W',
 TOLERANCE='1%',
 MATERIAL='EMPTY',
 VALUE='4.7K',
 PRIM_FILE='./archive_libs/logical/q_res/chips/chips.prt';

PART_NAME
 R4292 'Q_RES_0402LF-4.7K,1%,1/16W,EMPA':;

SECTION_NUMBER 1
 '@S9S_MB_2U_LIB.S9S_MB_2U(SCH_1):PAGE162_I63@PURE_QUANTA.Q_RES(CHIPS)':
 C_PATH='@s9s_mb_2u_lib.s9s_mb_2u(sch_1):page162_i63@pure_quanta.q_res(chips)',
 P_PATH='@s9s_mb_2u_lib.s9s_mb_2u(sch_1):page169_i63@pure_quanta.q_res(chips)',
 PATH='I63',
 DRAWING='@S9S_MB_2U_LIB.S9S_MB_2U(SCH_1):PAGE162',
 PHYS_PAGE='169',
 XY='(2000,2275)',
 ROT='0',
 VER='2',
 PACK_TYPE='0402LF',
 CDS_LIB='pure_quanta',
 CDS_PART_NAME='Q_RES_0402LF-4.7K,1%,1/16W,EMPA',
 WATTAGE='1/16W',
 TOLERANCE='1%',
 MATERIAL='EMPTY',
 VALUE='4.7K',
 PRIM_FILE='./archive_libs/logical/q_res/chips/chips.prt';

PART_NAME
 R4293 'Q_RES_0402LF-100,1%,1/16W,CHIPA':;

SECTION_NUMBER 1
 '@S9S_MB_2U_LIB.S9S_MB_2U(SCH_1):PAGE122_I34@PURE_QUANTA.Q_RES(CHIPS)':
 C_PATH='@s9s_mb_2u_lib.s9s_mb_2u(sch_1):page122_i34@pure_quanta.q_res(chips)',
 P_PATH='@s9s_mb_2u_lib.s9s_mb_2u(sch_1):page122_i34@pure_quanta.q_res(chips)',
 PATH='I34',
 DRAWING='@S9S_MB_2U_LIB.S9S_MB_2U(SCH_1):PAGE122',
 PHYS_PAGE='122',
 XY='(2450,4350)',
 ROT='0',
 VER='1',
 PACK_TYPE='0402LF',
 CDS_LIB='pure_quanta',
 CDS_PART_NAME='Q_RES_0402LF-100,1%,1/16W,CHIPA',
 WATTAGE='1/16W',
 TOLERANCE='1%',
 MATERIAL='CHIP',
 VALUE='100',
 PRIM_FILE='./archive_libs/logical/q_res/chips/chips.prt';

PART_NAME
 R4294 'Q_RES_0402LF-100,1%,1/16W,CHIPA':;

SECTION_NUMBER 1
 '@S9S_MB_2U_LIB.S9S_MB_2U(SCH_1):PAGE122_I33@PURE_QUANTA.Q_RES(CHIPS)':
 C_PATH='@s9s_mb_2u_lib.s9s_mb_2u(sch_1):page122_i33@pure_quanta.q_res(chips)',
 P_PATH='@s9s_mb_2u_lib.s9s_mb_2u(sch_1):page122_i33@pure_quanta.q_res(chips)',
 PATH='I33',
 DRAWING='@S9S_MB_2U_LIB.S9S_MB_2U(SCH_1):PAGE122',
 PHYS_PAGE='122',
 XY='(2450,3400)',
 ROT='0',
 VER='1',
 PACK_TYPE='0402LF',
 CDS_LIB='pure_quanta',
 CDS_PART_NAME='Q_RES_0402LF-100,1%,1/16W,CHIPA',
 WATTAGE='1/16W',
 TOLERANCE='1%',
 MATERIAL='CHIP',
 VALUE='100',
 PRIM_FILE='./archive_libs/logical/q_res/chips/chips.prt';

PART_NAME
 R4295 'Q_RES_0402LF-100,1%,1/16W,CHIPA':;

SECTION_NUMBER 1
 '@S9S_MB_2U_LIB.S9S_MB_2U(SCH_1):PAGE124_I87@PURE_QUANTA.Q_RES(CHIPS)':
 C_PATH='@s9s_mb_2u_lib.s9s_mb_2u(sch_1):page124_i87@pure_quanta.q_res(chips)',
 P_PATH='@s9s_mb_2u_lib.s9s_mb_2u(sch_1):page124_i87@pure_quanta.q_res(chips)',
 PATH='I87',
 DRAWING='@S9S_MB_2U_LIB.S9S_MB_2U(SCH_1):PAGE124',
 PHYS_PAGE='124',
 XY='(3725,2800)',
 ROT='0',
 VER='1',
 PACK_TYPE='0402LF',
 CDS_LIB='pure_quanta',
 CDS_PART_NAME='Q_RES_0402LF-100,1%,1/16W,CHIPA',
 WATTAGE='1/16W',
 TOLERANCE='1%',
 MATERIAL='CHIP',
 VALUE='100',
 PRIM_FILE='./archive_libs/logical/q_res/chips/chips.prt';

PART_NAME
 R4296 'Q_RES_0402LF-100,1%,1/16W,CHIPA':;

SECTION_NUMBER 1
 '@S9S_MB_2U_LIB.S9S_MB_2U(SCH_1):PAGE124_I85@PURE_QUANTA.Q_RES(CHIPS)':
 C_PATH='@s9s_mb_2u_lib.s9s_mb_2u(sch_1):page124_i85@pure_quanta.q_res(chips)',
 P_PATH='@s9s_mb_2u_lib.s9s_mb_2u(sch_1):page124_i85@pure_quanta.q_res(chips)',
 PATH='I85',
 DRAWING='@S9S_MB_2U_LIB.S9S_MB_2U(SCH_1):PAGE124',
 PHYS_PAGE='124',
 XY='(3725,1975)',
 ROT='0',
 VER='1',
 PACK_TYPE='0402LF',
 CDS_LIB='pure_quanta',
 CDS_PART_NAME='Q_RES_0402LF-100,1%,1/16W,CHIPA',
 WATTAGE='1/16W',
 TOLERANCE='1%',
 MATERIAL='CHIP',
 VALUE='100',
 PRIM_FILE='./archive_libs/logical/q_res/chips/chips.prt';

PART_NAME
 R4297 'Q_RES_0402LF-100,1%,1/16W,CHIPA':;

SECTION_NUMBER 1
 '@S9S_MB_2U_LIB.S9S_MB_2U(SCH_1):PAGE124_I82@PURE_QUANTA.Q_RES(CHIPS)':
 C_PATH='@s9s_mb_2u_lib.s9s_mb_2u(sch_1):page124_i82@pure_quanta.q_res(chips)',
 P_PATH='@s9s_mb_2u_lib.s9s_mb_2u(sch_1):page124_i82@pure_quanta.q_res(chips)',
 PATH='I82',
 DRAWING='@S9S_MB_2U_LIB.S9S_MB_2U(SCH_1):PAGE124',
 PHYS_PAGE='124',
 XY='(3725,1125)',
 ROT='0',
 VER='1',
 PACK_TYPE='0402LF',
 CDS_LIB='pure_quanta',
 CDS_PART_NAME='Q_RES_0402LF-100,1%,1/16W,CHIPA',
 WATTAGE='1/16W',
 TOLERANCE='1%',
 MATERIAL='CHIP',
 VALUE='100',
 PRIM_FILE='./archive_libs/logical/q_res/chips/chips.prt';

PART_NAME
 R4298 'Q_RES_0402LF-100,1%,1/16W,CHIPA':;

SECTION_NUMBER 1
 '@S9S_MB_2U_LIB.S9S_MB_2U(SCH_1):PAGE124_I79@PURE_QUANTA.Q_RES(CHIPS)':
 C_PATH='@s9s_mb_2u_lib.s9s_mb_2u(sch_1):page124_i79@pure_quanta.q_res(chips)',
 P_PATH='@s9s_mb_2u_lib.s9s_mb_2u(sch_1):page124_i79@pure_quanta.q_res(chips)',
 PATH='I79',
 DRAWING='@S9S_MB_2U_LIB.S9S_MB_2U(SCH_1):PAGE124',
 PHYS_PAGE='124',
 XY='(3725,300)',
 ROT='0',
 VER='1',
 PACK_TYPE='0402LF',
 CDS_LIB='pure_quanta',
 CDS_PART_NAME='Q_RES_0402LF-100,1%,1/16W,CHIPA',
 WATTAGE='1/16W',
 TOLERANCE='1%',
 MATERIAL='CHIP',
 VALUE='100',
 PRIM_FILE='./archive_libs/logical/q_res/chips/chips.prt';

PART_NAME
 R4299 'Q_RES_0402LF-100,1%,1/16W,CHIPA':;

SECTION_NUMBER 1
 '@S9S_MB_2U_LIB.S9S_MB_2U(SCH_1):PAGE125_I72@PURE_QUANTA.Q_RES(CHIPS)':
 C_PATH='@s9s_mb_2u_lib.s9s_mb_2u(sch_1):page125_i72@pure_quanta.q_res(chips)',
 P_PATH='@s9s_mb_2u_lib.s9s_mb_2u(sch_1):page125_i72@pure_quanta.q_res(chips)',
 PATH='I72',
 DRAWING='@S9S_MB_2U_LIB.S9S_MB_2U(SCH_1):PAGE125',
 PHYS_PAGE='125',
 XY='(-1100,3300)',
 ROT='0',
 VER='1',
 PACK_TYPE='0402LF',
 CDS_LIB='pure_quanta',
 CDS_PART_NAME='Q_RES_0402LF-100,1%,1/16W,CHIPA',
 WATTAGE='1/16W',
 TOLERANCE='1%',
 MATERIAL='CHIP',
 VALUE='100',
 PRIM_FILE='./archive_libs/logical/q_res/chips/chips.prt';

PART_NAME
 R4300 'Q_RES_0402LF-100,1%,1/16W,CHIPA':;

SECTION_NUMBER 1
 '@S9S_MB_2U_LIB.S9S_MB_2U(SCH_1):PAGE125_I70@PURE_QUANTA.Q_RES(CHIPS)':
 C_PATH='@s9s_mb_2u_lib.s9s_mb_2u(sch_1):page125_i70@pure_quanta.q_res(chips)',
 P_PATH='@s9s_mb_2u_lib.s9s_mb_2u(sch_1):page125_i70@pure_quanta.q_res(chips)',
 PATH='I70',
 DRAWING='@S9S_MB_2U_LIB.S9S_MB_2U(SCH_1):PAGE125',
 PHYS_PAGE='125',
 XY='(-1100,2450)',
 ROT='0',
 VER='1',
 PACK_TYPE='0402LF',
 CDS_LIB='pure_quanta',
 CDS_PART_NAME='Q_RES_0402LF-100,1%,1/16W,CHIPA',
 WATTAGE='1/16W',
 TOLERANCE='1%',
 MATERIAL='CHIP',
 VALUE='100',
 PRIM_FILE='./archive_libs/logical/q_res/chips/chips.prt';

PART_NAME
 R4301 'Q_RES_0402LF-100,1%,1/16W,CHIPA':;

SECTION_NUMBER 1
 '@S9S_MB_2U_LIB.S9S_MB_2U(SCH_1):PAGE125_I68@PURE_QUANTA.Q_RES(CHIPS)':
 C_PATH='@s9s_mb_2u_lib.s9s_mb_2u(sch_1):page125_i68@pure_quanta.q_res(chips)',
 P_PATH='@s9s_mb_2u_lib.s9s_mb_2u(sch_1):page125_i68@pure_quanta.q_res(chips)',
 PATH='I68',
 DRAWING='@S9S_MB_2U_LIB.S9S_MB_2U(SCH_1):PAGE125',
 PHYS_PAGE='125',
 XY='(-1100,1600)',
 ROT='0',
 VER='1',
 PACK_TYPE='0402LF',
 CDS_LIB='pure_quanta',
 CDS_PART_NAME='Q_RES_0402LF-100,1%,1/16W,CHIPA',
 WATTAGE='1/16W',
 TOLERANCE='1%',
 MATERIAL='CHIP',
 VALUE='100',
 PRIM_FILE='./archive_libs/logical/q_res/chips/chips.prt';

PART_NAME
 R4302 'Q_RES_0402LF-100,1%,1/16W,CHIPA':;

SECTION_NUMBER 1
 '@S9S_MB_2U_LIB.S9S_MB_2U(SCH_1):PAGE125_I66@PURE_QUANTA.Q_RES(CHIPS)':
 C_PATH='@s9s_mb_2u_lib.s9s_mb_2u(sch_1):page125_i66@pure_quanta.q_res(chips)',
 P_PATH='@s9s_mb_2u_lib.s9s_mb_2u(sch_1):page125_i66@pure_quanta.q_res(chips)',
 PATH='I66',
 DRAWING='@S9S_MB_2U_LIB.S9S_MB_2U(SCH_1):PAGE125',
 PHYS_PAGE='125',
 XY='(-1100,775)',
 ROT='0',
 VER='1',
 PACK_TYPE='0402LF',
 CDS_LIB='pure_quanta',
 CDS_PART_NAME='Q_RES_0402LF-100,1%,1/16W,CHIPA',
 WATTAGE='1/16W',
 TOLERANCE='1%',
 MATERIAL='CHIP',
 VALUE='100',
 PRIM_FILE='./archive_libs/logical/q_res/chips/chips.prt';

PART_NAME
 R4303 'Q_RES_0402LF-22,1%,1/16W,CHIP,A':;

SECTION_NUMBER 1
 '@S9S_MB_2U_LIB.S9S_MB_2U(SCH_1):PAGE171_I121@PURE_QUANTA.Q_RES(CHIPS)':
 C_PATH='@s9s_mb_2u_lib.s9s_mb_2u(sch_1):page171_i121@pure_quanta.q_res(chips)',
 P_PATH='@s9s_mb_2u_lib.s9s_mb_2u(sch_1):page179_i121@pure_quanta.q_res(chips)',
 PATH='I121',
 DRAWING='@S9S_MB_2U_LIB.S9S_MB_2U(SCH_1):PAGE171',
 PHYS_PAGE='179',
 XY='(1350,1675)',
 ROT='0',
 VER='1',
 PACK_TYPE='0402LF',
 LOCATION='R4303',
 CDS_LIB='pure_quanta',
 CDS_PART_NAME='Q_RES_0402LF-22,1%,1/16W,CHIP,A',
 WATTAGE='1/16W',
 TOLERANCE='1%',
 MATERIAL='CHIP',
 VALUE='22',
 PRIM_FILE='./archive_libs/logical/q_res/chips/chips.prt';

PART_NAME
 R4304 'Q_RES_0402LF-22,1%,1/16W,CHIP,A':;

SECTION_NUMBER 1
 '@S9S_MB_2U_LIB.S9S_MB_2U(SCH_1):PAGE171_I122@PURE_QUANTA.Q_RES(CHIPS)':
 C_PATH='@s9s_mb_2u_lib.s9s_mb_2u(sch_1):page171_i122@pure_quanta.q_res(chips)',
 P_PATH='@s9s_mb_2u_lib.s9s_mb_2u(sch_1):page179_i122@pure_quanta.q_res(chips)',
 PATH='I122',
 DRAWING='@S9S_MB_2U_LIB.S9S_MB_2U(SCH_1):PAGE171',
 PHYS_PAGE='179',
 XY='(1350,1525)',
 ROT='0',
 VER='1',
 PACK_TYPE='0402LF',
 LOCATION='R4304',
 CDS_LIB='pure_quanta',
 CDS_PART_NAME='Q_RES_0402LF-22,1%,1/16W,CHIP,A',
 WATTAGE='1/16W',
 TOLERANCE='1%',
 MATERIAL='CHIP',
 VALUE='22',
 PRIM_FILE='./archive_libs/logical/q_res/chips/chips.prt';

PART_NAME
 R4305 'Q_RES_0402LF-0,5%,1/16W,CHIP,CA':;

SECTION_NUMBER 1
 '@S9S_MB_2U_LIB.S9S_MB_2U(SCH_1):PAGE171_I116@PURE_QUANTA.Q_RES(CHIPS)':
 C_PATH='@s9s_mb_2u_lib.s9s_mb_2u(sch_1):page171_i116@pure_quanta.q_res(chips)',
 P_PATH='@s9s_mb_2u_lib.s9s_mb_2u(sch_1):page179_i116@pure_quanta.q_res(chips)',
 PATH='I116',
 DRAWING='@S9S_MB_2U_LIB.S9S_MB_2U(SCH_1):PAGE171',
 PHYS_PAGE='179',
 XY='(1350,1300)',
 ROT='0',
 VER='1',
 PACK_TYPE='0402LF',
 CDS_LIB='pure_quanta',
 CDS_PART_NAME='Q_RES_0402LF-0,5%,1/16W,CHIP,CA',
 WATTAGE='1/16W',
 TOLERANCE='5%',
 MATERIAL='CHIP',
 VALUE='0',
 PRIM_FILE='./archive_libs/logical/q_res/chips/chips.prt';

PART_NAME
 R4306 'Q_RES_0402LF-0,5%,1/16W,CHIP,CA':;

SECTION_NUMBER 1
 '@S9S_MB_2U_LIB.S9S_MB_2U(SCH_1):PAGE171_I117@PURE_QUANTA.Q_RES(CHIPS)':
 C_PATH='@s9s_mb_2u_lib.s9s_mb_2u(sch_1):page171_i117@pure_quanta.q_res(chips)',
 P_PATH='@s9s_mb_2u_lib.s9s_mb_2u(sch_1):page179_i117@pure_quanta.q_res(chips)',
 PATH='I117',
 DRAWING='@S9S_MB_2U_LIB.S9S_MB_2U(SCH_1):PAGE171',
 PHYS_PAGE='179',
 XY='(1350,1150)',
 ROT='0',
 VER='1',
 PACK_TYPE='0402LF',
 CDS_LIB='pure_quanta',
 CDS_PART_NAME='Q_RES_0402LF-0,5%,1/16W,CHIP,CA',
 WATTAGE='1/16W',
 TOLERANCE='5%',
 MATERIAL='CHIP',
 VALUE='0',
 PRIM_FILE='./archive_libs/logical/q_res/chips/chips.prt';

PART_NAME
 R4388 'Q_RES_0402LF-150,1%,1/16W,CHIPA':;

SECTION_NUMBER 1
 '@S9S_MB_2U_LIB.S9S_MB_2U(SCH_1):PAGE322_I174@PURE_QUANTA.Q_RES(CHIPS)':
 C_PATH='@s9s_mb_2u_lib.s9s_mb_2u(sch_1):page322_i174@pure_quanta.q_res(chips)',
 P_PATH='@s9s_mb_2u_lib.s9s_mb_2u(sch_1):page225_i174@pure_quanta.q_res(chips)',
 PATH='I174',
 DRAWING='@S9S_MB_2U_LIB.S9S_MB_2U(SCH_1):PAGE322',
 PHYS_PAGE='225',
 XY='(-12075,-1975)',
 ROT='0',
 VER='2',
 PACK_TYPE='0402LF',
 CDS_LIB='pure_quanta',
 CDS_PART_NAME='Q_RES_0402LF-150,1%,1/16W,CHIPA',
 WATTAGE='1/16W',
 TOLERANCE='1%',
 MATERIAL='CHIP',
 VALUE='150',
 PRIM_FILE='./archive_libs/logical/q_res/chips/chips.prt';

PART_NAME
 R4389 'Q_RES_0402LF-150,1%,1/16W,CHIPA':;

SECTION_NUMBER 1
 '@S9S_MB_2U_LIB.S9S_MB_2U(SCH_1):PAGE322_I177@PURE_QUANTA.Q_RES(CHIPS)':
 C_PATH='@s9s_mb_2u_lib.s9s_mb_2u(sch_1):page322_i177@pure_quanta.q_res(chips)',
 P_PATH='@s9s_mb_2u_lib.s9s_mb_2u(sch_1):page225_i177@pure_quanta.q_res(chips)',
 PATH='I177',
 DRAWING='@S9S_MB_2U_LIB.S9S_MB_2U(SCH_1):PAGE322',
 PHYS_PAGE='225',
 XY='(-12075,-2825)',
 ROT='0',
 VER='2',
 PACK_TYPE='0402LF',
 CDS_LIB='pure_quanta',
 CDS_PART_NAME='Q_RES_0402LF-150,1%,1/16W,CHIPA',
 WATTAGE='1/16W',
 TOLERANCE='1%',
 MATERIAL='CHIP',
 VALUE='150',
 PRIM_FILE='./archive_libs/logical/q_res/chips/chips.prt';

PART_NAME
 R4390 'Q_RES_0402LF-150,1%,1/16W,CHIPA':;

SECTION_NUMBER 1
 '@S9S_MB_2U_LIB.S9S_MB_2U(SCH_1):PAGE322_I169@PURE_QUANTA.Q_RES(CHIPS)':
 C_PATH='@s9s_mb_2u_lib.s9s_mb_2u(sch_1):page322_i169@pure_quanta.q_res(chips)',
 P_PATH='@s9s_mb_2u_lib.s9s_mb_2u(sch_1):page225_i169@pure_quanta.q_res(chips)',
 PATH='I169',
 DRAWING='@S9S_MB_2U_LIB.S9S_MB_2U(SCH_1):PAGE322',
 PHYS_PAGE='225',
 XY='(-12050,-1050)',
 ROT='0',
 VER='2',
 PACK_TYPE='0402LF',
 CDS_LIB='pure_quanta',
 CDS_PART_NAME='Q_RES_0402LF-150,1%,1/16W,CHIPA',
 WATTAGE='1/16W',
 TOLERANCE='1%',
 MATERIAL='CHIP',
 VALUE='150',
 PRIM_FILE='./archive_libs/logical/q_res/chips/chips.prt';

PART_NAME
 R4391 'Q_RES_0402LF-150,1%,1/16W,CHIPA':;

SECTION_NUMBER 1
 '@S9S_MB_2U_LIB.S9S_MB_2U(SCH_1):PAGE322_I190@PURE_QUANTA.Q_RES(CHIPS)':
 C_PATH='@s9s_mb_2u_lib.s9s_mb_2u(sch_1):page322_i190@pure_quanta.q_res(chips)',
 P_PATH='@s9s_mb_2u_lib.s9s_mb_2u(sch_1):page225_i190@pure_quanta.q_res(chips)',
 PATH='I190',
 DRAWING='@S9S_MB_2U_LIB.S9S_MB_2U(SCH_1):PAGE322',
 PHYS_PAGE='225',
 XY='(-10425,-3025)',
 ROT='0',
 VER='2',
 PACK_TYPE='0402LF',
 CDS_LIB='pure_quanta',
 CDS_PART_NAME='Q_RES_0402LF-150,1%,1/16W,CHIPA',
 WATTAGE='1/16W',
 TOLERANCE='1%',
 MATERIAL='CHIP',
 VALUE='150',
 PRIM_FILE='./archive_libs/logical/q_res/chips/chips.prt';

PART_NAME
 R4392 'Q_RES_0402LF-33.2,1%,1/16W,CHIA':;

SECTION_NUMBER 1
 '@S9S_MB_2U_LIB.S9S_MB_2U(SCH_1):PAGE322_I183@PURE_QUANTA.Q_RES(CHIPS)':
 C_PATH='@s9s_mb_2u_lib.s9s_mb_2u(sch_1):page322_i183@pure_quanta.q_res(chips)',
 P_PATH='@s9s_mb_2u_lib.s9s_mb_2u(sch_1):page225_i183@pure_quanta.q_res(chips)',
 PATH='I183',
 DRAWING='@S9S_MB_2U_LIB.S9S_MB_2U(SCH_1):PAGE322',
 PHYS_PAGE='225',
 XY='(-5800,-1875)',
 ROT='0',
 VER='1',
 PACK_TYPE='0402LF',
 CDS_LIB='pure_quanta',
 CDS_PART_NAME='Q_RES_0402LF-33.2,1%,1/16W,CHIA',
 WATTAGE='1/16W',
 TOLERANCE='1%',
 MATERIAL='CHIP',
 VALUE='33.2',
 PRIM_FILE='./archive_libs/logical/q_res/chips/chips.prt';

PART_NAME
 R4393 'Q_RES_0402LF-33.2,1%,1/16W,CHIA':;

SECTION_NUMBER 1
 '@S9S_MB_2U_LIB.S9S_MB_2U(SCH_1):PAGE322_I188@PURE_QUANTA.Q_RES(CHIPS)':
 C_PATH='@s9s_mb_2u_lib.s9s_mb_2u(sch_1):page322_i188@pure_quanta.q_res(chips)',
 P_PATH='@s9s_mb_2u_lib.s9s_mb_2u(sch_1):page225_i188@pure_quanta.q_res(chips)',
 PATH='I188',
 DRAWING='@S9S_MB_2U_LIB.S9S_MB_2U(SCH_1):PAGE322',
 PHYS_PAGE='225',
 XY='(-5800,-2375)',
 ROT='0',
 VER='1',
 PACK_TYPE='0402LF',
 CDS_LIB='pure_quanta',
 CDS_PART_NAME='Q_RES_0402LF-33.2,1%,1/16W,CHIA',
 WATTAGE='1/16W',
 TOLERANCE='1%',
 MATERIAL='CHIP',
 VALUE='33.2',
 PRIM_FILE='./archive_libs/logical/q_res/chips/chips.prt';

PART_NAME
 R4394 'Q_RES_0402LF-33.2,1%,1/16W,CHIA':;

SECTION_NUMBER 1
 '@S9S_MB_2U_LIB.S9S_MB_2U(SCH_1):PAGE322_I189@PURE_QUANTA.Q_RES(CHIPS)':
 C_PATH='@s9s_mb_2u_lib.s9s_mb_2u(sch_1):page322_i189@pure_quanta.q_res(chips)',
 P_PATH='@s9s_mb_2u_lib.s9s_mb_2u(sch_1):page225_i189@pure_quanta.q_res(chips)',
 PATH='I189',
 DRAWING='@S9S_MB_2U_LIB.S9S_MB_2U(SCH_1):PAGE322',
 PHYS_PAGE='225',
 XY='(-5800,-2875)',
 ROT='0',
 VER='1',
 PACK_TYPE='0402LF',
 CDS_LIB='pure_quanta',
 CDS_PART_NAME='Q_RES_0402LF-33.2,1%,1/16W,CHIA',
 WATTAGE='1/16W',
 TOLERANCE='1%',
 MATERIAL='CHIP',
 VALUE='33.2',
 PRIM_FILE='./archive_libs/logical/q_res/chips/chips.prt';

PART_NAME
 R4395 'Q_RES_0402LF-100,1%,1/16W,CHIPA':;

SECTION_NUMBER 1
 '@S9S_MB_2U_LIB.S9S_MB_2U(SCH_1):PAGE121_I13@PURE_QUANTA.Q_RES(CHIPS)':
 C_PATH='@s9s_mb_2u_lib.s9s_mb_2u(sch_1):page121_i13@pure_quanta.q_res(chips)',
 P_PATH='@s9s_mb_2u_lib.s9s_mb_2u(sch_1):page121_i13@pure_quanta.q_res(chips)',
 PATH='I13',
 DRAWING='@S9S_MB_2U_LIB.S9S_MB_2U(SCH_1):PAGE121',
 PHYS_PAGE='121',
 XY='(-2025,2475)',
 ROT='0',
 VER='2',
 PACK_TYPE='0402LF',
 CDS_LIB='pure_quanta',
 CDS_PART_NAME='Q_RES_0402LF-100,1%,1/16W,CHIPA',
 WATTAGE='1/16W',
 TOLERANCE='1%',
 MATERIAL='CHIP',
 VALUE='100',
 PRIM_FILE='./archive_libs/logical/q_res/chips/chips.prt';

PART_NAME
 R4396 'Q_RES_0402LF-100,1%,1/16W,CHIPA':;

SECTION_NUMBER 1
 '@S9S_MB_2U_LIB.S9S_MB_2U(SCH_1):PAGE121_I4@PURE_QUANTA.Q_RES(CHIPS)':
 C_PATH='@s9s_mb_2u_lib.s9s_mb_2u(sch_1):page121_i4@pure_quanta.q_res(chips)',
 P_PATH='@s9s_mb_2u_lib.s9s_mb_2u(sch_1):page121_i4@pure_quanta.q_res(chips)',
 PATH='I4',
 DRAWING='@S9S_MB_2U_LIB.S9S_MB_2U(SCH_1):PAGE121',
 PHYS_PAGE='121',
 XY='(-2025,1125)',
 ROT='0',
 VER='2',
 PACK_TYPE='0402LF',
 CDS_LIB='pure_quanta',
 CDS_PART_NAME='Q_RES_0402LF-100,1%,1/16W,CHIPA',
 WATTAGE='1/16W',
 TOLERANCE='1%',
 MATERIAL='CHIP',
 VALUE='100',
 PRIM_FILE='./archive_libs/logical/q_res/chips/chips.prt';

PART_NAME
 R4397 'Q_RES_0402LF-1.5K,1%,1/16W,CHIA':;

SECTION_NUMBER 1
 '@S9S_MB_2U_LIB.S9S_MB_2U(SCH_1):PAGE121_I16@PURE_QUANTA.Q_RES(CHIPS)':
 C_PATH='@s9s_mb_2u_lib.s9s_mb_2u(sch_1):page121_i16@pure_quanta.q_res(chips)',
 P_PATH='@s9s_mb_2u_lib.s9s_mb_2u(sch_1):page121_i16@pure_quanta.q_res(chips)',
 PATH='I16',
 DRAWING='@S9S_MB_2U_LIB.S9S_MB_2U(SCH_1):PAGE121',
 PHYS_PAGE='121',
 XY='(100,1950)',
 ROT='0',
 VER='1',
 PACK_TYPE='0402LF',
 CDS_LIB='pure_quanta',
 CDS_PART_NAME='Q_RES_0402LF-1.5K,1%,1/16W,CHIA',
 WATTAGE='1/16W',
 TOLERANCE='1%',
 MATERIAL='CHIP',
 VALUE='1.5K',
 PRIM_FILE='./archive_libs/logical/q_res/chips/chips.prt';

PART_NAME
 R4398 'Q_RES_0402LF-1.5K,1%,1/16W,CHIA':;

SECTION_NUMBER 1
 '@S9S_MB_2U_LIB.S9S_MB_2U(SCH_1):PAGE121_I10@PURE_QUANTA.Q_RES(CHIPS)':
 C_PATH='@s9s_mb_2u_lib.s9s_mb_2u(sch_1):page121_i10@pure_quanta.q_res(chips)',
 P_PATH='@s9s_mb_2u_lib.s9s_mb_2u(sch_1):page121_i10@pure_quanta.q_res(chips)',
 PATH='I10',
 DRAWING='@S9S_MB_2U_LIB.S9S_MB_2U(SCH_1):PAGE121',
 PHYS_PAGE='121',
 XY='(100,600)',
 ROT='0',
 VER='1',
 PACK_TYPE='0402LF',
 CDS_LIB='pure_quanta',
 CDS_PART_NAME='Q_RES_0402LF-1.5K,1%,1/16W,CHIA',
 WATTAGE='1/16W',
 TOLERANCE='1%',
 MATERIAL='CHIP',
 VALUE='1.5K',
 PRIM_FILE='./archive_libs/logical/q_res/chips/chips.prt';

PART_NAME
 R4399 'Q_RES_0402LF-33.2,1%,1/16W,CHIA':;

SECTION_NUMBER 1
 '@S9S_MB_2U_LIB.S9S_MB_2U(SCH_1):PAGE121_I35@PURE_QUANTA.Q_RES(CHIPS)':
 C_PATH='@s9s_mb_2u_lib.s9s_mb_2u(sch_1):page121_i35@pure_quanta.q_res(chips)',
 P_PATH='@s9s_mb_2u_lib.s9s_mb_2u(sch_1):page121_i35@pure_quanta.q_res(chips)',
 PATH='I35',
 DRAWING='@S9S_MB_2U_LIB.S9S_MB_2U(SCH_1):PAGE121',
 PHYS_PAGE='121',
 XY='(2375,1725)',
 ROT='0',
 VER='1',
 PACK_TYPE='0402LF',
 CDS_LIB='pure_quanta',
 CDS_PART_NAME='Q_RES_0402LF-33.2,1%,1/16W,CHIA',
 WATTAGE='1/16W',
 TOLERANCE='1%',
 MATERIAL='CHIP',
 VALUE='33.2',
 PRIM_FILE='./archive_libs/logical/q_res/chips/chips.prt';

PART_NAME
 R4400 'Q_RES_0402LF-33.2,1%,1/16W,CHIA':;

SECTION_NUMBER 1
 '@S9S_MB_2U_LIB.S9S_MB_2U(SCH_1):PAGE121_I29@PURE_QUANTA.Q_RES(CHIPS)':
 C_PATH='@s9s_mb_2u_lib.s9s_mb_2u(sch_1):page121_i29@pure_quanta.q_res(chips)',
 P_PATH='@s9s_mb_2u_lib.s9s_mb_2u(sch_1):page121_i29@pure_quanta.q_res(chips)',
 PATH='I29',
 DRAWING='@S9S_MB_2U_LIB.S9S_MB_2U(SCH_1):PAGE121',
 PHYS_PAGE='121',
 XY='(2375,375)',
 ROT='0',
 VER='1',
 PACK_TYPE='0402LF',
 CDS_LIB='pure_quanta',
 CDS_PART_NAME='Q_RES_0402LF-33.2,1%,1/16W,CHIA',
 WATTAGE='1/16W',
 TOLERANCE='1%',
 MATERIAL='CHIP',
 VALUE='33.2',
 PRIM_FILE='./archive_libs/logical/q_res/chips/chips.prt';

PART_NAME
 R4401 'Q_RES_0402LF-100,1%,1/16W,CHIPA':;

SECTION_NUMBER 1
 '@S9S_MB_2U_LIB.S9S_MB_2U(SCH_1):PAGE122_I8@PURE_QUANTA.Q_RES(CHIPS)':
 C_PATH='@s9s_mb_2u_lib.s9s_mb_2u(sch_1):page122_i8@pure_quanta.q_res(chips)',
 P_PATH='@s9s_mb_2u_lib.s9s_mb_2u(sch_1):page122_i8@pure_quanta.q_res(chips)',
 PATH='I8',
 DRAWING='@S9S_MB_2U_LIB.S9S_MB_2U(SCH_1):PAGE122',
 PHYS_PAGE='122',
 XY='(-2000,2450)',
 ROT='0',
 VER='2',
 PACK_TYPE='0402LF',
 CDS_LIB='pure_quanta',
 CDS_PART_NAME='Q_RES_0402LF-100,1%,1/16W,CHIPA',
 WATTAGE='1/16W',
 TOLERANCE='1%',
 MATERIAL='CHIP',
 VALUE='100',
 PRIM_FILE='./archive_libs/logical/q_res/chips/chips.prt';

PART_NAME
 R4402 'Q_RES_0402LF-100,1%,1/16W,CHIPA':;

SECTION_NUMBER 1
 '@S9S_MB_2U_LIB.S9S_MB_2U(SCH_1):PAGE122_I5@PURE_QUANTA.Q_RES(CHIPS)':
 C_PATH='@s9s_mb_2u_lib.s9s_mb_2u(sch_1):page122_i5@pure_quanta.q_res(chips)',
 P_PATH='@s9s_mb_2u_lib.s9s_mb_2u(sch_1):page122_i5@pure_quanta.q_res(chips)',
 PATH='I5',
 DRAWING='@S9S_MB_2U_LIB.S9S_MB_2U(SCH_1):PAGE122',
 PHYS_PAGE='122',
 XY='(-2000,1100)',
 ROT='0',
 VER='2',
 PACK_TYPE='0402LF',
 CDS_LIB='pure_quanta',
 CDS_PART_NAME='Q_RES_0402LF-100,1%,1/16W,CHIPA',
 WATTAGE='1/16W',
 TOLERANCE='1%',
 MATERIAL='CHIP',
 VALUE='100',
 PRIM_FILE='./archive_libs/logical/q_res/chips/chips.prt';

PART_NAME
 R4403 'Q_RES_0402LF-1.5K,1%,1/16W,CHIA':;

SECTION_NUMBER 1
 '@S9S_MB_2U_LIB.S9S_MB_2U(SCH_1):PAGE122_I21@PURE_QUANTA.Q_RES(CHIPS)':
 C_PATH='@s9s_mb_2u_lib.s9s_mb_2u(sch_1):page122_i21@pure_quanta.q_res(chips)',
 P_PATH='@s9s_mb_2u_lib.s9s_mb_2u(sch_1):page122_i21@pure_quanta.q_res(chips)',
 PATH='I21',
 DRAWING='@S9S_MB_2U_LIB.S9S_MB_2U(SCH_1):PAGE122',
 PHYS_PAGE='122',
 XY='(125,1925)',
 ROT='0',
 VER='1',
 PACK_TYPE='0402LF',
 CDS_LIB='pure_quanta',
 CDS_PART_NAME='Q_RES_0402LF-1.5K,1%,1/16W,CHIA',
 WATTAGE='1/16W',
 TOLERANCE='1%',
 MATERIAL='CHIP',
 VALUE='1.5K',
 PRIM_FILE='./archive_libs/logical/q_res/chips/chips.prt';

PART_NAME
 R4404 'Q_RES_0402LF-1.5K,1%,1/16W,CHIA':;

SECTION_NUMBER 1
 '@S9S_MB_2U_LIB.S9S_MB_2U(SCH_1):PAGE122_I20@PURE_QUANTA.Q_RES(CHIPS)':
 C_PATH='@s9s_mb_2u_lib.s9s_mb_2u(sch_1):page122_i20@pure_quanta.q_res(chips)',
 P_PATH='@s9s_mb_2u_lib.s9s_mb_2u(sch_1):page122_i20@pure_quanta.q_res(chips)',
 PATH='I20',
 DRAWING='@S9S_MB_2U_LIB.S9S_MB_2U(SCH_1):PAGE122',
 PHYS_PAGE='122',
 XY='(125,575)',
 ROT='0',
 VER='1',
 PACK_TYPE='0402LF',
 CDS_LIB='pure_quanta',
 CDS_PART_NAME='Q_RES_0402LF-1.5K,1%,1/16W,CHIA',
 WATTAGE='1/16W',
 TOLERANCE='1%',
 MATERIAL='CHIP',
 VALUE='1.5K',
 PRIM_FILE='./archive_libs/logical/q_res/chips/chips.prt';

PART_NAME
 R4405 'Q_RES_0402LF-4.75K,1%,1/16W,CHA':;

SECTION_NUMBER 1
 '@S9S_MB_2U_LIB.S9S_MB_2U(SCH_1):PAGE122_I27@PURE_QUANTA.Q_RES(CHIPS)':
 C_PATH='@s9s_mb_2u_lib.s9s_mb_2u(sch_1):page122_i27@pure_quanta.q_res(chips)',
 P_PATH='@s9s_mb_2u_lib.s9s_mb_2u(sch_1):page122_i27@pure_quanta.q_res(chips)',
 PATH='I27',
 DRAWING='@S9S_MB_2U_LIB.S9S_MB_2U(SCH_1):PAGE122',
 PHYS_PAGE='122',
 XY='(1750,2075)',
 ROT='0',
 VER='2',
 PACK_TYPE='0402LF',
 CDS_LIB='pure_quanta',
 CDS_PART_NAME='Q_RES_0402LF-4.75K,1%,1/16W,CHA',
 WATTAGE='1/16W',
 TOLERANCE='1%',
 MATERIAL='CHIP',
 VALUE='4.75K',
 PRIM_FILE='./archive_libs/logical/q_res/chips/chips.prt';

PART_NAME
 R4406 'Q_RES_0402LF-4.75K,1%,1/16W,CHA':;

SECTION_NUMBER 1
 '@S9S_MB_2U_LIB.S9S_MB_2U(SCH_1):PAGE122_I24@PURE_QUANTA.Q_RES(CHIPS)':
 C_PATH='@s9s_mb_2u_lib.s9s_mb_2u(sch_1):page122_i24@pure_quanta.q_res(chips)',
 P_PATH='@s9s_mb_2u_lib.s9s_mb_2u(sch_1):page122_i24@pure_quanta.q_res(chips)',
 PATH='I24',
 DRAWING='@S9S_MB_2U_LIB.S9S_MB_2U(SCH_1):PAGE122',
 PHYS_PAGE='122',
 XY='(1750,725)',
 ROT='0',
 VER='2',
 PACK_TYPE='0402LF',
 CDS_LIB='pure_quanta',
 CDS_PART_NAME='Q_RES_0402LF-4.75K,1%,1/16W,CHA',
 WATTAGE='1/16W',
 TOLERANCE='1%',
 MATERIAL='CHIP',
 VALUE='4.75K',
 PRIM_FILE='./archive_libs/logical/q_res/chips/chips.prt';

PART_NAME
 R4407 'Q_RES_0402LF-33.2,1%,1/16W,CHIA':;

SECTION_NUMBER 1
 '@S9S_MB_2U_LIB.S9S_MB_2U(SCH_1):PAGE122_I31@PURE_QUANTA.Q_RES(CHIPS)':
 C_PATH='@s9s_mb_2u_lib.s9s_mb_2u(sch_1):page122_i31@pure_quanta.q_res(chips)',
 P_PATH='@s9s_mb_2u_lib.s9s_mb_2u(sch_1):page122_i31@pure_quanta.q_res(chips)',
 PATH='I31',
 DRAWING='@S9S_MB_2U_LIB.S9S_MB_2U(SCH_1):PAGE122',
 PHYS_PAGE='122',
 XY='(2400,1700)',
 ROT='0',
 VER='1',
 PACK_TYPE='0402LF',
 CDS_LIB='pure_quanta',
 CDS_PART_NAME='Q_RES_0402LF-33.2,1%,1/16W,CHIA',
 WATTAGE='1/16W',
 TOLERANCE='1%',
 MATERIAL='CHIP',
 VALUE='33.2',
 PRIM_FILE='./archive_libs/logical/q_res/chips/chips.prt';

PART_NAME
 R4408 'Q_RES_0402LF-33.2,1%,1/16W,CHIA':;

SECTION_NUMBER 1
 '@S9S_MB_2U_LIB.S9S_MB_2U(SCH_1):PAGE122_I18@PURE_QUANTA.Q_RES(CHIPS)':
 C_PATH='@s9s_mb_2u_lib.s9s_mb_2u(sch_1):page122_i18@pure_quanta.q_res(chips)',
 P_PATH='@s9s_mb_2u_lib.s9s_mb_2u(sch_1):page122_i18@pure_quanta.q_res(chips)',
 PATH='I18',
 DRAWING='@S9S_MB_2U_LIB.S9S_MB_2U(SCH_1):PAGE122',
 PHYS_PAGE='122',
 XY='(2400,350)',
 ROT='0',
 VER='1',
 PACK_TYPE='0402LF',
 CDS_LIB='pure_quanta',
 CDS_PART_NAME='Q_RES_0402LF-33.2,1%,1/16W,CHIA',
 WATTAGE='1/16W',
 TOLERANCE='1%',
 MATERIAL='CHIP',
 VALUE='33.2',
 PRIM_FILE='./archive_libs/logical/q_res/chips/chips.prt';

PART_NAME
 R4409 'Q_RES_0402LF-1.5K,1%,1/16W,CHIA':;

SECTION_NUMBER 1
 '@S9S_MB_2U_LIB.S9S_MB_2U(SCH_1):PAGE123_I15@PURE_QUANTA.Q_RES(CHIPS)':
 C_PATH='@s9s_mb_2u_lib.s9s_mb_2u(sch_1):page123_i15@pure_quanta.q_res(chips)',
 P_PATH='@s9s_mb_2u_lib.s9s_mb_2u(sch_1):page123_i15@pure_quanta.q_res(chips)',
 PATH='I15',
 DRAWING='@S9S_MB_2U_LIB.S9S_MB_2U(SCH_1):PAGE123',
 PHYS_PAGE='123',
 XY='(-1250,-1025)',
 ROT='0',
 VER='1',
 PACK_TYPE='0402LF',
 CDS_LIB='pure_quanta',
 CDS_PART_NAME='Q_RES_0402LF-1.5K,1%,1/16W,CHIA',
 WATTAGE='1/16W',
 TOLERANCE='1%',
 MATERIAL='CHIP',
 VALUE='1.5K',
 PRIM_FILE='./archive_libs/logical/q_res/chips/chips.prt';

PART_NAME
 R4410 'Q_RES_0402LF-1.5K,1%,1/16W,CHIA':;

SECTION_NUMBER 1
 '@S9S_MB_2U_LIB.S9S_MB_2U(SCH_1):PAGE123_I14@PURE_QUANTA.Q_RES(CHIPS)':
 C_PATH='@s9s_mb_2u_lib.s9s_mb_2u(sch_1):page123_i14@pure_quanta.q_res(chips)',
 P_PATH='@s9s_mb_2u_lib.s9s_mb_2u(sch_1):page123_i14@pure_quanta.q_res(chips)',
 PATH='I14',
 DRAWING='@S9S_MB_2U_LIB.S9S_MB_2U(SCH_1):PAGE123',
 PHYS_PAGE='123',
 XY='(-1250,-2375)',
 ROT='0',
 VER='1',
 PACK_TYPE='0402LF',
 CDS_LIB='pure_quanta',
 CDS_PART_NAME='Q_RES_0402LF-1.5K,1%,1/16W,CHIA',
 WATTAGE='1/16W',
 TOLERANCE='1%',
 MATERIAL='CHIP',
 VALUE='1.5K',
 PRIM_FILE='./archive_libs/logical/q_res/chips/chips.prt';

PART_NAME
 R4411 'Q_RES_0402LF-4.75K,1%,1/16W,CHA':;

SECTION_NUMBER 1
 '@S9S_MB_2U_LIB.S9S_MB_2U(SCH_1):PAGE123_I32@PURE_QUANTA.Q_RES(CHIPS)':
 C_PATH='@s9s_mb_2u_lib.s9s_mb_2u(sch_1):page123_i32@pure_quanta.q_res(chips)',
 P_PATH='@s9s_mb_2u_lib.s9s_mb_2u(sch_1):page123_i32@pure_quanta.q_res(chips)',
 PATH='I32',
 DRAWING='@S9S_MB_2U_LIB.S9S_MB_2U(SCH_1):PAGE123',
 PHYS_PAGE='123',
 XY='(375,-875)',
 ROT='0',
 VER='2',
 PACK_TYPE='0402LF',
 CDS_LIB='pure_quanta',
 CDS_PART_NAME='Q_RES_0402LF-4.75K,1%,1/16W,CHA',
 WATTAGE='1/16W',
 TOLERANCE='1%',
 MATERIAL='CHIP',
 VALUE='4.75K',
 PRIM_FILE='./archive_libs/logical/q_res/chips/chips.prt';

PART_NAME
 R4412 'Q_RES_0402LF-4.75K,1%,1/16W,CHA':;

SECTION_NUMBER 1
 '@S9S_MB_2U_LIB.S9S_MB_2U(SCH_1):PAGE123_I29@PURE_QUANTA.Q_RES(CHIPS)':
 C_PATH='@s9s_mb_2u_lib.s9s_mb_2u(sch_1):page123_i29@pure_quanta.q_res(chips)',
 P_PATH='@s9s_mb_2u_lib.s9s_mb_2u(sch_1):page123_i29@pure_quanta.q_res(chips)',
 PATH='I29',
 DRAWING='@S9S_MB_2U_LIB.S9S_MB_2U(SCH_1):PAGE123',
 PHYS_PAGE='123',
 XY='(375,-2225)',
 ROT='0',
 VER='2',
 PACK_TYPE='0402LF',
 CDS_LIB='pure_quanta',
 CDS_PART_NAME='Q_RES_0402LF-4.75K,1%,1/16W,CHA',
 WATTAGE='1/16W',
 TOLERANCE='1%',
 MATERIAL='CHIP',
 VALUE='4.75K',
 PRIM_FILE='./archive_libs/logical/q_res/chips/chips.prt';

PART_NAME
 R4413 'Q_RES_0402LF-33.2,1%,1/16W,CHIA':;

SECTION_NUMBER 1
 '@S9S_MB_2U_LIB.S9S_MB_2U(SCH_1):PAGE123_I33@PURE_QUANTA.Q_RES(CHIPS)':
 C_PATH='@s9s_mb_2u_lib.s9s_mb_2u(sch_1):page123_i33@pure_quanta.q_res(chips)',
 P_PATH='@s9s_mb_2u_lib.s9s_mb_2u(sch_1):page123_i33@pure_quanta.q_res(chips)',
 PATH='I33',
 DRAWING='@S9S_MB_2U_LIB.S9S_MB_2U(SCH_1):PAGE123',
 PHYS_PAGE='123',
 XY='(1025,-1250)',
 ROT='0',
 VER='1',
 PACK_TYPE='0402LF',
 CDS_LIB='pure_quanta',
 CDS_PART_NAME='Q_RES_0402LF-33.2,1%,1/16W,CHIA',
 WATTAGE='1/16W',
 TOLERANCE='1%',
 MATERIAL='CHIP',
 VALUE='33.2',
 PRIM_FILE='./archive_libs/logical/q_res/chips/chips.prt';

PART_NAME
 R4414 'Q_RES_0402LF-33.2,1%,1/16W,CHIA':;

SECTION_NUMBER 1
 '@S9S_MB_2U_LIB.S9S_MB_2U(SCH_1):PAGE123_I31@PURE_QUANTA.Q_RES(CHIPS)':
 C_PATH='@s9s_mb_2u_lib.s9s_mb_2u(sch_1):page123_i31@pure_quanta.q_res(chips)',
 P_PATH='@s9s_mb_2u_lib.s9s_mb_2u(sch_1):page123_i31@pure_quanta.q_res(chips)',
 PATH='I31',
 DRAWING='@S9S_MB_2U_LIB.S9S_MB_2U(SCH_1):PAGE123',
 PHYS_PAGE='123',
 XY='(1025,-2600)',
 ROT='0',
 VER='1',
 PACK_TYPE='0402LF',
 CDS_LIB='pure_quanta',
 CDS_PART_NAME='Q_RES_0402LF-33.2,1%,1/16W,CHIA',
 WATTAGE='1/16W',
 TOLERANCE='1%',
 MATERIAL='CHIP',
 VALUE='33.2',
 PRIM_FILE='./archive_libs/logical/q_res/chips/chips.prt';

PART_NAME
 R4419 'Q_RES_0402LF-49.9,1%,1/16W,EMPA':;

SECTION_NUMBER 1
 '@S9S_MB_2U_LIB.S9S_MB_2U(SCH_1):PAGE155_I203@PURE_QUANTA.Q_RES(CHIPS)':
 C_PATH='@s9s_mb_2u_lib.s9s_mb_2u(sch_1):page155_i203@pure_quanta.q_res(chips)',
 P_PATH='@s9s_mb_2u_lib.s9s_mb_2u(sch_1):page152_i203@pure_quanta.q_res(chips)',
 PATH='I203',
 DRAWING='@S9S_MB_2U_LIB.S9S_MB_2U(SCH_1):PAGE155',
 PHYS_PAGE='152',
 XY='(3450,3675)',
 ROT='0',
 VER='2',
 PACK_TYPE='0402LF',
 CDS_LIB='pure_quanta',
 CDS_PART_NAME='Q_RES_0402LF-49.9,1%,1/16W,EMPA',
 WATTAGE='1/16W',
 TOLERANCE='1%',
 MATERIAL='EMPTY',
 VALUE='49.9',
 PRIM_FILE='./archive_libs/logical/q_res/chips/chips.prt';

PART_NAME
 R4420 'Q_RES_0402LF-49.9,1%,1/16W,EMPA':;

SECTION_NUMBER 1
 '@S9S_MB_2U_LIB.S9S_MB_2U(SCH_1):PAGE155_I202@PURE_QUANTA.Q_RES(CHIPS)':
 C_PATH='@s9s_mb_2u_lib.s9s_mb_2u(sch_1):page155_i202@pure_quanta.q_res(chips)',
 P_PATH='@s9s_mb_2u_lib.s9s_mb_2u(sch_1):page152_i202@pure_quanta.q_res(chips)',
 PATH='I202',
 DRAWING='@S9S_MB_2U_LIB.S9S_MB_2U(SCH_1):PAGE155',
 PHYS_PAGE='152',
 XY='(3625,3675)',
 ROT='0',
 VER='2',
 PACK_TYPE='0402LF',
 CDS_LIB='pure_quanta',
 CDS_PART_NAME='Q_RES_0402LF-49.9,1%,1/16W,EMPA',
 WATTAGE='1/16W',
 TOLERANCE='1%',
 MATERIAL='EMPTY',
 VALUE='49.9',
 PRIM_FILE='./archive_libs/logical/q_res/chips/chips.prt';

PART_NAME
 R4448 'Q_RES_0402LF-10K,1%,1/16W,EMPTA':;

SECTION_NUMBER 1
 '@S9S_MB_2U_LIB.S9S_MB_2U(SCH_1):PAGE194_I9@PURE_QUANTA.Q_RES(CHIPS)':
 C_PATH='@s9s_mb_2u_lib.s9s_mb_2u(sch_1):page194_i9@pure_quanta.q_res(chips)',
 P_PATH='@s9s_mb_2u_lib.s9s_mb_2u(sch_1):page196_i9@pure_quanta.q_res(chips)',
 PATH='I9',
 DRAWING='@S9S_MB_2U_LIB.S9S_MB_2U(SCH_1):PAGE194',
 PHYS_PAGE='196',
 XY='(-3500,500)',
 ROT='0',
 VER='2',
 PACK_TYPE='0402LF',
 CDS_LIB='pure_quanta',
 CDS_PART_NAME='Q_RES_0402LF-10K,1%,1/16W,EMPTA',
 WATTAGE='1/16W',
 TOLERANCE='1%',
 MATERIAL='EMPTY',
 VALUE='10K',
 PRIM_FILE='./archive_libs/logical/q_res/chips/chips.prt';

PART_NAME
 R4449 'Q_RES_0402LF-10K,1%,1/16W,EMPTA':;

SECTION_NUMBER 1
 '@S9S_MB_2U_LIB.S9S_MB_2U(SCH_1):PAGE194_I8@PURE_QUANTA.Q_RES(CHIPS)':
 C_PATH='@s9s_mb_2u_lib.s9s_mb_2u(sch_1):page194_i8@pure_quanta.q_res(chips)',
 P_PATH='@s9s_mb_2u_lib.s9s_mb_2u(sch_1):page196_i8@pure_quanta.q_res(chips)',
 PATH='I8',
 DRAWING='@S9S_MB_2U_LIB.S9S_MB_2U(SCH_1):PAGE194',
 PHYS_PAGE='196',
 XY='(-3500,-100)',
 ROT='0',
 VER='2',
 PACK_TYPE='0402LF',
 CDS_LIB='pure_quanta',
 CDS_PART_NAME='Q_RES_0402LF-10K,1%,1/16W,EMPTA',
 WATTAGE='1/16W',
 TOLERANCE='1%',
 MATERIAL='EMPTY',
 VALUE='10K',
 PRIM_FILE='./archive_libs/logical/q_res/chips/chips.prt';

PART_NAME
 R4450 'Q_RES_0402LF-0,5%,1/16W,EMPTY,A':;

SECTION_NUMBER 1
 '@S9S_MB_2U_LIB.S9S_MB_2U(SCH_1):PAGE194_I41@PURE_QUANTA.Q_RES(CHIPS)':
 C_PATH='@s9s_mb_2u_lib.s9s_mb_2u(sch_1):page194_i41@pure_quanta.q_res(chips)',
 P_PATH='@s9s_mb_2u_lib.s9s_mb_2u(sch_1):page196_i41@pure_quanta.q_res(chips)',
 PATH='I41',
 DRAWING='@S9S_MB_2U_LIB.S9S_MB_2U(SCH_1):PAGE194',
 PHYS_PAGE='196',
 XY='(-3100,2350)',
 ROT='0',
 VER='1',
 PACK_TYPE='0402LF',
 CDS_LIB='pure_quanta',
 CDS_PART_NAME='Q_RES_0402LF-0,5%,1/16W,EMPTY,A',
 WATTAGE='1/16W',
 TOLERANCE='5%',
 MATERIAL='EMPTY',
 VALUE='0',
 PRIM_FILE='./archive_libs/logical/q_res/chips/chips.prt';

PART_NAME
 R4451 'Q_RES_0402LF-33.2,1%,1/16W,EMPA':;

SECTION_NUMBER 1
 '@S9S_MB_2U_LIB.S9S_MB_2U(SCH_1):PAGE194_I13@PURE_QUANTA.Q_RES(CHIPS)':
 C_PATH='@s9s_mb_2u_lib.s9s_mb_2u(sch_1):page194_i13@pure_quanta.q_res(chips)',
 P_PATH='@s9s_mb_2u_lib.s9s_mb_2u(sch_1):page196_i13@pure_quanta.q_res(chips)',
 PATH='I13',
 DRAWING='@S9S_MB_2U_LIB.S9S_MB_2U(SCH_1):PAGE194',
 PHYS_PAGE='196',
 XY='(-2075,975)',
 ROT='0',
 VER='1',
 PACK_TYPE='0402LF',
 CDS_LIB='pure_quanta',
 CDS_PART_NAME='Q_RES_0402LF-33.2,1%,1/16W,EMPA',
 WATTAGE='1/16W',
 TOLERANCE='1%',
 MATERIAL='EMPTY',
 VALUE='33.2',
 PRIM_FILE='./archive_libs/logical/q_res/chips/chips.prt';

PART_NAME
 R4452 'Q_RES_0402LF-10K,1%,1/16W,EMPTA':;

SECTION_NUMBER 1
 '@S9S_MB_2U_LIB.S9S_MB_2U(SCH_1):PAGE194_I27@PURE_QUANTA.Q_RES(CHIPS)':
 C_PATH='@s9s_mb_2u_lib.s9s_mb_2u(sch_1):page194_i27@pure_quanta.q_res(chips)',
 P_PATH='@s9s_mb_2u_lib.s9s_mb_2u(sch_1):page196_i27@pure_quanta.q_res(chips)',
 PATH='I27',
 DRAWING='@S9S_MB_2U_LIB.S9S_MB_2U(SCH_1):PAGE194',
 PHYS_PAGE='196',
 XY='(-1250,1325)',
 ROT='0',
 VER='2',
 PACK_TYPE='0402LF',
 CDS_LIB='pure_quanta',
 CDS_PART_NAME='Q_RES_0402LF-10K,1%,1/16W,EMPTA',
 WATTAGE='1/16W',
 TOLERANCE='1%',
 MATERIAL='EMPTY',
 VALUE='10K',
 PRIM_FILE='./archive_libs/logical/q_res/chips/chips.prt';

PART_NAME
 R4453 'Q_RES_0402LF-47K,0.1%,1/16W,EMA':;

SECTION_NUMBER 1
 '@S9S_MB_2U_LIB.S9S_MB_2U(SCH_1):PAGE194_I26@PURE_QUANTA.Q_RES(CHIPS)':
 C_PATH='@s9s_mb_2u_lib.s9s_mb_2u(sch_1):page194_i26@pure_quanta.q_res(chips)',
 P_PATH='@s9s_mb_2u_lib.s9s_mb_2u(sch_1):page196_i26@pure_quanta.q_res(chips)',
 PATH='I26',
 DRAWING='@S9S_MB_2U_LIB.S9S_MB_2U(SCH_1):PAGE194',
 PHYS_PAGE='196',
 XY='(-1250,650)',
 ROT='1',
 VER='1',
 PACK_TYPE='0402LF',
 CDS_LIB='pure_quanta',
 CDS_PART_NAME='Q_RES_0402LF-47K,0.1%,1/16W,EMA',
 WATTAGE='1/16W',
 TOLERANCE='0.1%',
 MATERIAL='EMPTY',
 VALUE='47K',
 PRIM_FILE='./archive_libs/logical/q_res/chips/chips.prt';

PART_NAME
 R4454 'Q_RES_0402LF-0,5%,1/16W,EMPTY,A':;

SECTION_NUMBER 1
 '@S9S_MB_2U_LIB.S9S_MB_2U(SCH_1):PAGE194_I17@PURE_QUANTA.Q_RES(CHIPS)':
 C_PATH='@s9s_mb_2u_lib.s9s_mb_2u(sch_1):page194_i17@pure_quanta.q_res(chips)',
 P_PATH='@s9s_mb_2u_lib.s9s_mb_2u(sch_1):page196_i17@pure_quanta.q_res(chips)',
 PATH='I17',
 DRAWING='@S9S_MB_2U_LIB.S9S_MB_2U(SCH_1):PAGE194',
 PHYS_PAGE='196',
 XY='(-1550,-2225)',
 ROT='0',
 VER='1',
 PACK_TYPE='0402LF',
 CDS_LIB='pure_quanta',
 CDS_PART_NAME='Q_RES_0402LF-0,5%,1/16W,EMPTY,A',
 WATTAGE='1/16W',
 TOLERANCE='5%',
 MATERIAL='EMPTY',
 VALUE='0',
 PRIM_FILE='./archive_libs/logical/q_res/chips/chips.prt';

PART_NAME
 R4455 'Q_RES_0402LF-0,5%,1/16W,EMPTY,A':;

SECTION_NUMBER 1
 '@S9S_MB_2U_LIB.S9S_MB_2U(SCH_1):PAGE194_I16@PURE_QUANTA.Q_RES(CHIPS)':
 C_PATH='@s9s_mb_2u_lib.s9s_mb_2u(sch_1):page194_i16@pure_quanta.q_res(chips)',
 P_PATH='@s9s_mb_2u_lib.s9s_mb_2u(sch_1):page196_i16@pure_quanta.q_res(chips)',
 PATH='I16',
 DRAWING='@S9S_MB_2U_LIB.S9S_MB_2U(SCH_1):PAGE194',
 PHYS_PAGE='196',
 XY='(-1550,-2275)',
 ROT='0',
 VER='1',
 PACK_TYPE='0402LF',
 CDS_LIB='pure_quanta',
 CDS_PART_NAME='Q_RES_0402LF-0,5%,1/16W,EMPTY,A',
 WATTAGE='1/16W',
 TOLERANCE='5%',
 MATERIAL='EMPTY',
 VALUE='0',
 PRIM_FILE='./archive_libs/logical/q_res/chips/chips.prt';

PART_NAME
 R4456 'Q_RES_0402LF-10K,1%,1/16W,EMPTA':;

SECTION_NUMBER 1
 '@S9S_MB_2U_LIB.S9S_MB_2U(SCH_1):PAGE194_I25@PURE_QUANTA.Q_RES(CHIPS)':
 C_PATH='@s9s_mb_2u_lib.s9s_mb_2u(sch_1):page194_i25@pure_quanta.q_res(chips)',
 P_PATH='@s9s_mb_2u_lib.s9s_mb_2u(sch_1):page196_i25@pure_quanta.q_res(chips)',
 PATH='I25',
 DRAWING='@S9S_MB_2U_LIB.S9S_MB_2U(SCH_1):PAGE194',
 PHYS_PAGE='196',
 XY='(-900,-175)',
 ROT='0',
 VER='1',
 PACK_TYPE='0402LF',
 CDS_LIB='pure_quanta',
 CDS_PART_NAME='Q_RES_0402LF-10K,1%,1/16W,EMPTA',
 WATTAGE='1/16W',
 TOLERANCE='1%',
 MATERIAL='EMPTY',
 VALUE='10K',
 PRIM_FILE='./archive_libs/logical/q_res/chips/chips.prt';

PART_NAME
 R4457 'Q_RES_0402LF-10K,1%,1/16W,EMPTA':;

SECTION_NUMBER 1
 '@S9S_MB_2U_LIB.S9S_MB_2U(SCH_1):PAGE194_I24@PURE_QUANTA.Q_RES(CHIPS)':
 C_PATH='@s9s_mb_2u_lib.s9s_mb_2u(sch_1):page194_i24@pure_quanta.q_res(chips)',
 P_PATH='@s9s_mb_2u_lib.s9s_mb_2u(sch_1):page196_i24@pure_quanta.q_res(chips)',
 PATH='I24',
 DRAWING='@S9S_MB_2U_LIB.S9S_MB_2U(SCH_1):PAGE194',
 PHYS_PAGE='196',
 XY='(-900,-325)',
 ROT='0',
 VER='1',
 PACK_TYPE='0402LF',
 CDS_LIB='pure_quanta',
 CDS_PART_NAME='Q_RES_0402LF-10K,1%,1/16W,EMPTA',
 WATTAGE='1/16W',
 TOLERANCE='1%',
 MATERIAL='EMPTY',
 VALUE='10K',
 PRIM_FILE='./archive_libs/logical/q_res/chips/chips.prt';

PART_NAME
 R4458 'Q_RES_0402LF-10K,1%,1/16W,EMPTA':;

SECTION_NUMBER 1
 '@S9S_MB_2U_LIB.S9S_MB_2U(SCH_1):PAGE194_I23@PURE_QUANTA.Q_RES(CHIPS)':
 C_PATH='@s9s_mb_2u_lib.s9s_mb_2u(sch_1):page194_i23@pure_quanta.q_res(chips)',
 P_PATH='@s9s_mb_2u_lib.s9s_mb_2u(sch_1):page196_i23@pure_quanta.q_res(chips)',
 PATH='I23',
 DRAWING='@S9S_MB_2U_LIB.S9S_MB_2U(SCH_1):PAGE194',
 PHYS_PAGE='196',
 XY='(-900,-450)',
 ROT='0',
 VER='1',
 PACK_TYPE='0402LF',
 CDS_LIB='pure_quanta',
 CDS_PART_NAME='Q_RES_0402LF-10K,1%,1/16W,EMPTA',
 WATTAGE='1/16W',
 TOLERANCE='1%',
 MATERIAL='EMPTY',
 VALUE='10K',
 PRIM_FILE='./archive_libs/logical/q_res/chips/chips.prt';

PART_NAME
 R4459 'Q_RES_0402LF-10K,1%,1/16W,EMPTA':;

SECTION_NUMBER 1
 '@S9S_MB_2U_LIB.S9S_MB_2U(SCH_1):PAGE194_I22@PURE_QUANTA.Q_RES(CHIPS)':
 C_PATH='@s9s_mb_2u_lib.s9s_mb_2u(sch_1):page194_i22@pure_quanta.q_res(chips)',
 P_PATH='@s9s_mb_2u_lib.s9s_mb_2u(sch_1):page196_i22@pure_quanta.q_res(chips)',
 PATH='I22',
 DRAWING='@S9S_MB_2U_LIB.S9S_MB_2U(SCH_1):PAGE194',
 PHYS_PAGE='196',
 XY='(-900,-575)',
 ROT='0',
 VER='1',
 PACK_TYPE='0402LF',
 CDS_LIB='pure_quanta',
 CDS_PART_NAME='Q_RES_0402LF-10K,1%,1/16W,EMPTA',
 WATTAGE='1/16W',
 TOLERANCE='1%',
 MATERIAL='EMPTY',
 VALUE='10K',
 PRIM_FILE='./archive_libs/logical/q_res/chips/chips.prt';

PART_NAME
 R4460 'Q_RES_0402LF-0,5%,1/16W,CHIP,CA':;

SECTION_NUMBER 1
 '@S9S_MB_2U_LIB.S9S_MB_2U(SCH_1):PAGE194_I18@PURE_QUANTA.Q_RES(CHIPS)':
 C_PATH='@s9s_mb_2u_lib.s9s_mb_2u(sch_1):page194_i18@pure_quanta.q_res(chips)',
 P_PATH='@s9s_mb_2u_lib.s9s_mb_2u(sch_1):page196_i18@pure_quanta.q_res(chips)',
 PATH='I18',
 DRAWING='@S9S_MB_2U_LIB.S9S_MB_2U(SCH_1):PAGE194',
 PHYS_PAGE='196',
 XY='(-1350,-2100)',
 ROT='0',
 VER='2',
 PACK_TYPE='0402LF',
 CDS_LIB='pure_quanta',
 CDS_PART_NAME='Q_RES_0402LF-0,5%,1/16W,CHIP,CA',
 WATTAGE='1/16W',
 TOLERANCE='5%',
 MATERIAL='CHIP',
 VALUE='0',
 PRIM_FILE='./archive_libs/logical/q_res/chips/chips.prt';

PART_NAME
 R4461 'Q_RES_0402LF-0,5%,1/16W,CHIP,CA':;

SECTION_NUMBER 1
 '@S9S_MB_2U_LIB.S9S_MB_2U(SCH_1):PAGE194_I19@PURE_QUANTA.Q_RES(CHIPS)':
 C_PATH='@s9s_mb_2u_lib.s9s_mb_2u(sch_1):page194_i19@pure_quanta.q_res(chips)',
 P_PATH='@s9s_mb_2u_lib.s9s_mb_2u(sch_1):page196_i19@pure_quanta.q_res(chips)',
 PATH='I19',
 DRAWING='@S9S_MB_2U_LIB.S9S_MB_2U(SCH_1):PAGE194',
 PHYS_PAGE='196',
 XY='(-1275,-2100)',
 ROT='0',
 VER='2',
 PACK_TYPE='0402LF',
 CDS_LIB='pure_quanta',
 CDS_PART_NAME='Q_RES_0402LF-0,5%,1/16W,CHIP,CA',
 WATTAGE='1/16W',
 TOLERANCE='5%',
 MATERIAL='CHIP',
 VALUE='0',
 PRIM_FILE='./archive_libs/logical/q_res/chips/chips.prt';

PART_NAME
 R4462 'Q_RES_0402LF-0,5%,1/16W,EMPTY,A':;

SECTION_NUMBER 1
 '@S9S_MB_2U_LIB.S9S_MB_2U(SCH_1):PAGE194_I50@PURE_QUANTA.Q_RES(CHIPS)':
 C_PATH='@s9s_mb_2u_lib.s9s_mb_2u(sch_1):page194_i50@pure_quanta.q_res(chips)',
 P_PATH='@s9s_mb_2u_lib.s9s_mb_2u(sch_1):page196_i50@pure_quanta.q_res(chips)',
 PATH='I50',
 DRAWING='@S9S_MB_2U_LIB.S9S_MB_2U(SCH_1):PAGE194',
 PHYS_PAGE='196',
 XY='(-450,1475)',
 ROT='0',
 VER='1',
 PACK_TYPE='0402LF',
 CDS_LIB='pure_quanta',
 CDS_PART_NAME='Q_RES_0402LF-0,5%,1/16W,EMPTY,A',
 WATTAGE='1/16W',
 TOLERANCE='5%',
 MATERIAL='EMPTY',
 VALUE='0',
 PRIM_FILE='./archive_libs/logical/q_res/chips/chips.prt';

PART_NAME
 R4463 'Q_RES_0402LF-680,1%,1/16W,EMPTA':;

SECTION_NUMBER 1
 '@S9S_MB_2U_LIB.S9S_MB_2U(SCH_1):PAGE194_I37@PURE_QUANTA.Q_RES(CHIPS)':
 C_PATH='@s9s_mb_2u_lib.s9s_mb_2u(sch_1):page194_i37@pure_quanta.q_res(chips)',
 P_PATH='@s9s_mb_2u_lib.s9s_mb_2u(sch_1):page196_i37@pure_quanta.q_res(chips)',
 PATH='I37',
 DRAWING='@S9S_MB_2U_LIB.S9S_MB_2U(SCH_1):PAGE194',
 PHYS_PAGE='196',
 XY='(-425,650)',
 ROT='0',
 VER='2',
 PACK_TYPE='0402LF',
 CDS_LIB='pure_quanta',
 CDS_PART_NAME='Q_RES_0402LF-680,1%,1/16W,EMPTA',
 WATTAGE='1/16W',
 TOLERANCE='1%',
 MATERIAL='EMPTY',
 VALUE='680',
 PRIM_FILE='./archive_libs/logical/q_res/chips/chips.prt';

PART_NAME
 R4464 'Q_RES_0402LF-100K,1%,1/16W,EMPA':;

SECTION_NUMBER 1
 '@S9S_MB_2U_LIB.S9S_MB_2U(SCH_1):PAGE194_I38@PURE_QUANTA.Q_RES(CHIPS)':
 C_PATH='@s9s_mb_2u_lib.s9s_mb_2u(sch_1):page194_i38@pure_quanta.q_res(chips)',
 P_PATH='@s9s_mb_2u_lib.s9s_mb_2u(sch_1):page196_i38@pure_quanta.q_res(chips)',
 PATH='I38',
 DRAWING='@S9S_MB_2U_LIB.S9S_MB_2U(SCH_1):PAGE194',
 PHYS_PAGE='196',
 XY='(-100,625)',
 ROT='0',
 VER='2',
 PACK_TYPE='0402LF',
 CDS_LIB='pure_quanta',
 CDS_PART_NAME='Q_RES_0402LF-100K,1%,1/16W,EMPA',
 WATTAGE='1/16W',
 TOLERANCE='1%',
 MATERIAL='EMPTY',
 VALUE='100K',
 PRIM_FILE='./archive_libs/logical/q_res/chips/chips.prt';

PART_NAME
 R4465 'Q_RES_0402LF-3.9K,5%,1/16W,EMPA':;

SECTION_NUMBER 1
 '@S9S_MB_2U_LIB.S9S_MB_2U(SCH_1):PAGE194_I4@PURE_QUANTA.Q_RES(CHIPS)':
 C_PATH='@s9s_mb_2u_lib.s9s_mb_2u(sch_1):page194_i4@pure_quanta.q_res(chips)',
 P_PATH='@s9s_mb_2u_lib.s9s_mb_2u(sch_1):page196_i4@pure_quanta.q_res(chips)',
 PATH='I4',
 DRAWING='@S9S_MB_2U_LIB.S9S_MB_2U(SCH_1):PAGE194',
 PHYS_PAGE='196',
 XY='(-25,-2700)',
 ROT='0',
 VER='2',
 PACK_TYPE='0402LF',
 CDS_LIB='pure_quanta',
 CDS_PART_NAME='Q_RES_0402LF-3.9K,5%,1/16W,EMPA',
 WATTAGE='1/16W',
 TOLERANCE='5%',
 MATERIAL='EMPTY',
 VALUE='3.9K',
 PRIM_FILE='./archive_libs/logical/q_res/chips/chips.prt';

PART_NAME
 R4466 'Q_RES_0402LF-0,5%,1/16W,EMPTY,A':;

SECTION_NUMBER 1
 '@S9S_MB_2U_LIB.S9S_MB_2U(SCH_1):PAGE194_I75@PURE_QUANTA.Q_RES(CHIPS)':
 C_PATH='@s9s_mb_2u_lib.s9s_mb_2u(sch_1):page194_i75@pure_quanta.q_res(chips)',
 P_PATH='@s9s_mb_2u_lib.s9s_mb_2u(sch_1):page196_i75@pure_quanta.q_res(chips)',
 PATH='I75',
 DRAWING='@S9S_MB_2U_LIB.S9S_MB_2U(SCH_1):PAGE194',
 PHYS_PAGE='196',
 XY='(2125,1825)',
 ROT='0',
 VER='1',
 PACK_TYPE='0402LF',
 CDS_LIB='pure_quanta',
 CDS_PART_NAME='Q_RES_0402LF-0,5%,1/16W,EMPTY,A',
 WATTAGE='1/16W',
 TOLERANCE='5%',
 MATERIAL='EMPTY',
 VALUE='0',
 PRIM_FILE='./archive_libs/logical/q_res/chips/chips.prt';

PART_NAME
 R4467 'Q_RES_0402LF-0,5%,1/16W,CHIP,CA':;

SECTION_NUMBER 1
 '@S9S_MB_2U_LIB.S9S_MB_2U(SCH_1):PAGE194_I61@PURE_QUANTA.Q_RES(CHIPS)':
 C_PATH='@s9s_mb_2u_lib.s9s_mb_2u(sch_1):page194_i61@pure_quanta.q_res(chips)',
 P_PATH='@s9s_mb_2u_lib.s9s_mb_2u(sch_1):page196_i61@pure_quanta.q_res(chips)',
 PATH='I61',
 DRAWING='@S9S_MB_2U_LIB.S9S_MB_2U(SCH_1):PAGE194',
 PHYS_PAGE='196',
 XY='(2250,-2225)',
 ROT='0',
 VER='1',
 PACK_TYPE='0402LF',
 CDS_LIB='pure_quanta',
 CDS_PART_NAME='Q_RES_0402LF-0,5%,1/16W,CHIP,CA',
 WATTAGE='1/16W',
 TOLERANCE='5%',
 MATERIAL='CHIP',
 VALUE='0',
 PRIM_FILE='./archive_libs/logical/q_res/chips/chips.prt';

PART_NAME
 R4468 'Q_RES_0402LF-0,5%,1/16W,CHIP,CA':;

SECTION_NUMBER 1
 '@S9S_MB_2U_LIB.S9S_MB_2U(SCH_1):PAGE194_I60@PURE_QUANTA.Q_RES(CHIPS)':
 C_PATH='@s9s_mb_2u_lib.s9s_mb_2u(sch_1):page194_i60@pure_quanta.q_res(chips)',
 P_PATH='@s9s_mb_2u_lib.s9s_mb_2u(sch_1):page196_i60@pure_quanta.q_res(chips)',
 PATH='I60',
 DRAWING='@S9S_MB_2U_LIB.S9S_MB_2U(SCH_1):PAGE194',
 PHYS_PAGE='196',
 XY='(2250,-2275)',
 ROT='0',
 VER='1',
 PACK_TYPE='0402LF',
 CDS_LIB='pure_quanta',
 CDS_PART_NAME='Q_RES_0402LF-0,5%,1/16W,CHIP,CA',
 WATTAGE='1/16W',
 TOLERANCE='5%',
 MATERIAL='CHIP',
 VALUE='0',
 PRIM_FILE='./archive_libs/logical/q_res/chips/chips.prt';

PART_NAME
 R4471 'Q_RES_0402LF-0,5%,1/16W,EMPTY,A':;

SECTION_NUMBER 1
 '@S9S_MB_2U_LIB.S9S_MB_2U(SCH_1):PAGE194_I77@PURE_QUANTA.Q_RES(CHIPS)':
 C_PATH='@s9s_mb_2u_lib.s9s_mb_2u(sch_1):page194_i77@pure_quanta.q_res(chips)',
 P_PATH='@s9s_mb_2u_lib.s9s_mb_2u(sch_1):page196_i77@pure_quanta.q_res(chips)',
 PATH='I77',
 DRAWING='@S9S_MB_2U_LIB.S9S_MB_2U(SCH_1):PAGE194',
 PHYS_PAGE='196',
 XY='(3200,1475)',
 ROT='0',
 VER='1',
 PACK_TYPE='0402LF',
 CDS_LIB='pure_quanta',
 CDS_PART_NAME='Q_RES_0402LF-0,5%,1/16W,EMPTY,A',
 WATTAGE='1/16W',
 TOLERANCE='5%',
 MATERIAL='EMPTY',
 VALUE='0',
 PRIM_FILE='./archive_libs/logical/q_res/chips/chips.prt';

PART_NAME
 R4472 'Q_RES_0402LF-0,5%,1/16W,EMPTY,A':;

SECTION_NUMBER 1
 '@S9S_MB_2U_LIB.S9S_MB_2U(SCH_1):PAGE194_I78@PURE_QUANTA.Q_RES(CHIPS)':
 C_PATH='@s9s_mb_2u_lib.s9s_mb_2u(sch_1):page194_i78@pure_quanta.q_res(chips)',
 P_PATH='@s9s_mb_2u_lib.s9s_mb_2u(sch_1):page196_i78@pure_quanta.q_res(chips)',
 PATH='I78',
 DRAWING='@S9S_MB_2U_LIB.S9S_MB_2U(SCH_1):PAGE194',
 PHYS_PAGE='196',
 XY='(3200,1425)',
 ROT='0',
 VER='1',
 PACK_TYPE='0402LF',
 CDS_LIB='pure_quanta',
 CDS_PART_NAME='Q_RES_0402LF-0,5%,1/16W,EMPTY,A',
 WATTAGE='1/16W',
 TOLERANCE='5%',
 MATERIAL='EMPTY',
 VALUE='0',
 PRIM_FILE='./archive_libs/logical/q_res/chips/chips.prt';

PART_NAME
 R4473 'Q_RES_0402LF-0,5%,1/16W,CHIP,CA':;

SECTION_NUMBER 1
 '@S9S_MB_2U_LIB.S9S_MB_2U(SCH_1):PAGE194_I73@PURE_QUANTA.Q_RES(CHIPS)':
 C_PATH='@s9s_mb_2u_lib.s9s_mb_2u(sch_1):page194_i73@pure_quanta.q_res(chips)',
 P_PATH='@s9s_mb_2u_lib.s9s_mb_2u(sch_1):page196_i73@pure_quanta.q_res(chips)',
 PATH='I73',
 DRAWING='@S9S_MB_2U_LIB.S9S_MB_2U(SCH_1):PAGE194',
 PHYS_PAGE='196',
 XY='(3375,1200)',
 ROT='0',
 VER='2',
 PACK_TYPE='0402LF',
 CDS_LIB='pure_quanta',
 CDS_PART_NAME='Q_RES_0402LF-0,5%,1/16W,CHIP,CA',
 WATTAGE='1/16W',
 TOLERANCE='5%',
 MATERIAL='CHIP',
 VALUE='0',
 PRIM_FILE='./archive_libs/logical/q_res/chips/chips.prt';

PART_NAME
 R4474 'Q_RES_0402LF-0,5%,1/16W,CHIP,CA':;

SECTION_NUMBER 1
 '@S9S_MB_2U_LIB.S9S_MB_2U(SCH_1):PAGE194_I72@PURE_QUANTA.Q_RES(CHIPS)':
 C_PATH='@s9s_mb_2u_lib.s9s_mb_2u(sch_1):page194_i72@pure_quanta.q_res(chips)',
 P_PATH='@s9s_mb_2u_lib.s9s_mb_2u(sch_1):page196_i72@pure_quanta.q_res(chips)',
 PATH='I72',
 DRAWING='@S9S_MB_2U_LIB.S9S_MB_2U(SCH_1):PAGE194',
 PHYS_PAGE='196',
 XY='(3475,1200)',
 ROT='0',
 VER='2',
 PACK_TYPE='0402LF',
 CDS_LIB='pure_quanta',
 CDS_PART_NAME='Q_RES_0402LF-0,5%,1/16W,CHIP,CA',
 WATTAGE='1/16W',
 TOLERANCE='5%',
 MATERIAL='CHIP',
 VALUE='0',
 PRIM_FILE='./archive_libs/logical/q_res/chips/chips.prt';

PART_NAME
 R4475 'Q_RES_0603LF-1,1%,1/10W,CHIP,CA':;

SECTION_NUMBER 1
 '@S9S_MB_2U_LIB.S9S_MB_2U(SCH_1):PAGE200_I11@PURE_QUANTA.Q_RES(CHIPS)':
 C_PATH='@s9s_mb_2u_lib.s9s_mb_2u(sch_1):page200_i11@pure_quanta.q_res(chips)',
 P_PATH='@s9s_mb_2u_lib.s9s_mb_2u(sch_1):page211_i11@pure_quanta.q_res(chips)',
 PATH='I11',
 DRAWING='@S9S_MB_2U_LIB.S9S_MB_2U(SCH_1):PAGE200',
 PHYS_PAGE='211',
 XY='(5650,7525)',
 ROT='0',
 VER='1',
 PACK_TYPE='0603LF',
 CDS_LIB='pure_quanta',
 CDS_PART_NAME='Q_RES_0603LF-1,1%,1/10W,CHIP,CA',
 WATTAGE='1/10W',
 TOLERANCE='1%',
 MATERIAL='CHIP',
 VALUE='1',
 PRIM_FILE='./archive_libs/logical/q_res/chips/chips.prt';

PART_NAME
 R4476 'Q_RES_0402LF-49.9,1%,1/16W,CHIA':;

SECTION_NUMBER 1
 '@S9S_MB_2U_LIB.S9S_MB_2U(SCH_1):PAGE200_I39@PURE_QUANTA.Q_RES(CHIPS)':
 C_PATH='@s9s_mb_2u_lib.s9s_mb_2u(sch_1):page200_i39@pure_quanta.q_res(chips)',
 P_PATH='@s9s_mb_2u_lib.s9s_mb_2u(sch_1):page211_i39@pure_quanta.q_res(chips)',
 PATH='I39',
 DRAWING='@S9S_MB_2U_LIB.S9S_MB_2U(SCH_1):PAGE200',
 PHYS_PAGE='211',
 XY='(6525,5775)',
 ROT='0',
 VER='1',
 PACK_TYPE='0402LF',
 CDS_LIB='pure_quanta',
 CDS_PART_NAME='Q_RES_0402LF-49.9,1%,1/16W,CHIA',
 WATTAGE='1/16W',
 TOLERANCE='1%',
 MATERIAL='CHIP',
 VALUE='49.9',
 PRIM_FILE='./archive_libs/logical/q_res/chips/chips.prt';

PART_NAME
 R4477 'Q_RES_0402LF-33.2,1%,1/16W,CHIA':;

SECTION_NUMBER 1
 '@S9S_MB_2U_LIB.S9S_MB_2U(SCH_1):PAGE200_I74@PURE_QUANTA.Q_RES(CHIPS)':
 C_PATH='@s9s_mb_2u_lib.s9s_mb_2u(sch_1):page200_i74@pure_quanta.q_res(chips)',
 P_PATH='@s9s_mb_2u_lib.s9s_mb_2u(sch_1):page211_i74@pure_quanta.q_res(chips)',
 PATH='I74',
 DRAWING='@S9S_MB_2U_LIB.S9S_MB_2U(SCH_1):PAGE200',
 PHYS_PAGE='211',
 XY='(10250,5725)',
 ROT='0',
 VER='1',
 PACK_TYPE='0402LF',
 LOCATION='R4477',
 CDS_LIB='pure_quanta',
 CDS_PART_NAME='Q_RES_0402LF-33.2,1%,1/16W,CHIA',
 WATTAGE='1/16W',
 TOLERANCE='1%',
 MATERIAL='CHIP',
 VALUE='33.2',
 PRIM_FILE='./archive_libs/logical/q_res/chips/chips.prt';

PART_NAME
 R4478 'Q_RES_0402LF-33.2,1%,1/16W,CHIA':;

SECTION_NUMBER 1
 '@S9S_MB_2U_LIB.S9S_MB_2U(SCH_1):PAGE200_I75@PURE_QUANTA.Q_RES(CHIPS)':
 C_PATH='@s9s_mb_2u_lib.s9s_mb_2u(sch_1):page200_i75@pure_quanta.q_res(chips)',
 P_PATH='@s9s_mb_2u_lib.s9s_mb_2u(sch_1):page211_i75@pure_quanta.q_res(chips)',
 PATH='I75',
 DRAWING='@S9S_MB_2U_LIB.S9S_MB_2U(SCH_1):PAGE200',
 PHYS_PAGE='211',
 XY='(10250,5675)',
 ROT='0',
 VER='1',
 PACK_TYPE='0402LF',
 LOCATION='R4478',
 CDS_LIB='pure_quanta',
 CDS_PART_NAME='Q_RES_0402LF-33.2,1%,1/16W,CHIA',
 WATTAGE='1/16W',
 TOLERANCE='1%',
 MATERIAL='CHIP',
 VALUE='33.2',
 PRIM_FILE='./archive_libs/logical/q_res/chips/chips.prt';

PART_NAME
 R4479 'Q_RES_0402LF-33.2,1%,1/16W,CHIA':;

SECTION_NUMBER 1
 '@S9S_MB_2U_LIB.S9S_MB_2U(SCH_1):PAGE200_I76@PURE_QUANTA.Q_RES(CHIPS)':
 C_PATH='@s9s_mb_2u_lib.s9s_mb_2u(sch_1):page200_i76@pure_quanta.q_res(chips)',
 P_PATH='@s9s_mb_2u_lib.s9s_mb_2u(sch_1):page211_i76@pure_quanta.q_res(chips)',
 PATH='I76',
 DRAWING='@S9S_MB_2U_LIB.S9S_MB_2U(SCH_1):PAGE200',
 PHYS_PAGE='211',
 XY='(10250,5625)',
 ROT='0',
 VER='1',
 PACK_TYPE='0402LF',
 LOCATION='R4479',
 CDS_LIB='pure_quanta',
 CDS_PART_NAME='Q_RES_0402LF-33.2,1%,1/16W,CHIA',
 WATTAGE='1/16W',
 TOLERANCE='1%',
 MATERIAL='CHIP',
 VALUE='33.2',
 PRIM_FILE='./archive_libs/logical/q_res/chips/chips.prt';

PART_NAME
 R4480 'Q_RES_0402LF-33.2,1%,1/16W,CHIA':;

SECTION_NUMBER 1
 '@S9S_MB_2U_LIB.S9S_MB_2U(SCH_1):PAGE225_I24@PURE_QUANTA.Q_RES(CHIPS)':
 C_PATH='@s9s_mb_2u_lib.s9s_mb_2u(sch_1):page225_i24@pure_quanta.q_res(chips)',
 P_PATH='@s9s_mb_2u_lib.s9s_mb_2u(sch_1):page237_i24@pure_quanta.q_res(chips)',
 PATH='I24',
 DRAWING='@S9S_MB_2U_LIB.S9S_MB_2U(SCH_1):PAGE225',
 PHYS_PAGE='237',
 XY='(1525,-1525)',
 ROT='0',
 VER='1',
 PACK_TYPE='0402LF',
 CDS_LIB='pure_quanta',
 CDS_PART_NAME='Q_RES_0402LF-33.2,1%,1/16W,CHIA',
 WATTAGE='1/16W',
 TOLERANCE='1%',
 MATERIAL='CHIP',
 VALUE='33.2',
 PRIM_FILE='./archive_libs/logical/q_res/chips/chips.prt';

PART_NAME
 R4481 'Q_RES_0402LF-33.2,1%,1/16W,CHIA':;

SECTION_NUMBER 1
 '@S9S_MB_2U_LIB.S9S_MB_2U(SCH_1):PAGE225_I25@PURE_QUANTA.Q_RES(CHIPS)':
 C_PATH='@s9s_mb_2u_lib.s9s_mb_2u(sch_1):page225_i25@pure_quanta.q_res(chips)',
 P_PATH='@s9s_mb_2u_lib.s9s_mb_2u(sch_1):page237_i25@pure_quanta.q_res(chips)',
 PATH='I25',
 DRAWING='@S9S_MB_2U_LIB.S9S_MB_2U(SCH_1):PAGE225',
 PHYS_PAGE='237',
 XY='(1525,-1575)',
 ROT='0',
 VER='1',
 PACK_TYPE='0402LF',
 CDS_LIB='pure_quanta',
 CDS_PART_NAME='Q_RES_0402LF-33.2,1%,1/16W,CHIA',
 WATTAGE='1/16W',
 TOLERANCE='1%',
 MATERIAL='CHIP',
 VALUE='33.2',
 PRIM_FILE='./archive_libs/logical/q_res/chips/chips.prt';

PART_NAME
 R4482 'Q_RES_0402LF-49.9,1%,1/16W,EMPA':;

SECTION_NUMBER 1
 '@S9S_MB_2U_LIB.S9S_MB_2U(SCH_1):PAGE155_I208@PURE_QUANTA.Q_RES(CHIPS)':
 C_PATH='@s9s_mb_2u_lib.s9s_mb_2u(sch_1):page155_i208@pure_quanta.q_res(chips)',
 P_PATH='@s9s_mb_2u_lib.s9s_mb_2u(sch_1):page152_i208@pure_quanta.q_res(chips)',
 PATH='I208',
 DRAWING='@S9S_MB_2U_LIB.S9S_MB_2U(SCH_1):PAGE155',
 PHYS_PAGE='152',
 XY='(-2450,1025)',
 ROT='0',
 VER='2',
 PACK_TYPE='0402LF',
 CDS_LIB='pure_quanta',
 CDS_PART_NAME='Q_RES_0402LF-49.9,1%,1/16W,EMPA',
 WATTAGE='1/16W',
 TOLERANCE='1%',
 MATERIAL='EMPTY',
 VALUE='49.9',
 PRIM_FILE='./archive_libs/logical/q_res/chips/chips.prt';

PART_NAME
 R4483 'Q_RES_0402LF-49.9,1%,1/16W,EMPA':;

SECTION_NUMBER 1
 '@S9S_MB_2U_LIB.S9S_MB_2U(SCH_1):PAGE155_I206@PURE_QUANTA.Q_RES(CHIPS)':
 C_PATH='@s9s_mb_2u_lib.s9s_mb_2u(sch_1):page155_i206@pure_quanta.q_res(chips)',
 P_PATH='@s9s_mb_2u_lib.s9s_mb_2u(sch_1):page152_i206@pure_quanta.q_res(chips)',
 PATH='I206',
 DRAWING='@S9S_MB_2U_LIB.S9S_MB_2U(SCH_1):PAGE155',
 PHYS_PAGE='152',
 XY='(-2275,1025)',
 ROT='0',
 VER='2',
 PACK_TYPE='0402LF',
 CDS_LIB='pure_quanta',
 CDS_PART_NAME='Q_RES_0402LF-49.9,1%,1/16W,EMPA',
 WATTAGE='1/16W',
 TOLERANCE='1%',
 MATERIAL='EMPTY',
 VALUE='49.9',
 PRIM_FILE='./archive_libs/logical/q_res/chips/chips.prt';

PART_NAME
 R4486 'Q_RES_0402LF-49.9,1%,1/16W,EMPA':;

SECTION_NUMBER 1
 '@S9S_MB_2U_LIB.S9S_MB_2U(SCH_1):PAGE194_I90@PURE_QUANTA.Q_RES(CHIPS)':
 C_PATH='@s9s_mb_2u_lib.s9s_mb_2u(sch_1):page194_i90@pure_quanta.q_res(chips)',
 P_PATH='@s9s_mb_2u_lib.s9s_mb_2u(sch_1):page196_i90@pure_quanta.q_res(chips)',
 PATH='I90',
 DRAWING='@S9S_MB_2U_LIB.S9S_MB_2U(SCH_1):PAGE194',
 PHYS_PAGE='196',
 XY='(-1750,-1475)',
 ROT='0',
 VER='2',
 PACK_TYPE='0402LF',
 CDS_LIB='pure_quanta',
 CDS_PART_NAME='Q_RES_0402LF-49.9,1%,1/16W,EMPA',
 WATTAGE='1/16W',
 TOLERANCE='1%',
 MATERIAL='EMPTY',
 VALUE='49.9',
 PRIM_FILE='./archive_libs/logical/q_res/chips/chips.prt';

PART_NAME
 R4487 'Q_RES_0402LF-49.9,1%,1/16W,EMPA':;

SECTION_NUMBER 1
 '@S9S_MB_2U_LIB.S9S_MB_2U(SCH_1):PAGE194_I88@PURE_QUANTA.Q_RES(CHIPS)':
 C_PATH='@s9s_mb_2u_lib.s9s_mb_2u(sch_1):page194_i88@pure_quanta.q_res(chips)',
 P_PATH='@s9s_mb_2u_lib.s9s_mb_2u(sch_1):page196_i88@pure_quanta.q_res(chips)',
 PATH='I88',
 DRAWING='@S9S_MB_2U_LIB.S9S_MB_2U(SCH_1):PAGE194',
 PHYS_PAGE='196',
 XY='(-1575,-1475)',
 ROT='0',
 VER='2',
 PACK_TYPE='0402LF',
 CDS_LIB='pure_quanta',
 CDS_PART_NAME='Q_RES_0402LF-49.9,1%,1/16W,EMPA',
 WATTAGE='1/16W',
 TOLERANCE='1%',
 MATERIAL='EMPTY',
 VALUE='49.9',
 PRIM_FILE='./archive_libs/logical/q_res/chips/chips.prt';

PART_NAME
 R4489 'Q_RES_0402LF-4.75K,1%,1/16W,CHA':;

SECTION_NUMBER 1
 '@S9S_MB_2U_LIB.S9S_MB_2U(SCH_1):PAGE200_I30@PURE_QUANTA.Q_RES(CHIPS)':
 C_PATH='@s9s_mb_2u_lib.s9s_mb_2u(sch_1):page200_i30@pure_quanta.q_res(chips)',
 P_PATH='@s9s_mb_2u_lib.s9s_mb_2u(sch_1):page211_i30@pure_quanta.q_res(chips)',
 PATH='I30',
 DRAWING='@S9S_MB_2U_LIB.S9S_MB_2U(SCH_1):PAGE200',
 PHYS_PAGE='211',
 XY='(7275,4100)',
 ROT='0',
 VER='2',
 PACK_TYPE='0402LF',
 CDS_LIB='pure_quanta',
 CDS_PART_NAME='Q_RES_0402LF-4.75K,1%,1/16W,CHA',
 WATTAGE='1/16W',
 TOLERANCE='1%',
 MATERIAL='CHIP',
 VALUE='4.75K',
 PRIM_FILE='./archive_libs/logical/q_res/chips/chips.prt';

PART_NAME
 R4490 'Q_RES_0402LF-4.75K,1%,1/16W,EMA':;

SECTION_NUMBER 1
 '@S9S_MB_2U_LIB.S9S_MB_2U(SCH_1):PAGE200_I31@PURE_QUANTA.Q_RES(CHIPS)':
 C_PATH='@s9s_mb_2u_lib.s9s_mb_2u(sch_1):page200_i31@pure_quanta.q_res(chips)',
 P_PATH='@s9s_mb_2u_lib.s9s_mb_2u(sch_1):page211_i31@pure_quanta.q_res(chips)',
 PATH='I31',
 DRAWING='@S9S_MB_2U_LIB.S9S_MB_2U(SCH_1):PAGE200',
 PHYS_PAGE='211',
 XY='(7275,3675)',
 ROT='0',
 VER='2',
 PACK_TYPE='0402LF',
 CDS_LIB='pure_quanta',
 CDS_PART_NAME='Q_RES_0402LF-4.75K,1%,1/16W,EMA',
 WATTAGE='1/16W',
 TOLERANCE='1%',
 MATERIAL='EMPTY',
 VALUE='4.75K',
 PRIM_FILE='./archive_libs/logical/q_res/chips/chips.prt';

PART_NAME
 R4491 'Q_RES_0402LF-10K,1%,1/16W,CHIPA':;

SECTION_NUMBER 1
 '@S9S_MB_2U_LIB.S9S_MB_2U(SCH_1):PAGE200_I48@PURE_QUANTA.Q_RES(CHIPS)':
 C_PATH='@s9s_mb_2u_lib.s9s_mb_2u(sch_1):page200_i48@pure_quanta.q_res(chips)',
 P_PATH='@s9s_mb_2u_lib.s9s_mb_2u(sch_1):page211_i48@pure_quanta.q_res(chips)',
 PATH='I48',
 DRAWING='@S9S_MB_2U_LIB.S9S_MB_2U(SCH_1):PAGE200',
 PHYS_PAGE='211',
 XY='(9275,4100)',
 ROT='0',
 VER='2',
 PACK_TYPE='0402LF',
 CDS_LIB='pure_quanta',
 CDS_PART_NAME='Q_RES_0402LF-10K,1%,1/16W,CHIPA',
 WATTAGE='1/16W',
 TOLERANCE='1%',
 MATERIAL='CHIP',
 VALUE='10K',
 PRIM_FILE='./archive_libs/logical/q_res/chips/chips.prt';

PART_NAME
 R4492 'Q_RES_0402LF-10K,1%,1/16W,CHIPA':;

SECTION_NUMBER 1
 '@S9S_MB_2U_LIB.S9S_MB_2U(SCH_1):PAGE200_I49@PURE_QUANTA.Q_RES(CHIPS)':
 C_PATH='@s9s_mb_2u_lib.s9s_mb_2u(sch_1):page200_i49@pure_quanta.q_res(chips)',
 P_PATH='@s9s_mb_2u_lib.s9s_mb_2u(sch_1):page211_i49@pure_quanta.q_res(chips)',
 PATH='I49',
 DRAWING='@S9S_MB_2U_LIB.S9S_MB_2U(SCH_1):PAGE200',
 PHYS_PAGE='211',
 XY='(9275,3625)',
 ROT='0',
 VER='2',
 PACK_TYPE='0402LF',
 CDS_LIB='pure_quanta',
 CDS_PART_NAME='Q_RES_0402LF-10K,1%,1/16W,CHIPA',
 WATTAGE='1/16W',
 TOLERANCE='1%',
 MATERIAL='CHIP',
 VALUE='10K',
 PRIM_FILE='./archive_libs/logical/q_res/chips/chips.prt';

PART_NAME
 R4493 'Q_RES_0603LF-1,1%,1/10W,CHIP,CA':;

SECTION_NUMBER 1
 '@S9S_MB_2U_LIB.S9S_MB_2U(SCH_1):PAGE200_I4@PURE_QUANTA.Q_RES(CHIPS)':
 C_PATH='@s9s_mb_2u_lib.s9s_mb_2u(sch_1):page200_i4@pure_quanta.q_res(chips)',
 P_PATH='@s9s_mb_2u_lib.s9s_mb_2u(sch_1):page211_i4@pure_quanta.q_res(chips)',
 PATH='I4',
 DRAWING='@S9S_MB_2U_LIB.S9S_MB_2U(SCH_1):PAGE200',
 PHYS_PAGE='211',
 XY='(5600,8350)',
 ROT='0',
 VER='1',
 PACK_TYPE='0603LF',
 CDS_LIB='pure_quanta',
 CDS_PART_NAME='Q_RES_0603LF-1,1%,1/10W,CHIP,CA',
 WATTAGE='1/10W',
 TOLERANCE='1%',
 MATERIAL='CHIP',
 VALUE='1',
 PRIM_FILE='./archive_libs/logical/q_res/chips/chips.prt';

PART_NAME
 R4494 'Q_RES_0402LF-10K,1%,1/16W,CHIPA':;

SECTION_NUMBER 1
 '@S9S_MB_2U_LIB.S9S_MB_2U(SCH_1):PAGE200_I69@PURE_QUANTA.Q_RES(CHIPS)':
 C_PATH='@s9s_mb_2u_lib.s9s_mb_2u(sch_1):page200_i69@pure_quanta.q_res(chips)',
 P_PATH='@s9s_mb_2u_lib.s9s_mb_2u(sch_1):page211_i69@pure_quanta.q_res(chips)',
 PATH='I69',
 DRAWING='@S9S_MB_2U_LIB.S9S_MB_2U(SCH_1):PAGE200',
 PHYS_PAGE='211',
 XY='(10250,5575)',
 ROT='0',
 VER='1',
 PACK_TYPE='0402LF',
 CDS_LIB='pure_quanta',
 CDS_PART_NAME='Q_RES_0402LF-10K,1%,1/16W,CHIPA',
 WATTAGE='1/16W',
 TOLERANCE='1%',
 MATERIAL='CHIP',
 VALUE='10K',
 PRIM_FILE='./archive_libs/logical/q_res/chips/chips.prt';

PART_NAME
 R4495 'Q_RES_0402LF-33.2,1%,1/16W,CHIA':;

SECTION_NUMBER 1
 '@S9S_MB_2U_LIB.S9S_MB_2U(SCH_1):PAGE314_I141@PURE_QUANTA.Q_RES(CHIPS)':
 C_PATH='@s9s_mb_2u_lib.s9s_mb_2u(sch_1):page314_i141@pure_quanta.q_res(chips)',
 P_PATH='@s9s_mb_2u_lib.s9s_mb_2u(sch_1):page213_i141@pure_quanta.q_res(chips)',
 PATH='I141',
 DRAWING='@S9S_MB_2U_LIB.S9S_MB_2U(SCH_1):PAGE314',
 PHYS_PAGE='213',
 XY='(2725,825)',
 ROT='0',
 VER='1',
 PACK_TYPE='0402LF',
 CDS_LIB='pure_quanta',
 CDS_PART_NAME='Q_RES_0402LF-33.2,1%,1/16W,CHIA',
 WATTAGE='1/16W',
 TOLERANCE='1%',
 MATERIAL='CHIP',
 VALUE='33.2',
 PRIM_FILE='./archive_libs/logical/q_res/chips/chips.prt';

PART_NAME
 R4496 'Q_RES_0402LF-33.2,1%,1/16W,CHIA':;

SECTION_NUMBER 1
 '@S9S_MB_2U_LIB.S9S_MB_2U(SCH_1):PAGE225_I27@PURE_QUANTA.Q_RES(CHIPS)':
 C_PATH='@s9s_mb_2u_lib.s9s_mb_2u(sch_1):page225_i27@pure_quanta.q_res(chips)',
 P_PATH='@s9s_mb_2u_lib.s9s_mb_2u(sch_1):page237_i27@pure_quanta.q_res(chips)',
 PATH='I27',
 DRAWING='@S9S_MB_2U_LIB.S9S_MB_2U(SCH_1):PAGE225',
 PHYS_PAGE='237',
 XY='(1550,-975)',
 ROT='0',
 VER='1',
 PACK_TYPE='0402LF',
 CDS_LIB='pure_quanta',
 CDS_PART_NAME='Q_RES_0402LF-33.2,1%,1/16W,CHIA',
 WATTAGE='1/16W',
 TOLERANCE='1%',
 MATERIAL='CHIP',
 VALUE='33.2',
 PRIM_FILE='./archive_libs/logical/q_res/chips/chips.prt';

PART_NAME
 R4497 'Q_RES_0402LF-33.2,1%,1/16W,CHIA':;

SECTION_NUMBER 1
 '@S9S_MB_2U_LIB.S9S_MB_2U(SCH_1):PAGE225_I26@PURE_QUANTA.Q_RES(CHIPS)':
 C_PATH='@s9s_mb_2u_lib.s9s_mb_2u(sch_1):page225_i26@pure_quanta.q_res(chips)',
 P_PATH='@s9s_mb_2u_lib.s9s_mb_2u(sch_1):page237_i26@pure_quanta.q_res(chips)',
 PATH='I26',
 DRAWING='@S9S_MB_2U_LIB.S9S_MB_2U(SCH_1):PAGE225',
 PHYS_PAGE='237',
 XY='(1550,-1025)',
 ROT='0',
 VER='1',
 PACK_TYPE='0402LF',
 CDS_LIB='pure_quanta',
 CDS_PART_NAME='Q_RES_0402LF-33.2,1%,1/16W,CHIA',
 WATTAGE='1/16W',
 TOLERANCE='1%',
 MATERIAL='CHIP',
 VALUE='33.2',
 PRIM_FILE='./archive_libs/logical/q_res/chips/chips.prt';

PART_NAME
 R4498 'Q_RES_0402LF-4.7K,5%,1/16W,CHIA':;

SECTION_NUMBER 1
 '@S9S_MB_2U_LIB.S9S_MB_2U(SCH_1):PAGE225_I11@PURE_QUANTA.Q_RES(CHIPS)':
 C_PATH='@s9s_mb_2u_lib.s9s_mb_2u(sch_1):page225_i11@pure_quanta.q_res(chips)',
 P_PATH='@s9s_mb_2u_lib.s9s_mb_2u(sch_1):page237_i11@pure_quanta.q_res(chips)',
 PATH='I11',
 DRAWING='@S9S_MB_2U_LIB.S9S_MB_2U(SCH_1):PAGE225',
 PHYS_PAGE='237',
 XY='(1700,1025)',
 ROT='0',
 VER='2',
 PACK_TYPE='0402LF',
 CDS_LIB='pure_quanta',
 CDS_PART_NAME='Q_RES_0402LF-4.7K,5%,1/16W,CHIA',
 WATTAGE='1/16W',
 TOLERANCE='5%',
 MATERIAL='CHIP',
 VALUE='4.7K',
 PRIM_FILE='./archive_libs/logical/q_res/chips/chips.prt';

PART_NAME
 R4499 'Q_RES_0402LF-4.7K,5%,1/16W,CHIA':;

SECTION_NUMBER 1
 '@S9S_MB_2U_LIB.S9S_MB_2U(SCH_1):PAGE225_I12@PURE_QUANTA.Q_RES(CHIPS)':
 C_PATH='@s9s_mb_2u_lib.s9s_mb_2u(sch_1):page225_i12@pure_quanta.q_res(chips)',
 P_PATH='@s9s_mb_2u_lib.s9s_mb_2u(sch_1):page237_i12@pure_quanta.q_res(chips)',
 PATH='I12',
 DRAWING='@S9S_MB_2U_LIB.S9S_MB_2U(SCH_1):PAGE225',
 PHYS_PAGE='237',
 XY='(1950,1025)',
 ROT='0',
 VER='2',
 PACK_TYPE='0402LF',
 CDS_LIB='pure_quanta',
 CDS_PART_NAME='Q_RES_0402LF-4.7K,5%,1/16W,CHIA',
 WATTAGE='1/16W',
 TOLERANCE='5%',
 MATERIAL='CHIP',
 VALUE='4.7K',
 PRIM_FILE='./archive_libs/logical/q_res/chips/chips.prt';

PART_NAME
 R4500 'Q_RES_0402LF-10K,1%,1/16W,EMPTA':;

SECTION_NUMBER 1
 '@S9S_MB_2U_LIB.S9S_MB_2U(SCH_1):PAGE225_I32@PURE_QUANTA.Q_RES(CHIPS)':
 C_PATH='@s9s_mb_2u_lib.s9s_mb_2u(sch_1):page225_i32@pure_quanta.q_res(chips)',
 P_PATH='@s9s_mb_2u_lib.s9s_mb_2u(sch_1):page237_i32@pure_quanta.q_res(chips)',
 PATH='I32',
 DRAWING='@S9S_MB_2U_LIB.S9S_MB_2U(SCH_1):PAGE225',
 PHYS_PAGE='237',
 XY='(1425,1050)',
 ROT='0',
 VER='2',
 PACK_TYPE='0402LF',
 CDS_LIB='pure_quanta',
 CDS_PART_NAME='Q_RES_0402LF-10K,1%,1/16W,EMPTA',
 WATTAGE='1/16W',
 TOLERANCE='1%',
 MATERIAL='EMPTY',
 VALUE='10K',
 PRIM_FILE='./archive_libs/logical/q_res/chips/chips.prt';

PART_NAME
 R4501 'Q_RES_0402LF-0,5%,1/16W,CHIP,CA':;

SECTION_NUMBER 1
 '@S9S_MB_2U_LIB.S9S_MB_2U(SCH_1):PAGE201_I160@PURE_QUANTA.Q_RES(CHIPS)':
 C_PATH='@s9s_mb_2u_lib.s9s_mb_2u(sch_1):page201_i160@pure_quanta.q_res(chips)',
 P_PATH='@s9s_mb_2u_lib.s9s_mb_2u(sch_1):page212_i160@pure_quanta.q_res(chips)',
 PATH='I160',
 DRAWING='@S9S_MB_2U_LIB.S9S_MB_2U(SCH_1):PAGE201',
 PHYS_PAGE='212',
 XY='(-3475,4375)',
 ROT='0',
 VER='1',
 PACK_TYPE='0402LF',
 CDS_LIB='pure_quanta',
 CDS_PART_NAME='Q_RES_0402LF-0,5%,1/16W,CHIP,CA',
 WATTAGE='1/16W',
 TOLERANCE='5%',
 MATERIAL='CHIP',
 VALUE='0',
 PRIM_FILE='./archive_libs/logical/q_res/chips/chips.prt';

PART_NAME
 R4502 'Q_RES_0402LF-33.2,1%,1/16W,CHIA':;

SECTION_NUMBER 1
 '@S9S_MB_2U_LIB.S9S_MB_2U(SCH_1):PAGE133_I148@PURE_QUANTA.Q_RES(CHIPS)':
 C_PATH='@s9s_mb_2u_lib.s9s_mb_2u(sch_1):page133_i148@pure_quanta.q_res(chips)',
 P_PATH='@s9s_mb_2u_lib.s9s_mb_2u(sch_1):page131_i148@pure_quanta.q_res(chips)',
 PATH='I148',
 DRAWING='@S9S_MB_2U_LIB.S9S_MB_2U(SCH_1):PAGE133',
 PHYS_PAGE='131',
 XY='(625,750)',
 ROT='0',
 VER='1',
 PACK_TYPE='0402LF',
 CDS_LIB='pure_quanta',
 CDS_PART_NAME='Q_RES_0402LF-33.2,1%,1/16W,CHIA',
 WATTAGE='1/16W',
 TOLERANCE='1%',
 MATERIAL='CHIP',
 VALUE='33.2',
 PRIM_FILE='./archive_libs/logical/q_res/chips/chips.prt';

PART_NAME
 R4503 'Q_RES_0402LF-0,5%,1/16W,CHIP,CA':;

SECTION_NUMBER 1
 '@S9S_MB_2U_LIB.S9S_MB_2U(SCH_1):PAGE133_I153@PURE_QUANTA.Q_RES(CHIPS)':
 C_PATH='@s9s_mb_2u_lib.s9s_mb_2u(sch_1):page133_i153@pure_quanta.q_res(chips)',
 P_PATH='@s9s_mb_2u_lib.s9s_mb_2u(sch_1):page131_i153@pure_quanta.q_res(chips)',
 PATH='I153',
 DRAWING='@S9S_MB_2U_LIB.S9S_MB_2U(SCH_1):PAGE133',
 PHYS_PAGE='131',
 XY='(625,700)',
 ROT='0',
 VER='1',
 PACK_TYPE='0402LF',
 CDS_LIB='pure_quanta',
 CDS_PART_NAME='Q_RES_0402LF-0,5%,1/16W,CHIP,CA',
 WATTAGE='1/16W',
 TOLERANCE='5%',
 MATERIAL='CHIP',
 VALUE='0',
 PRIM_FILE='./archive_libs/logical/q_res/chips/chips.prt';

PART_NAME
 R4504 'Q_RES_0402LF-0,5%,1/16W,CHIP,CA':;

SECTION_NUMBER 1
 '@S9S_MB_2U_LIB.S9S_MB_2U(SCH_1):PAGE175_I308@PURE_QUANTA.Q_RES(CHIPS)':
 C_PATH='@s9s_mb_2u_lib.s9s_mb_2u(sch_1):page175_i308@pure_quanta.q_res(chips)',
 P_PATH='@s9s_mb_2u_lib.s9s_mb_2u(sch_1):page183_i308@pure_quanta.q_res(chips)',
 PATH='I308',
 DRAWING='@S9S_MB_2U_LIB.S9S_MB_2U(SCH_1):PAGE175',
 PHYS_PAGE='183',
 XY='(2950,1500)',
 ROT='0',
 VER='1',
 PACK_TYPE='0402LF',
 CDS_LIB='pure_quanta',
 CDS_PART_NAME='Q_RES_0402LF-0,5%,1/16W,CHIP,CA',
 WATTAGE='1/16W',
 TOLERANCE='5%',
 MATERIAL='CHIP',
 VALUE='0',
 PRIM_FILE='./archive_libs/logical/q_res/chips/chips.prt';

PART_NAME
 R4505 'Q_RES_0402LF-33.2,1%,1/16W,CHIA':;

SECTION_NUMBER 1
 '@S9S_MB_2U_LIB.S9S_MB_2U(SCH_1):PAGE175_I305@PURE_QUANTA.Q_RES(CHIPS)':
 C_PATH='@s9s_mb_2u_lib.s9s_mb_2u(sch_1):page175_i305@pure_quanta.q_res(chips)',
 P_PATH='@s9s_mb_2u_lib.s9s_mb_2u(sch_1):page183_i305@pure_quanta.q_res(chips)',
 PATH='I305',
 DRAWING='@S9S_MB_2U_LIB.S9S_MB_2U(SCH_1):PAGE175',
 PHYS_PAGE='183',
 XY='(2950,1450)',
 ROT='0',
 VER='1',
 PACK_TYPE='0402LF',
 CDS_LIB='pure_quanta',
 CDS_PART_NAME='Q_RES_0402LF-33.2,1%,1/16W,CHIA',
 WATTAGE='1/16W',
 TOLERANCE='1%',
 MATERIAL='CHIP',
 VALUE='33.2',
 PRIM_FILE='./archive_libs/logical/q_res/chips/chips.prt';

PART_NAME
 R4506 'Q_RES_0402LF-33.2,1%,1/16W,CHIA':;

SECTION_NUMBER 1
 '@S9S_MB_2U_LIB.S9S_MB_2U(SCH_1):PAGE227_I90@PURE_QUANTA.Q_RES(CHIPS)':
 C_PATH='@s9s_mb_2u_lib.s9s_mb_2u(sch_1):page227_i90@pure_quanta.q_res(chips)',
 P_PATH='@s9s_mb_2u_lib.s9s_mb_2u(sch_1):page240_i90@pure_quanta.q_res(chips)',
 PATH='I90',
 DRAWING='@S9S_MB_2U_LIB.S9S_MB_2U(SCH_1):PAGE227',
 PHYS_PAGE='240',
 XY='(-13275,175)',
 ROT='0',
 VER='1',
 PACK_TYPE='0402LF',
 CDS_LIB='pure_quanta',
 CDS_PART_NAME='Q_RES_0402LF-33.2,1%,1/16W,CHIA',
 WATTAGE='1/16W',
 TOLERANCE='1%',
 MATERIAL='CHIP',
 VALUE='33.2',
 PRIM_FILE='./archive_libs/logical/q_res/chips/chips.prt';

PART_NAME
 R4507 'Q_RES_0402LF-33.2,1%,1/16W,CHIA':;

SECTION_NUMBER 1
 '@S9S_MB_2U_LIB.S9S_MB_2U(SCH_1):PAGE227_I89@PURE_QUANTA.Q_RES(CHIPS)':
 C_PATH='@s9s_mb_2u_lib.s9s_mb_2u(sch_1):page227_i89@pure_quanta.q_res(chips)',
 P_PATH='@s9s_mb_2u_lib.s9s_mb_2u(sch_1):page240_i89@pure_quanta.q_res(chips)',
 PATH='I89',
 DRAWING='@S9S_MB_2U_LIB.S9S_MB_2U(SCH_1):PAGE227',
 PHYS_PAGE='240',
 XY='(-13275,125)',
 ROT='0',
 VER='1',
 PACK_TYPE='0402LF',
 CDS_LIB='pure_quanta',
 CDS_PART_NAME='Q_RES_0402LF-33.2,1%,1/16W,CHIA',
 WATTAGE='1/16W',
 TOLERANCE='1%',
 MATERIAL='CHIP',
 VALUE='33.2',
 PRIM_FILE='./archive_libs/logical/q_res/chips/chips.prt';

PART_NAME
 R4508 'Q_RES_0402LF-33.2,1%,1/16W,CHIA':;

SECTION_NUMBER 1
 '@S9S_MB_2U_LIB.S9S_MB_2U(SCH_1):PAGE227_I87@PURE_QUANTA.Q_RES(CHIPS)':
 C_PATH='@s9s_mb_2u_lib.s9s_mb_2u(sch_1):page227_i87@pure_quanta.q_res(chips)',
 P_PATH='@s9s_mb_2u_lib.s9s_mb_2u(sch_1):page240_i87@pure_quanta.q_res(chips)',
 PATH='I87',
 DRAWING='@S9S_MB_2U_LIB.S9S_MB_2U(SCH_1):PAGE227',
 PHYS_PAGE='240',
 XY='(-13275,75)',
 ROT='0',
 VER='1',
 PACK_TYPE='0402LF',
 CDS_LIB='pure_quanta',
 CDS_PART_NAME='Q_RES_0402LF-33.2,1%,1/16W,CHIA',
 WATTAGE='1/16W',
 TOLERANCE='1%',
 MATERIAL='CHIP',
 VALUE='33.2',
 PRIM_FILE='./archive_libs/logical/q_res/chips/chips.prt';

PART_NAME
 R4509 'Q_RES_0402LF-33.2,1%,1/16W,CHIA':;

SECTION_NUMBER 1
 '@S9S_MB_2U_LIB.S9S_MB_2U(SCH_1):PAGE227_I88@PURE_QUANTA.Q_RES(CHIPS)':
 C_PATH='@s9s_mb_2u_lib.s9s_mb_2u(sch_1):page227_i88@pure_quanta.q_res(chips)',
 P_PATH='@s9s_mb_2u_lib.s9s_mb_2u(sch_1):page240_i88@pure_quanta.q_res(chips)',
 PATH='I88',
 DRAWING='@S9S_MB_2U_LIB.S9S_MB_2U(SCH_1):PAGE227',
 PHYS_PAGE='240',
 XY='(-13275,25)',
 ROT='0',
 VER='1',
 PACK_TYPE='0402LF',
 CDS_LIB='pure_quanta',
 CDS_PART_NAME='Q_RES_0402LF-33.2,1%,1/16W,CHIA',
 WATTAGE='1/16W',
 TOLERANCE='1%',
 MATERIAL='CHIP',
 VALUE='33.2',
 PRIM_FILE='./archive_libs/logical/q_res/chips/chips.prt';

PART_NAME
 R4510 'Q_RES_0402LF-33.2,1%,1/16W,CHIA':;

SECTION_NUMBER 1
 '@S9S_MB_2U_LIB.S9S_MB_2U(SCH_1):PAGE228_I285@PURE_QUANTA.Q_RES(CHIPS)':
 C_PATH='@s9s_mb_2u_lib.s9s_mb_2u(sch_1):page228_i285@pure_quanta.q_res(chips)',
 P_PATH='@s9s_mb_2u_lib.s9s_mb_2u(sch_1):page241_i285@pure_quanta.q_res(chips)',
 PATH='I285',
 DRAWING='@S9S_MB_2U_LIB.S9S_MB_2U(SCH_1):PAGE228',
 PHYS_PAGE='241',
 XY='(-350,6725)',
 ROT='0',
 VER='1',
 PACK_TYPE='0402LF',
 CDS_LIB='pure_quanta',
 CDS_PART_NAME='Q_RES_0402LF-33.2,1%,1/16W,CHIA',
 WATTAGE='1/16W',
 TOLERANCE='1%',
 MATERIAL='CHIP',
 VALUE='33.2',
 PRIM_FILE='./archive_libs/logical/q_res/chips/chips.prt';

PART_NAME
 R4511 'Q_RES_0402LF-0,5%,1/16W,CHIP,CA':;

SECTION_NUMBER 1
 '@S9S_MB_2U_LIB.S9S_MB_2U(SCH_1):PAGE228_I284@PURE_QUANTA.Q_RES(CHIPS)':
 C_PATH='@s9s_mb_2u_lib.s9s_mb_2u(sch_1):page228_i284@pure_quanta.q_res(chips)',
 P_PATH='@s9s_mb_2u_lib.s9s_mb_2u(sch_1):page241_i284@pure_quanta.q_res(chips)',
 PATH='I284',
 DRAWING='@S9S_MB_2U_LIB.S9S_MB_2U(SCH_1):PAGE228',
 PHYS_PAGE='241',
 XY='(-350,6675)',
 ROT='0',
 VER='1',
 PACK_TYPE='0402LF',
 CDS_LIB='pure_quanta',
 CDS_PART_NAME='Q_RES_0402LF-0,5%,1/16W,CHIP,CA',
 WATTAGE='1/16W',
 TOLERANCE='5%',
 MATERIAL='CHIP',
 VALUE='0',
 PRIM_FILE='./archive_libs/logical/q_res/chips/chips.prt';

PART_NAME
 R4512 'Q_RES_0402LF-33.2,1%,1/16W,CHIA':;

SECTION_NUMBER 1
 '@S9S_MB_2U_LIB.S9S_MB_2U(SCH_1):PAGE228_I305@PURE_QUANTA.Q_RES(CHIPS)':
 C_PATH='@s9s_mb_2u_lib.s9s_mb_2u(sch_1):page228_i305@pure_quanta.q_res(chips)',
 P_PATH='@s9s_mb_2u_lib.s9s_mb_2u(sch_1):page241_i305@pure_quanta.q_res(chips)',
 PATH='I305',
 DRAWING='@S9S_MB_2U_LIB.S9S_MB_2U(SCH_1):PAGE228',
 PHYS_PAGE='241',
 XY='(-1225,6050)',
 ROT='0',
 VER='1',
 PACK_TYPE='0402LF',
 CDS_LIB='pure_quanta',
 CDS_PART_NAME='Q_RES_0402LF-33.2,1%,1/16W,CHIA',
 WATTAGE='1/16W',
 TOLERANCE='1%',
 MATERIAL='CHIP',
 VALUE='33.2',
 PRIM_FILE='./archive_libs/logical/q_res/chips/chips.prt';

PART_NAME
 R4513 'Q_RES_0402LF-0,5%,1/16W,CHIP,CA':;

SECTION_NUMBER 1
 '@S9S_MB_2U_LIB.S9S_MB_2U(SCH_1):PAGE228_I306@PURE_QUANTA.Q_RES(CHIPS)':
 C_PATH='@s9s_mb_2u_lib.s9s_mb_2u(sch_1):page228_i306@pure_quanta.q_res(chips)',
 P_PATH='@s9s_mb_2u_lib.s9s_mb_2u(sch_1):page241_i306@pure_quanta.q_res(chips)',
 PATH='I306',
 DRAWING='@S9S_MB_2U_LIB.S9S_MB_2U(SCH_1):PAGE228',
 PHYS_PAGE='241',
 XY='(-1225,6000)',
 ROT='0',
 VER='1',
 PACK_TYPE='0402LF',
 CDS_LIB='pure_quanta',
 CDS_PART_NAME='Q_RES_0402LF-0,5%,1/16W,CHIP,CA',
 WATTAGE='1/16W',
 TOLERANCE='5%',
 MATERIAL='CHIP',
 VALUE='0',
 PRIM_FILE='./archive_libs/logical/q_res/chips/chips.prt';

PART_NAME
 R4514 'Q_RES_0402LF-4.7K,1%,1/16W,EMPA':;

SECTION_NUMBER 1
 '@S9S_MB_2U_LIB.S9S_MB_2U(SCH_1):PAGE201_I161@PURE_QUANTA.Q_RES(CHIPS)':
 C_PATH='@s9s_mb_2u_lib.s9s_mb_2u(sch_1):page201_i161@pure_quanta.q_res(chips)',
 P_PATH='@s9s_mb_2u_lib.s9s_mb_2u(sch_1):page212_i161@pure_quanta.q_res(chips)',
 PATH='I161',
 DRAWING='@S9S_MB_2U_LIB.S9S_MB_2U(SCH_1):PAGE201',
 PHYS_PAGE='212',
 XY='(-3400,975)',
 ROT='0',
 VER='2',
 PACK_TYPE='0402LF',
 CDS_LIB='pure_quanta',
 CDS_PART_NAME='Q_RES_0402LF-4.7K,1%,1/16W,EMPA',
 WATTAGE='1/16W',
 TOLERANCE='1%',
 MATERIAL='EMPTY',
 VALUE='4.7K',
 PRIM_FILE='./archive_libs/logical/q_res/chips/chips.prt';

PART_NAME
 R4515 'Q_RES_0402LF-100K,1%,1/16W,CHIA':;

SECTION_NUMBER 1
 '@S9S_MB_2U_LIB.S9S_MB_2U(SCH_1):PAGE140_I200@PURE_QUANTA.Q_RES(CHIPS)':
 C_PATH='@s9s_mb_2u_lib.s9s_mb_2u(sch_1):page140_i200@pure_quanta.q_res(chips)',
 P_PATH='@s9s_mb_2u_lib.s9s_mb_2u(sch_1):page151_i200@pure_quanta.q_res(chips)',
 PATH='I200',
 DRAWING='@S9S_MB_2U_LIB.S9S_MB_2U(SCH_1):PAGE140',
 PHYS_PAGE='151',
 XY='(-1900,-1525)',
 ROT='0',
 VER='2',
 PACK_TYPE='0402LF',
 LOCATION='R4515',
 CDS_LIB='pure_quanta',
 CDS_PART_NAME='Q_RES_0402LF-100K,1%,1/16W,CHIA',
 WATTAGE='1/16W',
 TOLERANCE='1%',
 MATERIAL='CHIP',
 VALUE='100K',
 PRIM_FILE='./archive_libs/logical/q_res/chips/chips.prt';

PART_NAME
 R4516 'Q_RES_0402LF-10K,1%,1/16W,CHIPA':;

SECTION_NUMBER 1
 '@S9S_MB_2U_LIB.S9S_MB_2U(SCH_1):PAGE195_I539@PURE_QUANTA.Q_RES(CHIPS)':
 C_PATH='@s9s_mb_2u_lib.s9s_mb_2u(sch_1):page195_i539@pure_quanta.q_res(chips)',
 P_PATH='@s9s_mb_2u_lib.s9s_mb_2u(sch_1):page206_i539@pure_quanta.q_res(chips)',
 PATH='I539',
 DRAWING='@S9S_MB_2U_LIB.S9S_MB_2U(SCH_1):PAGE195',
 PHYS_PAGE='206',
 XY='(-7450,2425)',
 ROT='0',
 VER='2',
 PACK_TYPE='0402LF',
 CDS_LIB='pure_quanta',
 CDS_PART_NAME='Q_RES_0402LF-10K,1%,1/16W,CHIPA',
 WATTAGE='1/16W',
 TOLERANCE='1%',
 MATERIAL='CHIP',
 VALUE='10K',
 PRIM_FILE='./archive_libs/logical/q_res/chips/chips.prt';

PART_NAME
 R4517 'Q_RES_0402LF-10K,1%,1/16W,CHIPA':;

SECTION_NUMBER 1
 '@S9S_MB_2U_LIB.S9S_MB_2U(SCH_1):PAGE195_I540@PURE_QUANTA.Q_RES(CHIPS)':
 C_PATH='@s9s_mb_2u_lib.s9s_mb_2u(sch_1):page195_i540@pure_quanta.q_res(chips)',
 P_PATH='@s9s_mb_2u_lib.s9s_mb_2u(sch_1):page206_i540@pure_quanta.q_res(chips)',
 PATH='I540',
 DRAWING='@S9S_MB_2U_LIB.S9S_MB_2U(SCH_1):PAGE195',
 PHYS_PAGE='206',
 XY='(-7125,2425)',
 ROT='0',
 VER='2',
 PACK_TYPE='0402LF',
 CDS_LIB='pure_quanta',
 CDS_PART_NAME='Q_RES_0402LF-10K,1%,1/16W,CHIPA',
 WATTAGE='1/16W',
 TOLERANCE='1%',
 MATERIAL='CHIP',
 VALUE='10K',
 PRIM_FILE='./archive_libs/logical/q_res/chips/chips.prt';

PART_NAME
 R4518 'Q_RES_0402LF-10K,1%,1/16W,CHIPA':;

SECTION_NUMBER 1
 '@S9S_MB_2U_LIB.S9S_MB_2U(SCH_1):PAGE200_I77@PURE_QUANTA.Q_RES(CHIPS)':
 C_PATH='@s9s_mb_2u_lib.s9s_mb_2u(sch_1):page200_i77@pure_quanta.q_res(chips)',
 P_PATH='@s9s_mb_2u_lib.s9s_mb_2u(sch_1):page211_i77@pure_quanta.q_res(chips)',
 PATH='I77',
 DRAWING='@S9S_MB_2U_LIB.S9S_MB_2U(SCH_1):PAGE200',
 PHYS_PAGE='211',
 XY='(11400,6125)',
 ROT='0',
 VER='2',
 PACK_TYPE='0402LF',
 CDS_LIB='pure_quanta',
 CDS_PART_NAME='Q_RES_0402LF-10K,1%,1/16W,CHIPA',
 WATTAGE='1/16W',
 TOLERANCE='1%',
 MATERIAL='CHIP',
 VALUE='10K',
 PRIM_FILE='./archive_libs/logical/q_res/chips/chips.prt';

PART_NAME
 R4519 'Q_RES_0402LF-10K,1%,1/16W,CHIPA':;

SECTION_NUMBER 1
 '@S9S_MB_2U_LIB.S9S_MB_2U(SCH_1):PAGE200_I78@PURE_QUANTA.Q_RES(CHIPS)':
 C_PATH='@s9s_mb_2u_lib.s9s_mb_2u(sch_1):page200_i78@pure_quanta.q_res(chips)',
 P_PATH='@s9s_mb_2u_lib.s9s_mb_2u(sch_1):page211_i78@pure_quanta.q_res(chips)',
 PATH='I78',
 DRAWING='@S9S_MB_2U_LIB.S9S_MB_2U(SCH_1):PAGE200',
 PHYS_PAGE='211',
 XY='(11625,6125)',
 ROT='0',
 VER='2',
 PACK_TYPE='0402LF',
 CDS_LIB='pure_quanta',
 CDS_PART_NAME='Q_RES_0402LF-10K,1%,1/16W,CHIPA',
 WATTAGE='1/16W',
 TOLERANCE='1%',
 MATERIAL='CHIP',
 VALUE='10K',
 PRIM_FILE='./archive_libs/logical/q_res/chips/chips.prt';

PART_NAME
 R4520 'Q_RES_0402LF-10K,1%,1/16W,CHIPA':;

SECTION_NUMBER 1
 '@S9S_MB_2U_LIB.S9S_MB_2U(SCH_1):PAGE200_I79@PURE_QUANTA.Q_RES(CHIPS)':
 C_PATH='@s9s_mb_2u_lib.s9s_mb_2u(sch_1):page200_i79@pure_quanta.q_res(chips)',
 P_PATH='@s9s_mb_2u_lib.s9s_mb_2u(sch_1):page211_i79@pure_quanta.q_res(chips)',
 PATH='I79',
 DRAWING='@S9S_MB_2U_LIB.S9S_MB_2U(SCH_1):PAGE200',
 PHYS_PAGE='211',
 XY='(11825,6125)',
 ROT='0',
 VER='2',
 PACK_TYPE='0402LF',
 CDS_LIB='pure_quanta',
 CDS_PART_NAME='Q_RES_0402LF-10K,1%,1/16W,CHIPA',
 WATTAGE='1/16W',
 TOLERANCE='1%',
 MATERIAL='CHIP',
 VALUE='10K',
 PRIM_FILE='./archive_libs/logical/q_res/chips/chips.prt';

PART_NAME
 R4521 'Q_RES_0402LF-10K,1%,1/16W,CHIPA':;

SECTION_NUMBER 1
 '@S9S_MB_2U_LIB.S9S_MB_2U(SCH_1):PAGE201_I163@PURE_QUANTA.Q_RES(CHIPS)':
 C_PATH='@s9s_mb_2u_lib.s9s_mb_2u(sch_1):page201_i163@pure_quanta.q_res(chips)',
 P_PATH='@s9s_mb_2u_lib.s9s_mb_2u(sch_1):page212_i163@pure_quanta.q_res(chips)',
 PATH='I163',
 DRAWING='@S9S_MB_2U_LIB.S9S_MB_2U(SCH_1):PAGE201',
 PHYS_PAGE='212',
 XY='(-5075,3725)',
 ROT='0',
 VER='2',
 PACK_TYPE='0402LF',
 CDS_LIB='pure_quanta',
 CDS_PART_NAME='Q_RES_0402LF-10K,1%,1/16W,CHIPA',
 WATTAGE='1/16W',
 TOLERANCE='1%',
 MATERIAL='CHIP',
 VALUE='10K',
 PRIM_FILE='./archive_libs/logical/q_res/chips/chips.prt';

PART_NAME
 R4530 'Q_RES_0402LF-33.2,1%,1/16W,CHIA':;

SECTION_NUMBER 1
 '@S9S_MB_2U_LIB.S9S_MB_2U(SCH_1):PAGE228_I293@PURE_QUANTA.Q_RES(CHIPS)':
 C_PATH='@s9s_mb_2u_lib.s9s_mb_2u(sch_1):page228_i293@pure_quanta.q_res(chips)',
 P_PATH='@s9s_mb_2u_lib.s9s_mb_2u(sch_1):page241_i293@pure_quanta.q_res(chips)',
 PATH='I293',
 DRAWING='@S9S_MB_2U_LIB.S9S_MB_2U(SCH_1):PAGE228',
 PHYS_PAGE='241',
 XY='(-300,3525)',
 ROT='0',
 VER='1',
 PACK_TYPE='0402LF',
 LOCATION='R4530',
 CDS_LIB='pure_quanta',
 CDS_PART_NAME='Q_RES_0402LF-33.2,1%,1/16W,CHIA',
 WATTAGE='1/16W',
 TOLERANCE='1%',
 MATERIAL='CHIP',
 VALUE='33.2',
 PRIM_FILE='./archive_libs/logical/q_res/chips/chips.prt';

PART_NAME
 R4531 'Q_RES_0402LF-0,5%,1/16W,CHIP,CA':;

SECTION_NUMBER 1
 '@S9S_MB_2U_LIB.S9S_MB_2U(SCH_1):PAGE228_I296@PURE_QUANTA.Q_RES(CHIPS)':
 C_PATH='@s9s_mb_2u_lib.s9s_mb_2u(sch_1):page228_i296@pure_quanta.q_res(chips)',
 P_PATH='@s9s_mb_2u_lib.s9s_mb_2u(sch_1):page241_i296@pure_quanta.q_res(chips)',
 PATH='I296',
 DRAWING='@S9S_MB_2U_LIB.S9S_MB_2U(SCH_1):PAGE228',
 PHYS_PAGE='241',
 XY='(-300,3475)',
 ROT='0',
 VER='1',
 PACK_TYPE='0402LF',
 LOCATION='R4531',
 CDS_LIB='pure_quanta',
 CDS_PART_NAME='Q_RES_0402LF-0,5%,1/16W,CHIP,CA',
 WATTAGE='1/16W',
 TOLERANCE='5%',
 MATERIAL='CHIP',
 VALUE='0',
 PRIM_FILE='./archive_libs/logical/q_res/chips/chips.prt';

PART_NAME
 R4532 'Q_RES_0402LF-10K,1%,1/16W,CHIPA':
 ROOM='NIC1_P12V_MPS_MAM_BOM3';

SECTION_NUMBER 1
 '@S9S_MB_2U_LIB.S9S_MB_2U(SCH_1):PAGE236_I76@PURE_QUANTA.Q_RES(CHIPS)':
 C_PATH='@s9s_mb_2u_lib.s9s_mb_2u(sch_1):page236_i76@pure_quanta.q_res(chips)',
 P_PATH='@s9s_mb_2u_lib.s9s_mb_2u(sch_1):page157_i76@pure_quanta.q_res(chips)',
 PATH='I76',
 DRAWING='@S9S_MB_2U_LIB.S9S_MB_2U(SCH_1):PAGE236',
 ROOM1='NIC1_P12V_MPS_TIC_BOM4',
 PHYS_PAGE='157',
 XY='(-5950,10225)',
 ROT='0',
 VER='2',
 PACK_TYPE='0402LF',
 CDS_LIB='pure_quanta',
 CDS_PART_NAME='Q_RES_0402LF-10K,1%,1/16W,CHIPA',
 WATTAGE='1/16W',
 TOLERANCE='1%',
 MATERIAL='CHIP',
 ROOM='NIC1_P12V_MPS_MAM_BOM3',
 VALUE='10K',
 PRIM_FILE='./archive_libs/logical/q_res/chips/chips.prt';

PART_NAME
 R4533 'Q_RES_0402LF-2K,1%,1/16W,EMPTYA':;

SECTION_NUMBER 1
 '@S9S_MB_2U_LIB.S9S_MB_2U(SCH_1):PAGE208_I19@PURE_QUANTA.Q_RES(CHIPS)':
 C_PATH='@s9s_mb_2u_lib.s9s_mb_2u(sch_1):page208_i19@pure_quanta.q_res(chips)',
 P_PATH='@s9s_mb_2u_lib.s9s_mb_2u(sch_1):page219_i19@pure_quanta.q_res(chips)',
 PATH='I19',
 DRAWING='@S9S_MB_2U_LIB.S9S_MB_2U(SCH_1):PAGE208',
 PHYS_PAGE='219',
 XY='(-300,1625)',
 ROT='0',
 VER='1',
 PACK_TYPE='0402LF',
 CDS_LIB='pure_quanta',
 CDS_PART_NAME='Q_RES_0402LF-2K,1%,1/16W,EMPTYA',
 WATTAGE='1/16W',
 TOLERANCE='1%',
 MATERIAL='EMPTY',
 VALUE='2K',
 PRIM_FILE='./archive_libs/logical/q_res/chips/chips.prt';

PART_NAME
 R4534 'Q_RES_0402LF-0,5%,1/16W,CHIP,CA':;

SECTION_NUMBER 1
 '@S9S_MB_2U_LIB.S9S_MB_2U(SCH_1):PAGE195_I487@PURE_QUANTA.Q_RES(CHIPS)':
 C_PATH='@s9s_mb_2u_lib.s9s_mb_2u(sch_1):page195_i487@pure_quanta.q_res(chips)',
 P_PATH='@s9s_mb_2u_lib.s9s_mb_2u(sch_1):page206_i487@pure_quanta.q_res(chips)',
 PATH='I487',
 DRAWING='@S9S_MB_2U_LIB.S9S_MB_2U(SCH_1):PAGE195',
 PHYS_PAGE='206',
 XY='(-5300,2100)',
 ROT='0',
 VER='1',
 PACK_TYPE='0402LF',
 CDS_LIB='pure_quanta',
 CDS_PART_NAME='Q_RES_0402LF-0,5%,1/16W,CHIP,CA',
 WATTAGE='1/16W',
 TOLERANCE='5%',
 MATERIAL='CHIP',
 VALUE='0',
 PRIM_FILE='./archive_libs/logical/q_res/chips/chips.prt';

PART_NAME
 R4535 'Q_RES_0402LF-10,1%,1/16W,CHIP,A':;

SECTION_NUMBER 1
 '@S9S_MB_2U_LIB.S9S_MB_2U(SCH_1):PAGE227_I91@PURE_QUANTA.Q_RES(CHIPS)':
 C_PATH='@s9s_mb_2u_lib.s9s_mb_2u(sch_1):page227_i91@pure_quanta.q_res(chips)',
 P_PATH='@s9s_mb_2u_lib.s9s_mb_2u(sch_1):page240_i91@pure_quanta.q_res(chips)',
 PATH='I91',
 DRAWING='@S9S_MB_2U_LIB.S9S_MB_2U(SCH_1):PAGE227',
 PHYS_PAGE='240',
 XY='(-13275,725)',
 ROT='0',
 VER='1',
 PACK_TYPE='0402LF',
 CDS_LIB='pure_quanta',
 CDS_PART_NAME='Q_RES_0402LF-10,1%,1/16W,CHIP,A',
 WATTAGE='1/16W',
 TOLERANCE='1%',
 MATERIAL='CHIP',
 VALUE='10',
 PRIM_FILE='./archive_libs/logical/q_res/chips/chips.prt';

PART_NAME
 R4536 'Q_RES_0402LF-10,1%,1/16W,CHIP,A':;

SECTION_NUMBER 1
 '@S9S_MB_2U_LIB.S9S_MB_2U(SCH_1):PAGE227_I92@PURE_QUANTA.Q_RES(CHIPS)':
 C_PATH='@s9s_mb_2u_lib.s9s_mb_2u(sch_1):page227_i92@pure_quanta.q_res(chips)',
 P_PATH='@s9s_mb_2u_lib.s9s_mb_2u(sch_1):page240_i92@pure_quanta.q_res(chips)',
 PATH='I92',
 DRAWING='@S9S_MB_2U_LIB.S9S_MB_2U(SCH_1):PAGE227',
 PHYS_PAGE='240',
 XY='(-13275,675)',
 ROT='0',
 VER='1',
 PACK_TYPE='0402LF',
 CDS_LIB='pure_quanta',
 CDS_PART_NAME='Q_RES_0402LF-10,1%,1/16W,CHIP,A',
 WATTAGE='1/16W',
 TOLERANCE='1%',
 MATERIAL='CHIP',
 VALUE='10',
 PRIM_FILE='./archive_libs/logical/q_res/chips/chips.prt';

PART_NAME
 R4537 'Q_RES_0402LF-0,5%,1/16W,CHIP,CA':
 ROOM='PCIE REDRIVER1_BOM1';

SECTION_NUMBER 1
 '@S9S_MB_2U_LIB.S9S_MB_2U(SCH_1):PAGE136_I73@PURE_QUANTA.Q_RES(CHIPS)':
 C_PATH='@s9s_mb_2u_lib.s9s_mb_2u(sch_1):page136_i73@pure_quanta.q_res(chips)',
 P_PATH='@s9s_mb_2u_lib.s9s_mb_2u(sch_1):page166_i73@pure_quanta.q_res(chips)',
 PATH='I73',
 DRAWING='@S9S_MB_2U_LIB.S9S_MB_2U(SCH_1):PAGE136',
 PHYS_PAGE='166',
 XY='(-250,1500)',
 ROT='0',
 VER='1',
 PACK_TYPE='0402LF',
 CDS_LIB='pure_quanta',
 CDS_PART_NAME='Q_RES_0402LF-0,5%,1/16W,CHIP,CA',
 WATTAGE='1/16W',
 TOLERANCE='5%',
 MATERIAL='CHIP',
 ROOM='PCIE REDRIVER1_BOM1',
 VALUE='0',
 PRIM_FILE='./archive_libs/logical/q_res/chips/chips.prt';

PART_NAME
 R4540 'Q_RES_0402LF-33.2,1%,1/16W,CHIA':;

SECTION_NUMBER 1
 '@S9S_MB_2U_LIB.S9S_MB_2U(SCH_1):PAGE225_I33@PURE_QUANTA.Q_RES(CHIPS)':
 C_PATH='@s9s_mb_2u_lib.s9s_mb_2u(sch_1):page225_i33@pure_quanta.q_res(chips)',
 P_PATH='@s9s_mb_2u_lib.s9s_mb_2u(sch_1):page237_i33@pure_quanta.q_res(chips)',
 PATH='I33',
 DRAWING='@S9S_MB_2U_LIB.S9S_MB_2U(SCH_1):PAGE225',
 PHYS_PAGE='237',
 XY='(2200,675)',
 ROT='0',
 VER='1',
 PACK_TYPE='0402LF',
 CDS_LIB='pure_quanta',
 CDS_PART_NAME='Q_RES_0402LF-33.2,1%,1/16W,CHIA',
 WATTAGE='1/16W',
 TOLERANCE='1%',
 MATERIAL='CHIP',
 VALUE='33.2',
 PRIM_FILE='./archive_libs/logical/q_res/chips/chips.prt';

PART_NAME
 R4541 'Q_RES_0402LF-33.2,1%,1/16W,CHIA':;

SECTION_NUMBER 1
 '@S9S_MB_2U_LIB.S9S_MB_2U(SCH_1):PAGE225_I34@PURE_QUANTA.Q_RES(CHIPS)':
 C_PATH='@s9s_mb_2u_lib.s9s_mb_2u(sch_1):page225_i34@pure_quanta.q_res(chips)',
 P_PATH='@s9s_mb_2u_lib.s9s_mb_2u(sch_1):page237_i34@pure_quanta.q_res(chips)',
 PATH='I34',
 DRAWING='@S9S_MB_2U_LIB.S9S_MB_2U(SCH_1):PAGE225',
 PHYS_PAGE='237',
 XY='(2200,575)',
 ROT='0',
 VER='1',
 PACK_TYPE='0402LF',
 CDS_LIB='pure_quanta',
 CDS_PART_NAME='Q_RES_0402LF-33.2,1%,1/16W,CHIA',
 WATTAGE='1/16W',
 TOLERANCE='1%',
 MATERIAL='CHIP',
 VALUE='33.2',
 PRIM_FILE='./archive_libs/logical/q_res/chips/chips.prt';

PART_NAME
 R4543 'Q_RES_0402LF-4.7K,5%,1/16W,CHIA':;

SECTION_NUMBER 1
 '@S9S_MB_2U_LIB.S9S_MB_2U(SCH_1):PAGE139_I85@PURE_QUANTA.Q_RES(CHIPS)':
 C_PATH='@s9s_mb_2u_lib.s9s_mb_2u(sch_1):page139_i85@pure_quanta.q_res(chips)',
 P_PATH='@s9s_mb_2u_lib.s9s_mb_2u(sch_1):page145_i85@pure_quanta.q_res(chips)',
 PATH='I85',
 DRAWING='@S9S_MB_2U_LIB.S9S_MB_2U(SCH_1):PAGE139',
 PHYS_PAGE='145',
 XY='(-2000,750)',
 ROT='0',
 VER='2',
 PACK_TYPE='0402LF',
 LOCATION='R4543',
 CDS_LIB='pure_quanta',
 CDS_PART_NAME='Q_RES_0402LF-4.7K,5%,1/16W,CHIA',
 WATTAGE='1/16W',
 TOLERANCE='5%',
 MATERIAL='CHIP',
 VALUE='4.7K',
 PRIM_FILE='./archive_libs/logical/q_res/chips/chips.prt';

PART_NAME
 R4544 'Q_RES_0402LF-100K,1%,1/16W,EMPA':;

SECTION_NUMBER 1
 '@S9S_MB_2U_LIB.S9S_MB_2U(SCH_1):PAGE139_I62@PURE_QUANTA.Q_RES(CHIPS)':
 C_PATH='@s9s_mb_2u_lib.s9s_mb_2u(sch_1):page139_i62@pure_quanta.q_res(chips)',
 P_PATH='@s9s_mb_2u_lib.s9s_mb_2u(sch_1):page145_i62@pure_quanta.q_res(chips)',
 PATH='I62',
 DRAWING='@S9S_MB_2U_LIB.S9S_MB_2U(SCH_1):PAGE139',
 PHYS_PAGE='145',
 XY='(-1975,275)',
 ROT='0',
 VER='2',
 PACK_TYPE='0402LF',
 CDS_LIB='pure_quanta',
 CDS_PART_NAME='Q_RES_0402LF-100K,1%,1/16W,EMPA',
 WATTAGE='1/16W',
 TOLERANCE='1%',
 MATERIAL='EMPTY',
 VALUE='100K',
 PRIM_FILE='./archive_libs/logical/q_res/chips/chips.prt';

PART_NAME
 R4545 'Q_RES_0402LF-4.7K,5%,1/16W,CHIA':;

SECTION_NUMBER 1
 '@S9S_MB_2U_LIB.S9S_MB_2U(SCH_1):PAGE139_I57@PURE_QUANTA.Q_RES(CHIPS)':
 C_PATH='@s9s_mb_2u_lib.s9s_mb_2u(sch_1):page139_i57@pure_quanta.q_res(chips)',
 P_PATH='@s9s_mb_2u_lib.s9s_mb_2u(sch_1):page145_i57@pure_quanta.q_res(chips)',
 PATH='I57',
 DRAWING='@S9S_MB_2U_LIB.S9S_MB_2U(SCH_1):PAGE139',
 PHYS_PAGE='145',
 XY='(-825,1125)',
 ROT='0',
 VER='2',
 PACK_TYPE='0402LF',
 CDS_LIB='pure_quanta',
 CDS_PART_NAME='Q_RES_0402LF-4.7K,5%,1/16W,CHIA',
 WATTAGE='1/16W',
 TOLERANCE='5%',
 MATERIAL='CHIP',
 VALUE='4.7K',
 PRIM_FILE='./archive_libs/logical/q_res/chips/chips.prt';

PART_NAME
 R4546 'Q_RES_0402LF-4.7K,5%,1/16W,EMPA':;

SECTION_NUMBER 1
 '@S9S_MB_2U_LIB.S9S_MB_2U(SCH_1):PAGE139_I50@PURE_QUANTA.Q_RES(CHIPS)':
 C_PATH='@s9s_mb_2u_lib.s9s_mb_2u(sch_1):page139_i50@pure_quanta.q_res(chips)',
 P_PATH='@s9s_mb_2u_lib.s9s_mb_2u(sch_1):page145_i50@pure_quanta.q_res(chips)',
 PATH='I50',
 DRAWING='@S9S_MB_2U_LIB.S9S_MB_2U(SCH_1):PAGE139',
 PHYS_PAGE='145',
 XY='(325,1250)',
 ROT='0',
 VER='2',
 PACK_TYPE='0402LF',
 CDS_LIB='pure_quanta',
 CDS_PART_NAME='Q_RES_0402LF-4.7K,5%,1/16W,EMPA',
 WATTAGE='1/16W',
 TOLERANCE='5%',
 MATERIAL='EMPTY',
 VALUE='4.7K',
 PRIM_FILE='./archive_libs/logical/q_res/chips/chips.prt';

PART_NAME
 R4547 'Q_RES_0402LF-100K,1%,1/16W,EMPA':;

SECTION_NUMBER 1
 '@S9S_MB_2U_LIB.S9S_MB_2U(SCH_1):PAGE139_I89@PURE_QUANTA.Q_RES(CHIPS)':
 C_PATH='@s9s_mb_2u_lib.s9s_mb_2u(sch_1):page139_i89@pure_quanta.q_res(chips)',
 P_PATH='@s9s_mb_2u_lib.s9s_mb_2u(sch_1):page145_i89@pure_quanta.q_res(chips)',
 PATH='I89',
 DRAWING='@S9S_MB_2U_LIB.S9S_MB_2U(SCH_1):PAGE139',
 PHYS_PAGE='145',
 XY='(2375,5550)',
 ROT='0',
 VER='2',
 PACK_TYPE='0402LF',
 CDS_LIB='pure_quanta',
 CDS_PART_NAME='Q_RES_0402LF-100K,1%,1/16W,EMPA',
 WATTAGE='1/16W',
 TOLERANCE='1%',
 MATERIAL='EMPTY',
 VALUE='100K',
 PRIM_FILE='./archive_libs/logical/q_res/chips/chips.prt';

PART_NAME
 R4548 'Q_RES_0402LF-100K,1%,1/16W,CHIA':;

SECTION_NUMBER 1
 '@S9S_MB_2U_LIB.S9S_MB_2U(SCH_1):PAGE139_I87@PURE_QUANTA.Q_RES(CHIPS)':
 C_PATH='@s9s_mb_2u_lib.s9s_mb_2u(sch_1):page139_i87@pure_quanta.q_res(chips)',
 P_PATH='@s9s_mb_2u_lib.s9s_mb_2u(sch_1):page145_i87@pure_quanta.q_res(chips)',
 PATH='I87',
 DRAWING='@S9S_MB_2U_LIB.S9S_MB_2U(SCH_1):PAGE139',
 PHYS_PAGE='145',
 XY='(2400,5075)',
 ROT='0',
 VER='2',
 PACK_TYPE='0402LF',
 LOCATION='R4548',
 CDS_LIB='pure_quanta',
 CDS_PART_NAME='Q_RES_0402LF-100K,1%,1/16W,CHIA',
 WATTAGE='1/16W',
 TOLERANCE='1%',
 MATERIAL='CHIP',
 VALUE='100K',
 PRIM_FILE='./archive_libs/logical/q_res/chips/chips.prt';

PART_NAME
 R4549 'Q_RES_0402LF-4.7K,5%,1/16W,EMPA':;

SECTION_NUMBER 1
 '@S9S_MB_2U_LIB.S9S_MB_2U(SCH_1):PAGE139_I98@PURE_QUANTA.Q_RES(CHIPS)':
 C_PATH='@s9s_mb_2u_lib.s9s_mb_2u(sch_1):page139_i98@pure_quanta.q_res(chips)',
 P_PATH='@s9s_mb_2u_lib.s9s_mb_2u(sch_1):page145_i98@pure_quanta.q_res(chips)',
 PATH='I98',
 DRAWING='@S9S_MB_2U_LIB.S9S_MB_2U(SCH_1):PAGE139',
 PHYS_PAGE='145',
 XY='(5125,5525)',
 ROT='0',
 VER='2',
 PACK_TYPE='0402LF',
 CDS_LIB='pure_quanta',
 CDS_PART_NAME='Q_RES_0402LF-4.7K,5%,1/16W,EMPA',
 WATTAGE='1/16W',
 TOLERANCE='5%',
 MATERIAL='EMPTY',
 VALUE='4.7K',
 PRIM_FILE='./archive_libs/logical/q_res/chips/chips.prt';

PART_NAME
 R4550 'Q_RES_0402LF-49.9,1%,1/16W,CHIA':;

SECTION_NUMBER 1
 '@S9S_MB_2U_LIB.S9S_MB_2U(SCH_1):PAGE139_I110@PURE_QUANTA.Q_RES(CHIPS)':
 C_PATH='@s9s_mb_2u_lib.s9s_mb_2u(sch_1):page139_i110@pure_quanta.q_res(chips)',
 P_PATH='@s9s_mb_2u_lib.s9s_mb_2u(sch_1):page145_i110@pure_quanta.q_res(chips)',
 PATH='I110',
 DRAWING='@S9S_MB_2U_LIB.S9S_MB_2U(SCH_1):PAGE139',
 PHYS_PAGE='145',
 XY='(5375,5275)',
 ROT='0',
 VER='1',
 PACK_TYPE='0402LF',
 LOCATION='R4550',
 CDS_LIB='pure_quanta',
 CDS_PART_NAME='Q_RES_0402LF-49.9,1%,1/16W,CHIA',
 WATTAGE='1/16W',
 TOLERANCE='1%',
 MATERIAL='CHIP',
 VALUE='49.9',
 PRIM_FILE='./archive_libs/logical/q_res/chips/chips.prt';

PART_NAME
 R4551 'Q_RES_0402LF-54.9K,1%,1/16W,EMA':;

SECTION_NUMBER 1
 '@S9S_MB_2U_LIB.S9S_MB_2U(SCH_1):PAGE230_I51@PURE_QUANTA.Q_RES(CHIPS)':
 C_PATH='@s9s_mb_2u_lib.s9s_mb_2u(sch_1):page230_i51@pure_quanta.q_res(chips)',
 P_PATH='@s9s_mb_2u_lib.s9s_mb_2u(sch_1):page246_i51@pure_quanta.q_res(chips)',
 PATH='I51',
 DRAWING='@S9S_MB_2U_LIB.S9S_MB_2U(SCH_1):PAGE230',
 PHYS_PAGE='246',
 XY='(-1125,-1800)',
 ROT='0',
 VER='2',
 PACK_TYPE='0402LF',
 CDS_LIB='pure_quanta',
 CDS_PART_NAME='Q_RES_0402LF-54.9K,1%,1/16W,EMA',
 WATTAGE='1/16W',
 TOLERANCE='1%',
 MATERIAL='EMPTY',
 VALUE='54.9K',
 PRIM_FILE='./archive_libs/logical/q_res/chips/chips.prt';

PART_NAME
 R4552 'Q_RES_0402LF-100K,1%,1/16W,CHIA':;

SECTION_NUMBER 1
 '@S9S_MB_2U_LIB.S9S_MB_2U(SCH_1):PAGE230_I50@PURE_QUANTA.Q_RES(CHIPS)':
 C_PATH='@s9s_mb_2u_lib.s9s_mb_2u(sch_1):page230_i50@pure_quanta.q_res(chips)',
 P_PATH='@s9s_mb_2u_lib.s9s_mb_2u(sch_1):page246_i50@pure_quanta.q_res(chips)',
 PATH='I50',
 DRAWING='@S9S_MB_2U_LIB.S9S_MB_2U(SCH_1):PAGE230',
 PHYS_PAGE='246',
 XY='(-1100,-2275)',
 ROT='0',
 VER='2',
 PACK_TYPE='0402LF',
 CDS_LIB='pure_quanta',
 CDS_PART_NAME='Q_RES_0402LF-100K,1%,1/16W,CHIA',
 WATTAGE='1/16W',
 TOLERANCE='1%',
 MATERIAL='CHIP',
 VALUE='100K',
 PRIM_FILE='./archive_libs/logical/q_res/chips/chips.prt';

PART_NAME
 R4553 'Q_RES_0402LF-4.7K,5%,1/16W,CHIA':;

SECTION_NUMBER 1
 '@S9S_MB_2U_LIB.S9S_MB_2U(SCH_1):PAGE230_I55@PURE_QUANTA.Q_RES(CHIPS)':
 C_PATH='@s9s_mb_2u_lib.s9s_mb_2u(sch_1):page230_i55@pure_quanta.q_res(chips)',
 P_PATH='@s9s_mb_2u_lib.s9s_mb_2u(sch_1):page246_i55@pure_quanta.q_res(chips)',
 PATH='I55',
 DRAWING='@S9S_MB_2U_LIB.S9S_MB_2U(SCH_1):PAGE230',
 PHYS_PAGE='246',
 XY='(50,-1425)',
 ROT='0',
 VER='2',
 PACK_TYPE='0402LF',
 CDS_LIB='pure_quanta',
 CDS_PART_NAME='Q_RES_0402LF-4.7K,5%,1/16W,CHIA',
 WATTAGE='1/16W',
 TOLERANCE='5%',
 MATERIAL='CHIP',
 VALUE='4.7K',
 PRIM_FILE='./archive_libs/logical/q_res/chips/chips.prt';

PART_NAME
 R4554 'Q_RES_0402LF-4.7K,5%,1/16W,CHIA':;

SECTION_NUMBER 1
 '@S9S_MB_2U_LIB.S9S_MB_2U(SCH_1):PAGE230_I59@PURE_QUANTA.Q_RES(CHIPS)':
 C_PATH='@s9s_mb_2u_lib.s9s_mb_2u(sch_1):page230_i59@pure_quanta.q_res(chips)',
 P_PATH='@s9s_mb_2u_lib.s9s_mb_2u(sch_1):page246_i59@pure_quanta.q_res(chips)',
 PATH='I59',
 DRAWING='@S9S_MB_2U_LIB.S9S_MB_2U(SCH_1):PAGE230',
 PHYS_PAGE='246',
 XY='(1200,-1300)',
 ROT='0',
 VER='2',
 PACK_TYPE='0402LF',
 CDS_LIB='pure_quanta',
 CDS_PART_NAME='Q_RES_0402LF-4.7K,5%,1/16W,CHIA',
 WATTAGE='1/16W',
 TOLERANCE='5%',
 MATERIAL='CHIP',
 VALUE='4.7K',
 PRIM_FILE='./archive_libs/logical/q_res/chips/chips.prt';

PART_NAME
 R4555 'Q_RES_0402LF-4.7K,5%,1/16W,EMPA':;

SECTION_NUMBER 1
 '@S9S_MB_2U_LIB.S9S_MB_2U(SCH_1):PAGE139_I99@PURE_QUANTA.Q_RES(CHIPS)':
 C_PATH='@s9s_mb_2u_lib.s9s_mb_2u(sch_1):page139_i99@pure_quanta.q_res(chips)',
 P_PATH='@s9s_mb_2u_lib.s9s_mb_2u(sch_1):page145_i99@pure_quanta.q_res(chips)',
 PATH='I99',
 DRAWING='@S9S_MB_2U_LIB.S9S_MB_2U(SCH_1):PAGE139',
 PHYS_PAGE='145',
 XY='(5175,5000)',
 ROT='0',
 VER='2',
 PACK_TYPE='0402LF',
 LOCATION='R4555',
 CDS_LIB='pure_quanta',
 CDS_PART_NAME='Q_RES_0402LF-4.7K,5%,1/16W,EMPA',
 WATTAGE='1/16W',
 TOLERANCE='5%',
 MATERIAL='EMPTY',
 VALUE='4.7K',
 PRIM_FILE='./archive_libs/logical/q_res/chips/chips.prt';

PART_NAME
 R4556 'Q_RES_0402LF-33.2,1%,1/16W,CHIA':;

SECTION_NUMBER 1
 '@S9S_MB_2U_LIB.S9S_MB_2U(SCH_1):PAGE312_I143@PURE_QUANTA.Q_RES(CHIPS)':
 C_PATH='@s9s_mb_2u_lib.s9s_mb_2u(sch_1):page312_i143@pure_quanta.q_res(chips)',
 P_PATH='@s9s_mb_2u_lib.s9s_mb_2u(sch_1):page215_i143@pure_quanta.q_res(chips)',
 PATH='I143',
 DRAWING='@S9S_MB_2U_LIB.S9S_MB_2U(SCH_1):PAGE312',
 PHYS_PAGE='215',
 XY='(-575,525)',
 ROT='0',
 VER='1',
 PACK_TYPE='0402LF',
 CDS_LIB='pure_quanta',
 CDS_PART_NAME='Q_RES_0402LF-33.2,1%,1/16W,CHIA',
 WATTAGE='1/16W',
 TOLERANCE='1%',
 MATERIAL='CHIP',
 VALUE='33.2',
 PRIM_FILE='./archive_libs/logical/q_res/chips/chips.prt';

PART_NAME
 R4557 'Q_RES_0402LF-33.2,1%,1/16W,CHIA':;

SECTION_NUMBER 1
 '@S9S_MB_2U_LIB.S9S_MB_2U(SCH_1):PAGE312_I145@PURE_QUANTA.Q_RES(CHIPS)':
 C_PATH='@s9s_mb_2u_lib.s9s_mb_2u(sch_1):page312_i145@pure_quanta.q_res(chips)',
 P_PATH='@s9s_mb_2u_lib.s9s_mb_2u(sch_1):page215_i145@pure_quanta.q_res(chips)',
 PATH='I145',
 DRAWING='@S9S_MB_2U_LIB.S9S_MB_2U(SCH_1):PAGE312',
 PHYS_PAGE='215',
 XY='(-575,350)',
 ROT='0',
 VER='1',
 PACK_TYPE='0402LF',
 CDS_LIB='pure_quanta',
 CDS_PART_NAME='Q_RES_0402LF-33.2,1%,1/16W,CHIA',
 WATTAGE='1/16W',
 TOLERANCE='1%',
 MATERIAL='CHIP',
 VALUE='33.2',
 PRIM_FILE='./archive_libs/logical/q_res/chips/chips.prt';

PART_NAME
 R4558 'Q_RES_0402LF-33.2,1%,1/16W,CHIA':;

SECTION_NUMBER 1
 '@S9S_MB_2U_LIB.S9S_MB_2U(SCH_1):PAGE312_I150@PURE_QUANTA.Q_RES(CHIPS)':
 C_PATH='@s9s_mb_2u_lib.s9s_mb_2u(sch_1):page312_i150@pure_quanta.q_res(chips)',
 P_PATH='@s9s_mb_2u_lib.s9s_mb_2u(sch_1):page215_i150@pure_quanta.q_res(chips)',
 PATH='I150',
 DRAWING='@S9S_MB_2U_LIB.S9S_MB_2U(SCH_1):PAGE312',
 PHYS_PAGE='215',
 XY='(-575,175)',
 ROT='0',
 VER='1',
 PACK_TYPE='0402LF',
 CDS_LIB='pure_quanta',
 CDS_PART_NAME='Q_RES_0402LF-33.2,1%,1/16W,CHIA',
 WATTAGE='1/16W',
 TOLERANCE='1%',
 MATERIAL='CHIP',
 VALUE='33.2',
 PRIM_FILE='./archive_libs/logical/q_res/chips/chips.prt';

PART_NAME
 R4559 'Q_RES_0402LF-100K,1%,1/16W,CHIA':;

SECTION_NUMBER 1
 '@S9S_MB_2U_LIB.S9S_MB_2U(SCH_1):PAGE143_I129@PURE_QUANTA.Q_RES(CHIPS)':
 C_PATH='@s9s_mb_2u_lib.s9s_mb_2u(sch_1):page143_i129@pure_quanta.q_res(chips)',
 P_PATH='@s9s_mb_2u_lib.s9s_mb_2u(sch_1):page146_i129@pure_quanta.q_res(chips)',
 PATH='I129',
 DRAWING='@S9S_MB_2U_LIB.S9S_MB_2U(SCH_1):PAGE143',
 PHYS_PAGE='146',
 XY='(2350,-750)',
 ROT='0',
 VER='2',
 PACK_TYPE='0402LF',
 CDS_LIB='pure_quanta',
 CDS_PART_NAME='Q_RES_0402LF-100K,1%,1/16W,CHIA',
 WATTAGE='1/16W',
 TOLERANCE='1%',
 MATERIAL='CHIP',
 VALUE='100K',
 PRIM_FILE='./archive_libs/logical/q_res/chips/chips.prt';

PART_NAME
 R4560 'Q_RES_0402LF-4.7K,5%,1/16W,CHIA':;

SECTION_NUMBER 1
 '@S9S_MB_2U_LIB.S9S_MB_2U(SCH_1):PAGE143_I124@PURE_QUANTA.Q_RES(CHIPS)':
 C_PATH='@s9s_mb_2u_lib.s9s_mb_2u(sch_1):page143_i124@pure_quanta.q_res(chips)',
 P_PATH='@s9s_mb_2u_lib.s9s_mb_2u(sch_1):page146_i124@pure_quanta.q_res(chips)',
 PATH='I124',
 DRAWING='@S9S_MB_2U_LIB.S9S_MB_2U(SCH_1):PAGE143',
 PHYS_PAGE='146',
 XY='(3500,100)',
 ROT='0',
 VER='2',
 PACK_TYPE='0402LF',
 CDS_LIB='pure_quanta',
 CDS_PART_NAME='Q_RES_0402LF-4.7K,5%,1/16W,CHIA',
 WATTAGE='1/16W',
 TOLERANCE='5%',
 MATERIAL='CHIP',
 VALUE='4.7K',
 PRIM_FILE='./archive_libs/logical/q_res/chips/chips.prt';

PART_NAME
 R4561 'Q_RES_0402LF-4.7K,5%,1/16W,CHIA':;

SECTION_NUMBER 1
 '@S9S_MB_2U_LIB.S9S_MB_2U(SCH_1):PAGE143_I116@PURE_QUANTA.Q_RES(CHIPS)':
 C_PATH='@s9s_mb_2u_lib.s9s_mb_2u(sch_1):page143_i116@pure_quanta.q_res(chips)',
 P_PATH='@s9s_mb_2u_lib.s9s_mb_2u(sch_1):page146_i116@pure_quanta.q_res(chips)',
 PATH='I116',
 DRAWING='@S9S_MB_2U_LIB.S9S_MB_2U(SCH_1):PAGE143',
 PHYS_PAGE='146',
 XY='(4650,225)',
 ROT='0',
 VER='2',
 PACK_TYPE='0402LF',
 CDS_LIB='pure_quanta',
 CDS_PART_NAME='Q_RES_0402LF-4.7K,5%,1/16W,CHIA',
 WATTAGE='1/16W',
 TOLERANCE='5%',
 MATERIAL='CHIP',
 VALUE='4.7K',
 PRIM_FILE='./archive_libs/logical/q_res/chips/chips.prt';

PART_NAME
 R4562 'Q_RES_0402LF-100K,1%,1/16W,EMPA':;

SECTION_NUMBER 1
 '@S9S_MB_2U_LIB.S9S_MB_2U(SCH_1):PAGE143_I132@PURE_QUANTA.Q_RES(CHIPS)':
 C_PATH='@s9s_mb_2u_lib.s9s_mb_2u(sch_1):page143_i132@pure_quanta.q_res(chips)',
 P_PATH='@s9s_mb_2u_lib.s9s_mb_2u(sch_1):page146_i132@pure_quanta.q_res(chips)',
 PATH='I132',
 DRAWING='@S9S_MB_2U_LIB.S9S_MB_2U(SCH_1):PAGE143',
 PHYS_PAGE='146',
 XY='(2325,-275)',
 ROT='0',
 VER='2',
 PACK_TYPE='0402LF',
 CDS_LIB='pure_quanta',
 CDS_PART_NAME='Q_RES_0402LF-100K,1%,1/16W,EMPA',
 WATTAGE='1/16W',
 TOLERANCE='1%',
 MATERIAL='EMPTY',
 VALUE='100K',
 PRIM_FILE='./archive_libs/logical/q_res/chips/chips.prt';

PART_NAME
 R4563 'Q_RES_0402LF-33.2,1%,1/16W,CHIA':;

SECTION_NUMBER 1
 '@S9S_MB_2U_LIB.S9S_MB_2U(SCH_1):PAGE312_I158@PURE_QUANTA.Q_RES(CHIPS)':
 C_PATH='@s9s_mb_2u_lib.s9s_mb_2u(sch_1):page312_i158@pure_quanta.q_res(chips)',
 P_PATH='@s9s_mb_2u_lib.s9s_mb_2u(sch_1):page215_i158@pure_quanta.q_res(chips)',
 PATH='I158',
 DRAWING='@S9S_MB_2U_LIB.S9S_MB_2U(SCH_1):PAGE312',
 PHYS_PAGE='215',
 XY='(-600,-125)',
 ROT='0',
 VER='1',
 PACK_TYPE='0402LF',
 CDS_LIB='pure_quanta',
 CDS_PART_NAME='Q_RES_0402LF-33.2,1%,1/16W,CHIA',
 WATTAGE='1/16W',
 TOLERANCE='1%',
 MATERIAL='CHIP',
 VALUE='33.2',
 PRIM_FILE='./archive_libs/logical/q_res/chips/chips.prt';

PART_NAME
 R4564 'Q_RES_0402LF-10K,1%,1/16W,CHIPA':;

SECTION_NUMBER 1
 '@S9S_MB_2U_LIB.S9S_MB_2U(SCH_1):PAGE176_I239@PURE_QUANTA.Q_RES(CHIPS)':
 C_PATH='@s9s_mb_2u_lib.s9s_mb_2u(sch_1):page176_i239@pure_quanta.q_res(chips)',
 P_PATH='@s9s_mb_2u_lib.s9s_mb_2u(sch_1):page184_i239@pure_quanta.q_res(chips)',
 PATH='I239',
 DRAWING='@S9S_MB_2U_LIB.S9S_MB_2U(SCH_1):PAGE176',
 PHYS_PAGE='184',
 XY='(1925,-775)',
 ROT='0',
 VER='1',
 PACK_TYPE='0402LF',
 CDS_LIB='pure_quanta',
 CDS_PART_NAME='Q_RES_0402LF-10K,1%,1/16W,CHIPA',
 WATTAGE='1/16W',
 TOLERANCE='1%',
 MATERIAL='CHIP',
 VALUE='10K',
 PRIM_FILE='./archive_libs/logical/q_res/chips/chips.prt';

PART_NAME
 R4565 'Q_RES_0402LF-10K,1%,1/16W,CHIPA':;

SECTION_NUMBER 1
 '@S9S_MB_2U_LIB.S9S_MB_2U(SCH_1):PAGE176_I240@PURE_QUANTA.Q_RES(CHIPS)':
 C_PATH='@s9s_mb_2u_lib.s9s_mb_2u(sch_1):page176_i240@pure_quanta.q_res(chips)',
 P_PATH='@s9s_mb_2u_lib.s9s_mb_2u(sch_1):page184_i240@pure_quanta.q_res(chips)',
 PATH='I240',
 DRAWING='@S9S_MB_2U_LIB.S9S_MB_2U(SCH_1):PAGE176',
 PHYS_PAGE='184',
 XY='(1925,-875)',
 ROT='0',
 VER='1',
 PACK_TYPE='0402LF',
 CDS_LIB='pure_quanta',
 CDS_PART_NAME='Q_RES_0402LF-10K,1%,1/16W,CHIPA',
 WATTAGE='1/16W',
 TOLERANCE='1%',
 MATERIAL='CHIP',
 VALUE='10K',
 PRIM_FILE='./archive_libs/logical/q_res/chips/chips.prt';

PART_NAME
 R4567 'Q_RES_0402LF-5.11K,1%,1/16W,CHA':;

SECTION_NUMBER 1
 '@S9S_MB_2U_LIB.S9S_MB_2U(SCH_1):PAGE239_I348@PURE_QUANTA.Q_RES(CHIPS)':
 C_PATH='@s9s_mb_2u_lib.s9s_mb_2u(sch_1):page239_i348@pure_quanta.q_res(chips)',
 P_PATH='@s9s_mb_2u_lib.s9s_mb_2u(sch_1):page250_i348@pure_quanta.q_res(chips)',
 PATH='I348',
 DRAWING='@S9S_MB_2U_LIB.S9S_MB_2U(SCH_1):PAGE239',
 PHYS_PAGE='250',
 XY='(-475,525)',
 ROT='0',
 VER='2',
 PACK_TYPE='0402LF',
 CDS_LIB='pure_quanta',
 CDS_PART_NAME='Q_RES_0402LF-5.11K,1%,1/16W,CHA',
 WATTAGE='1/16W',
 TOLERANCE='1%',
 MATERIAL='CHIP',
 VALUE='5.11K',
 PRIM_FILE='./archive_libs/logical/q_res/chips/chips.prt';

PART_NAME
 R4568 'Q_RES_0402LF-4.7K,1%,1/16W,CHIA':;

SECTION_NUMBER 1
 '@S9S_MB_2U_LIB.S9S_MB_2U(SCH_1):PAGE239_I346@PURE_QUANTA.Q_RES(CHIPS)':
 C_PATH='@s9s_mb_2u_lib.s9s_mb_2u(sch_1):page239_i346@pure_quanta.q_res(chips)',
 P_PATH='@s9s_mb_2u_lib.s9s_mb_2u(sch_1):page250_i346@pure_quanta.q_res(chips)',
 PATH='I346',
 DRAWING='@S9S_MB_2U_LIB.S9S_MB_2U(SCH_1):PAGE239',
 PHYS_PAGE='250',
 XY='(-475,150)',
 ROT='0',
 VER='2',
 PACK_TYPE='0402LF',
 CDS_LIB='pure_quanta',
 CDS_PART_NAME='Q_RES_0402LF-4.7K,1%,1/16W,CHIA',
 WATTAGE='1/16W',
 TOLERANCE='1%',
 MATERIAL='CHIP',
 VALUE='4.7K',
 PRIM_FILE='./archive_libs/logical/q_res/chips/chips.prt';

PART_NAME
 R4569 'Q_RES_0402LF-0,5%,1/16W,EMPTY,A':;

SECTION_NUMBER 1
 '@S9S_MB_2U_LIB.S9S_MB_2U(SCH_1):PAGE139_I107@PURE_QUANTA.Q_RES(CHIPS)':
 C_PATH='@s9s_mb_2u_lib.s9s_mb_2u(sch_1):page139_i107@pure_quanta.q_res(chips)',
 P_PATH='@s9s_mb_2u_lib.s9s_mb_2u(sch_1):page145_i107@pure_quanta.q_res(chips)',
 PATH='I107',
 DRAWING='@S9S_MB_2U_LIB.S9S_MB_2U(SCH_1):PAGE139',
 PHYS_PAGE='145',
 XY='(-650,6050)',
 ROT='0',
 VER='1',
 PACK_TYPE='0402LF',
 CDS_LIB='pure_quanta',
 CDS_PART_NAME='Q_RES_0402LF-0,5%,1/16W,EMPTY,A',
 WATTAGE='1/16W',
 TOLERANCE='5%',
 MATERIAL='EMPTY',
 VALUE='0',
 PRIM_FILE='./archive_libs/logical/q_res/chips/chips.prt';

PART_NAME
 R4570 'Q_RES_0402LF-0,5%,1/16W,EMPTY,A':;

SECTION_NUMBER 1
 '@S9S_MB_2U_LIB.S9S_MB_2U(SCH_1):PAGE139_I109@PURE_QUANTA.Q_RES(CHIPS)':
 C_PATH='@s9s_mb_2u_lib.s9s_mb_2u(sch_1):page139_i109@pure_quanta.q_res(chips)',
 P_PATH='@s9s_mb_2u_lib.s9s_mb_2u(sch_1):page145_i109@pure_quanta.q_res(chips)',
 PATH='I109',
 DRAWING='@S9S_MB_2U_LIB.S9S_MB_2U(SCH_1):PAGE139',
 PHYS_PAGE='145',
 XY='(-425,4575)',
 ROT='0',
 VER='1',
 PACK_TYPE='0402LF',
 CDS_LIB='pure_quanta',
 CDS_PART_NAME='Q_RES_0402LF-0,5%,1/16W,EMPTY,A',
 WATTAGE='1/16W',
 TOLERANCE='5%',
 MATERIAL='EMPTY',
 VALUE='0',
 PRIM_FILE='./archive_libs/logical/q_res/chips/chips.prt';

PART_NAME
 R4571 'Q_RES_0402LF-0,5%,1/16W,EMPTY,A':;

SECTION_NUMBER 1
 '@S9S_MB_2U_LIB.S9S_MB_2U(SCH_1):PAGE139_I108@PURE_QUANTA.Q_RES(CHIPS)':
 C_PATH='@s9s_mb_2u_lib.s9s_mb_2u(sch_1):page139_i108@pure_quanta.q_res(chips)',
 P_PATH='@s9s_mb_2u_lib.s9s_mb_2u(sch_1):page145_i108@pure_quanta.q_res(chips)',
 PATH='I108',
 DRAWING='@S9S_MB_2U_LIB.S9S_MB_2U(SCH_1):PAGE139',
 PHYS_PAGE='145',
 XY='(-425,3125)',
 ROT='0',
 VER='1',
 PACK_TYPE='0402LF',
 CDS_LIB='pure_quanta',
 CDS_PART_NAME='Q_RES_0402LF-0,5%,1/16W,EMPTY,A',
 WATTAGE='1/16W',
 TOLERANCE='5%',
 MATERIAL='EMPTY',
 VALUE='0',
 PRIM_FILE='./archive_libs/logical/q_res/chips/chips.prt';

PART_NAME
 R4572 'Q_RES_0402LF-0,5%,1/16W,EMPTY,A':;

SECTION_NUMBER 1
 '@S9S_MB_2U_LIB.S9S_MB_2U(SCH_1):PAGE143_I141@PURE_QUANTA.Q_RES(CHIPS)':
 C_PATH='@s9s_mb_2u_lib.s9s_mb_2u(sch_1):page143_i141@pure_quanta.q_res(chips)',
 P_PATH='@s9s_mb_2u_lib.s9s_mb_2u(sch_1):page146_i141@pure_quanta.q_res(chips)',
 PATH='I141',
 DRAWING='@S9S_MB_2U_LIB.S9S_MB_2U(SCH_1):PAGE143',
 PHYS_PAGE='146',
 XY='(-850,3100)',
 ROT='0',
 VER='1',
 PACK_TYPE='0402LF',
 CDS_LIB='pure_quanta',
 CDS_PART_NAME='Q_RES_0402LF-0,5%,1/16W,EMPTY,A',
 WATTAGE='1/16W',
 TOLERANCE='5%',
 MATERIAL='EMPTY',
 VALUE='0',
 PRIM_FILE='./archive_libs/logical/q_res/chips/chips.prt';

PART_NAME
 R4573 'Q_RES_0402LF-0,5%,1/16W,EMPTY,A':;

SECTION_NUMBER 1
 '@S9S_MB_2U_LIB.S9S_MB_2U(SCH_1):PAGE143_I140@PURE_QUANTA.Q_RES(CHIPS)':
 C_PATH='@s9s_mb_2u_lib.s9s_mb_2u(sch_1):page143_i140@pure_quanta.q_res(chips)',
 P_PATH='@s9s_mb_2u_lib.s9s_mb_2u(sch_1):page146_i140@pure_quanta.q_res(chips)',
 PATH='I140',
 DRAWING='@S9S_MB_2U_LIB.S9S_MB_2U(SCH_1):PAGE143',
 PHYS_PAGE='146',
 XY='(-850,1650)',
 ROT='0',
 VER='1',
 PACK_TYPE='0402LF',
 CDS_LIB='pure_quanta',
 CDS_PART_NAME='Q_RES_0402LF-0,5%,1/16W,EMPTY,A',
 WATTAGE='1/16W',
 TOLERANCE='5%',
 MATERIAL='EMPTY',
 VALUE='0',
 PRIM_FILE='./archive_libs/logical/q_res/chips/chips.prt';

PART_NAME
 R4574 'Q_RES_0402LF-0,5%,1/16W,EMPTY,A':;

SECTION_NUMBER 1
 '@S9S_MB_2U_LIB.S9S_MB_2U(SCH_1):PAGE143_I136@PURE_QUANTA.Q_RES(CHIPS)':
 C_PATH='@s9s_mb_2u_lib.s9s_mb_2u(sch_1):page143_i136@pure_quanta.q_res(chips)',
 P_PATH='@s9s_mb_2u_lib.s9s_mb_2u(sch_1):page146_i136@pure_quanta.q_res(chips)',
 PATH='I136',
 DRAWING='@S9S_MB_2U_LIB.S9S_MB_2U(SCH_1):PAGE143',
 PHYS_PAGE='146',
 XY='(-775,175)',
 ROT='0',
 VER='1',
 PACK_TYPE='0402LF',
 CDS_LIB='pure_quanta',
 CDS_PART_NAME='Q_RES_0402LF-0,5%,1/16W,EMPTY,A',
 WATTAGE='1/16W',
 TOLERANCE='5%',
 MATERIAL='EMPTY',
 VALUE='0',
 PRIM_FILE='./archive_libs/logical/q_res/chips/chips.prt';

PART_NAME
 R4575 'Q_RES_0402LF-0,5%,1/16W,EMPTY,A':;

SECTION_NUMBER 1
 '@S9S_MB_2U_LIB.S9S_MB_2U(SCH_1):PAGE143_I142@PURE_QUANTA.Q_RES(CHIPS)':
 C_PATH='@s9s_mb_2u_lib.s9s_mb_2u(sch_1):page143_i142@pure_quanta.q_res(chips)',
 P_PATH='@s9s_mb_2u_lib.s9s_mb_2u(sch_1):page146_i142@pure_quanta.q_res(chips)',
 PATH='I142',
 DRAWING='@S9S_MB_2U_LIB.S9S_MB_2U(SCH_1):PAGE143',
 PHYS_PAGE='146',
 XY='(-725,4550)',
 ROT='0',
 VER='1',
 PACK_TYPE='0402LF',
 CDS_LIB='pure_quanta',
 CDS_PART_NAME='Q_RES_0402LF-0,5%,1/16W,EMPTY,A',
 WATTAGE='1/16W',
 TOLERANCE='5%',
 MATERIAL='EMPTY',
 VALUE='0',
 PRIM_FILE='./archive_libs/logical/q_res/chips/chips.prt';

PART_NAME
 R4576 'Q_RES_0402LF-0,5%,1/16W,EMPTY,A':;

SECTION_NUMBER 1
 '@S9S_MB_2U_LIB.S9S_MB_2U(SCH_1):PAGE143_I139@PURE_QUANTA.Q_RES(CHIPS)':
 C_PATH='@s9s_mb_2u_lib.s9s_mb_2u(sch_1):page143_i139@pure_quanta.q_res(chips)',
 P_PATH='@s9s_mb_2u_lib.s9s_mb_2u(sch_1):page146_i139@pure_quanta.q_res(chips)',
 PATH='I139',
 DRAWING='@S9S_MB_2U_LIB.S9S_MB_2U(SCH_1):PAGE143',
 PHYS_PAGE='146',
 XY='(3775,1950)',
 ROT='0',
 VER='1',
 PACK_TYPE='0402LF',
 CDS_LIB='pure_quanta',
 CDS_PART_NAME='Q_RES_0402LF-0,5%,1/16W,EMPTY,A',
 WATTAGE='1/16W',
 TOLERANCE='5%',
 MATERIAL='EMPTY',
 VALUE='0',
 PRIM_FILE='./archive_libs/logical/q_res/chips/chips.prt';

PART_NAME
 R4577 'Q_RES_0402LF-0,5%,1/16W,EMPTY,A':;

SECTION_NUMBER 1
 '@S9S_MB_2U_LIB.S9S_MB_2U(SCH_1):PAGE143_I137@PURE_QUANTA.Q_RES(CHIPS)':
 C_PATH='@s9s_mb_2u_lib.s9s_mb_2u(sch_1):page143_i137@pure_quanta.q_res(chips)',
 P_PATH='@s9s_mb_2u_lib.s9s_mb_2u(sch_1):page146_i137@pure_quanta.q_res(chips)',
 PATH='I137',
 DRAWING='@S9S_MB_2U_LIB.S9S_MB_2U(SCH_1):PAGE143',
 PHYS_PAGE='146',
 XY='(3800,4775)',
 ROT='0',
 VER='1',
 PACK_TYPE='0402LF',
 CDS_LIB='pure_quanta',
 CDS_PART_NAME='Q_RES_0402LF-0,5%,1/16W,EMPTY,A',
 WATTAGE='1/16W',
 TOLERANCE='5%',
 MATERIAL='EMPTY',
 VALUE='0',
 PRIM_FILE='./archive_libs/logical/q_res/chips/chips.prt';

PART_NAME
 R4578 'Q_RES_0402LF-0,5%,1/16W,EMPTY,A':;

SECTION_NUMBER 1
 '@S9S_MB_2U_LIB.S9S_MB_2U(SCH_1):PAGE143_I138@PURE_QUANTA.Q_RES(CHIPS)':
 C_PATH='@s9s_mb_2u_lib.s9s_mb_2u(sch_1):page143_i138@pure_quanta.q_res(chips)',
 P_PATH='@s9s_mb_2u_lib.s9s_mb_2u(sch_1):page146_i138@pure_quanta.q_res(chips)',
 PATH='I138',
 DRAWING='@S9S_MB_2U_LIB.S9S_MB_2U(SCH_1):PAGE143',
 PHYS_PAGE='146',
 XY='(3850,3400)',
 ROT='0',
 VER='1',
 PACK_TYPE='0402LF',
 CDS_LIB='pure_quanta',
 CDS_PART_NAME='Q_RES_0402LF-0,5%,1/16W,EMPTY,A',
 WATTAGE='1/16W',
 TOLERANCE='5%',
 MATERIAL='EMPTY',
 VALUE='0',
 PRIM_FILE='./archive_libs/logical/q_res/chips/chips.prt';

PART_NAME
 R4579 'Q_RES_0402LF-10K,1%,1/16W,CHIPA':;

SECTION_NUMBER 1
 '@S9S_MB_2U_LIB.S9S_MB_2U(SCH_1):PAGE184_I67@PURE_QUANTA.Q_RES(CHIPS)':
 C_PATH='@s9s_mb_2u_lib.s9s_mb_2u(sch_1):page184_i67@pure_quanta.q_res(chips)',
 P_PATH='@s9s_mb_2u_lib.s9s_mb_2u(sch_1):page195_i67@pure_quanta.q_res(chips)',
 PATH='I67',
 DRAWING='@S9S_MB_2U_LIB.S9S_MB_2U(SCH_1):PAGE184',
 PHYS_PAGE='195',
 XY='(2425,2675)',
 ROT='0',
 VER='2',
 PACK_TYPE='0402LF',
 CDS_LIB='pure_quanta',
 CDS_PART_NAME='Q_RES_0402LF-10K,1%,1/16W,CHIPA',
 WATTAGE='1/16W',
 TOLERANCE='1%',
 MATERIAL='CHIP',
 VALUE='10K',
 PRIM_FILE='./archive_libs/logical/q_res/chips/chips.prt';

PART_NAME
 R4580 'Q_RES_0402LF-10K,1%,1/16W,EMPTA':;

SECTION_NUMBER 1
 '@S9S_MB_2U_LIB.S9S_MB_2U(SCH_1):PAGE184_I5@PURE_QUANTA.Q_RES(CHIPS)':
 C_PATH='@s9s_mb_2u_lib.s9s_mb_2u(sch_1):page184_i5@pure_quanta.q_res(chips)',
 P_PATH='@s9s_mb_2u_lib.s9s_mb_2u(sch_1):page195_i5@pure_quanta.q_res(chips)',
 PATH='I5',
 DRAWING='@S9S_MB_2U_LIB.S9S_MB_2U(SCH_1):PAGE184',
 PHYS_PAGE='195',
 XY='(-1125,2900)',
 ROT='0',
 VER='2',
 PACK_TYPE='0402LF',
 CDS_LIB='pure_quanta',
 CDS_PART_NAME='Q_RES_0402LF-10K,1%,1/16W,EMPTA',
 WATTAGE='1/16W',
 TOLERANCE='1%',
 MATERIAL='EMPTY',
 VALUE='10K',
 PRIM_FILE='./archive_libs/logical/q_res/chips/chips.prt';

PART_NAME
 R4581 'Q_RES_0402LF-1K,1%,1/16W,CHIP,A':;

SECTION_NUMBER 1
 '@S9S_MB_2U_LIB.S9S_MB_2U(SCH_1):PAGE184_I1@PURE_QUANTA.Q_RES(CHIPS)':
 C_PATH='@s9s_mb_2u_lib.s9s_mb_2u(sch_1):page184_i1@pure_quanta.q_res(chips)',
 P_PATH='@s9s_mb_2u_lib.s9s_mb_2u(sch_1):page195_i1@pure_quanta.q_res(chips)',
 PATH='I1',
 DRAWING='@S9S_MB_2U_LIB.S9S_MB_2U(SCH_1):PAGE184',
 PHYS_PAGE='195',
 XY='(-1125,2075)',
 ROT='0',
 VER='2',
 PACK_TYPE='0402LF',
 CDS_LIB='pure_quanta',
 CDS_PART_NAME='Q_RES_0402LF-1K,1%,1/16W,CHIP,A',
 WATTAGE='1/16W',
 TOLERANCE='1%',
 MATERIAL='CHIP',
 VALUE='1K',
 PRIM_FILE='./archive_libs/logical/q_res/chips/chips.prt';

PART_NAME
 R4582 'Q_RES_0402LF-10K,1%,1/16W,EMPTA':;

SECTION_NUMBER 1
 '@S9S_MB_2U_LIB.S9S_MB_2U(SCH_1):PAGE184_I23@PURE_QUANTA.Q_RES(CHIPS)':
 C_PATH='@s9s_mb_2u_lib.s9s_mb_2u(sch_1):page184_i23@pure_quanta.q_res(chips)',
 P_PATH='@s9s_mb_2u_lib.s9s_mb_2u(sch_1):page195_i23@pure_quanta.q_res(chips)',
 PATH='I23',
 DRAWING='@S9S_MB_2U_LIB.S9S_MB_2U(SCH_1):PAGE184',
 PHYS_PAGE='195',
 XY='(-300,2900)',
 ROT='0',
 VER='2',
 PACK_TYPE='0402LF',
 CDS_LIB='pure_quanta',
 CDS_PART_NAME='Q_RES_0402LF-10K,1%,1/16W,EMPTA',
 WATTAGE='1/16W',
 TOLERANCE='1%',
 MATERIAL='EMPTY',
 VALUE='10K',
 PRIM_FILE='./archive_libs/logical/q_res/chips/chips.prt';

PART_NAME
 R4583 'Q_RES_0402LF-1K,1%,1/16W,CHIP,A':;

SECTION_NUMBER 1
 '@S9S_MB_2U_LIB.S9S_MB_2U(SCH_1):PAGE184_I18@PURE_QUANTA.Q_RES(CHIPS)':
 C_PATH='@s9s_mb_2u_lib.s9s_mb_2u(sch_1):page184_i18@pure_quanta.q_res(chips)',
 P_PATH='@s9s_mb_2u_lib.s9s_mb_2u(sch_1):page195_i18@pure_quanta.q_res(chips)',
 PATH='I18',
 DRAWING='@S9S_MB_2U_LIB.S9S_MB_2U(SCH_1):PAGE184',
 PHYS_PAGE='195',
 XY='(-300,2075)',
 ROT='0',
 VER='2',
 PACK_TYPE='0402LF',
 CDS_LIB='pure_quanta',
 CDS_PART_NAME='Q_RES_0402LF-1K,1%,1/16W,CHIP,A',
 WATTAGE='1/16W',
 TOLERANCE='1%',
 MATERIAL='CHIP',
 VALUE='1K',
 PRIM_FILE='./archive_libs/logical/q_res/chips/chips.prt';

PART_NAME
 R4584 'Q_RES_0402LF-10K,1%,1/16W,EMPTA':;

SECTION_NUMBER 1
 '@S9S_MB_2U_LIB.S9S_MB_2U(SCH_1):PAGE184_I24@PURE_QUANTA.Q_RES(CHIPS)':
 C_PATH='@s9s_mb_2u_lib.s9s_mb_2u(sch_1):page184_i24@pure_quanta.q_res(chips)',
 P_PATH='@s9s_mb_2u_lib.s9s_mb_2u(sch_1):page195_i24@pure_quanta.q_res(chips)',
 PATH='I24',
 DRAWING='@S9S_MB_2U_LIB.S9S_MB_2U(SCH_1):PAGE184',
 PHYS_PAGE='195',
 XY='(-25,2900)',
 ROT='0',
 VER='2',
 PACK_TYPE='0402LF',
 CDS_LIB='pure_quanta',
 CDS_PART_NAME='Q_RES_0402LF-10K,1%,1/16W,EMPTA',
 WATTAGE='1/16W',
 TOLERANCE='1%',
 MATERIAL='EMPTY',
 VALUE='10K',
 PRIM_FILE='./archive_libs/logical/q_res/chips/chips.prt';

PART_NAME
 R4585 'Q_RES_0402LF-1K,1%,1/16W,CHIP,A':;

SECTION_NUMBER 1
 '@S9S_MB_2U_LIB.S9S_MB_2U(SCH_1):PAGE184_I20@PURE_QUANTA.Q_RES(CHIPS)':
 C_PATH='@s9s_mb_2u_lib.s9s_mb_2u(sch_1):page184_i20@pure_quanta.q_res(chips)',
 P_PATH='@s9s_mb_2u_lib.s9s_mb_2u(sch_1):page195_i20@pure_quanta.q_res(chips)',
 PATH='I20',
 DRAWING='@S9S_MB_2U_LIB.S9S_MB_2U(SCH_1):PAGE184',
 PHYS_PAGE='195',
 XY='(-25,2075)',
 ROT='0',
 VER='2',
 PACK_TYPE='0402LF',
 CDS_LIB='pure_quanta',
 CDS_PART_NAME='Q_RES_0402LF-1K,1%,1/16W,CHIP,A',
 WATTAGE='1/16W',
 TOLERANCE='1%',
 MATERIAL='CHIP',
 VALUE='1K',
 PRIM_FILE='./archive_libs/logical/q_res/chips/chips.prt';

PART_NAME
 R4586 'Q_RES_0402LF-10K,1%,1/16W,CHIPA':;

SECTION_NUMBER 1
 '@S9S_MB_2U_LIB.S9S_MB_2U(SCH_1):PAGE184_I62@PURE_QUANTA.Q_RES(CHIPS)':
 C_PATH='@s9s_mb_2u_lib.s9s_mb_2u(sch_1):page184_i62@pure_quanta.q_res(chips)',
 P_PATH='@s9s_mb_2u_lib.s9s_mb_2u(sch_1):page195_i62@pure_quanta.q_res(chips)',
 PATH='I62',
 DRAWING='@S9S_MB_2U_LIB.S9S_MB_2U(SCH_1):PAGE184',
 PHYS_PAGE='195',
 XY='(1875,2675)',
 ROT='0',
 VER='2',
 PACK_TYPE='0402LF',
 CDS_LIB='pure_quanta',
 CDS_PART_NAME='Q_RES_0402LF-10K,1%,1/16W,CHIPA',
 WATTAGE='1/16W',
 TOLERANCE='1%',
 MATERIAL='CHIP',
 VALUE='10K',
 PRIM_FILE='./archive_libs/logical/q_res/chips/chips.prt';

PART_NAME
 R4588 'Q_RES_0402LF-1K,1%,1/16W,EMPTYA':;

SECTION_NUMBER 1
 '@S9S_MB_2U_LIB.S9S_MB_2U(SCH_1):PAGE184_I58@PURE_QUANTA.Q_RES(CHIPS)':
 C_PATH='@s9s_mb_2u_lib.s9s_mb_2u(sch_1):page184_i58@pure_quanta.q_res(chips)',
 P_PATH='@s9s_mb_2u_lib.s9s_mb_2u(sch_1):page195_i58@pure_quanta.q_res(chips)',
 PATH='I58',
 DRAWING='@S9S_MB_2U_LIB.S9S_MB_2U(SCH_1):PAGE184',
 PHYS_PAGE='195',
 XY='(1875,2025)',
 ROT='0',
 VER='2',
 PACK_TYPE='0402LF',
 CDS_LIB='pure_quanta',
 CDS_PART_NAME='Q_RES_0402LF-1K,1%,1/16W,EMPTYA',
 WATTAGE='1/16W',
 TOLERANCE='1%',
 MATERIAL='EMPTY',
 VALUE='1K',
 PRIM_FILE='./archive_libs/logical/q_res/chips/chips.prt';

PART_NAME
 R4589 'Q_RES_0402LF-10K,1%,1/16W,CHIPA':;

SECTION_NUMBER 1
 '@S9S_MB_2U_LIB.S9S_MB_2U(SCH_1):PAGE184_I63@PURE_QUANTA.Q_RES(CHIPS)':
 C_PATH='@s9s_mb_2u_lib.s9s_mb_2u(sch_1):page184_i63@pure_quanta.q_res(chips)',
 P_PATH='@s9s_mb_2u_lib.s9s_mb_2u(sch_1):page195_i63@pure_quanta.q_res(chips)',
 PATH='I63',
 DRAWING='@S9S_MB_2U_LIB.S9S_MB_2U(SCH_1):PAGE184',
 PHYS_PAGE='195',
 XY='(2150,2675)',
 ROT='0',
 VER='2',
 PACK_TYPE='0402LF',
 CDS_LIB='pure_quanta',
 CDS_PART_NAME='Q_RES_0402LF-10K,1%,1/16W,CHIPA',
 WATTAGE='1/16W',
 TOLERANCE='1%',
 MATERIAL='CHIP',
 VALUE='10K',
 PRIM_FILE='./archive_libs/logical/q_res/chips/chips.prt';

PART_NAME
 R4590 'Q_RES_0402LF-1K,1%,1/16W,EMPTYA':;

SECTION_NUMBER 1
 '@S9S_MB_2U_LIB.S9S_MB_2U(SCH_1):PAGE184_I59@PURE_QUANTA.Q_RES(CHIPS)':
 C_PATH='@s9s_mb_2u_lib.s9s_mb_2u(sch_1):page184_i59@pure_quanta.q_res(chips)',
 P_PATH='@s9s_mb_2u_lib.s9s_mb_2u(sch_1):page195_i59@pure_quanta.q_res(chips)',
 PATH='I59',
 DRAWING='@S9S_MB_2U_LIB.S9S_MB_2U(SCH_1):PAGE184',
 PHYS_PAGE='195',
 XY='(2150,2025)',
 ROT='0',
 VER='2',
 PACK_TYPE='0402LF',
 CDS_LIB='pure_quanta',
 CDS_PART_NAME='Q_RES_0402LF-1K,1%,1/16W,EMPTYA',
 WATTAGE='1/16W',
 TOLERANCE='1%',
 MATERIAL='EMPTY',
 VALUE='1K',
 PRIM_FILE='./archive_libs/logical/q_res/chips/chips.prt';

PART_NAME
 R4591 'Q_RES_0402LF-10K,1%,1/16W,EMPTA':;

SECTION_NUMBER 1
 '@S9S_MB_2U_LIB.S9S_MB_2U(SCH_1):PAGE184_I6@PURE_QUANTA.Q_RES(CHIPS)':
 C_PATH='@s9s_mb_2u_lib.s9s_mb_2u(sch_1):page184_i6@pure_quanta.q_res(chips)',
 P_PATH='@s9s_mb_2u_lib.s9s_mb_2u(sch_1):page195_i6@pure_quanta.q_res(chips)',
 PATH='I6',
 DRAWING='@S9S_MB_2U_LIB.S9S_MB_2U(SCH_1):PAGE184',
 PHYS_PAGE='195',
 XY='(-850,2900)',
 ROT='0',
 VER='2',
 PACK_TYPE='0402LF',
 CDS_LIB='pure_quanta',
 CDS_PART_NAME='Q_RES_0402LF-10K,1%,1/16W,EMPTA',
 WATTAGE='1/16W',
 TOLERANCE='1%',
 MATERIAL='EMPTY',
 VALUE='10K',
 PRIM_FILE='./archive_libs/logical/q_res/chips/chips.prt';

PART_NAME
 R4592 'Q_RES_0402LF-1K,1%,1/16W,CHIP,A':;

SECTION_NUMBER 1
 '@S9S_MB_2U_LIB.S9S_MB_2U(SCH_1):PAGE184_I4@PURE_QUANTA.Q_RES(CHIPS)':
 C_PATH='@s9s_mb_2u_lib.s9s_mb_2u(sch_1):page184_i4@pure_quanta.q_res(chips)',
 P_PATH='@s9s_mb_2u_lib.s9s_mb_2u(sch_1):page195_i4@pure_quanta.q_res(chips)',
 PATH='I4',
 DRAWING='@S9S_MB_2U_LIB.S9S_MB_2U(SCH_1):PAGE184',
 PHYS_PAGE='195',
 XY='(-850,2075)',
 ROT='0',
 VER='2',
 PACK_TYPE='0402LF',
 CDS_LIB='pure_quanta',
 CDS_PART_NAME='Q_RES_0402LF-1K,1%,1/16W,CHIP,A',
 WATTAGE='1/16W',
 TOLERANCE='1%',
 MATERIAL='CHIP',
 VALUE='1K',
 PRIM_FILE='./archive_libs/logical/q_res/chips/chips.prt';

PART_NAME
 R4593 'Q_RES_0402LF-0,5%,1/16W,CHIP,CA':;

SECTION_NUMBER 1
 '@S9S_MB_2U_LIB.S9S_MB_2U(SCH_1):PAGE252_I66@PURE_QUANTA.Q_RES(CHIPS)':
 C_PATH='@s9s_mb_2u_lib.s9s_mb_2u(sch_1):page252_i66@pure_quanta.q_res(chips)',
 P_PATH='@s9s_mb_2u_lib.s9s_mb_2u(sch_1):page266_i66@pure_quanta.q_res(chips)',
 PATH='I66',
 DRAWING='@S9S_MB_2U_LIB.S9S_MB_2U(SCH_1):PAGE252',
 PHYS_PAGE='266',
 XY='(-4600,2700)',
 ROT='0',
 VER='1',
 PACK_TYPE='0402LF',
 LOCATION='R4593',
 CDS_LIB='pure_quanta',
 CDS_PART_NAME='Q_RES_0402LF-0,5%,1/16W,CHIP,CA',
 WATTAGE='1/16W',
 TOLERANCE='5%',
 MATERIAL='CHIP',
 VALUE='0',
 PRIM_FILE='./archive_libs/logical/q_res/chips/chips.prt';

PART_NAME
 R4594 'Q_RES_0402LF-0,5%,1/16W,CHIP,CA':;

SECTION_NUMBER 1
 '@S9S_MB_2U_LIB.S9S_MB_2U(SCH_1):PAGE278_I58@PURE_QUANTA.Q_RES(CHIPS)':
 C_PATH='@s9s_mb_2u_lib.s9s_mb_2u(sch_1):page278_i58@pure_quanta.q_res(chips)',
 P_PATH='@s9s_mb_2u_lib.s9s_mb_2u(sch_1):page292_i58@pure_quanta.q_res(chips)',
 PATH='I58',
 DRAWING='@S9S_MB_2U_LIB.S9S_MB_2U(SCH_1):PAGE278',
 PHYS_PAGE='292',
 XY='(1175,8000)',
 ROT='0',
 VER='1',
 PACK_TYPE='0402LF',
 LOCATION='R4594',
 SEC='1',
 CDS_LIB='pure_quanta',
 CDS_PART_NAME='Q_RES_0402LF-0,5%,1/16W,CHIP,CA',
 SEC_TYPE='0402LF',
 WATTAGE='1/16W',
 TOLERANCE='5%',
 MATERIAL='CHIP',
 VALUE='0',
 PRIM_FILE='./archive_libs/logical/q_res/chips/chips.prt';

PART_NAME
 R4595 'Q_RES_0402LF-0,5%,1/16W,CHIP,CA':;

SECTION_NUMBER 1
 '@S9S_MB_2U_LIB.S9S_MB_2U(SCH_1):PAGE282_I39@PURE_QUANTA.Q_RES(CHIPS)':
 C_PATH='@s9s_mb_2u_lib.s9s_mb_2u(sch_1):page282_i39@pure_quanta.q_res(chips)',
 P_PATH='@s9s_mb_2u_lib.s9s_mb_2u(sch_1):page296_i39@pure_quanta.q_res(chips)',
 PATH='I39',
 DRAWING='@S9S_MB_2U_LIB.S9S_MB_2U(SCH_1):PAGE282',
 PHYS_PAGE='296',
 XY='(-5325,4300)',
 ROT='0',
 VER='1',
 PACK_TYPE='0402LF',
 LOCATION='R4595',
 CDS_LIB='pure_quanta',
 CDS_PART_NAME='Q_RES_0402LF-0,5%,1/16W,CHIP,CA',
 WATTAGE='1/16W',
 TOLERANCE='5%',
 MATERIAL='CHIP',
 VALUE='0',
 PRIM_FILE='./archive_libs/logical/q_res/chips/chips.prt';

PART_NAME
 R4596 'Q_RES_0402LF-1K,1%,1/16W,EMPTYA':;

SECTION_NUMBER 1
 '@S9S_MB_2U_LIB.S9S_MB_2U(SCH_1):PAGE184_I61@PURE_QUANTA.Q_RES(CHIPS)':
 C_PATH='@s9s_mb_2u_lib.s9s_mb_2u(sch_1):page184_i61@pure_quanta.q_res(chips)',
 P_PATH='@s9s_mb_2u_lib.s9s_mb_2u(sch_1):page195_i61@pure_quanta.q_res(chips)',
 PATH='I61',
 DRAWING='@S9S_MB_2U_LIB.S9S_MB_2U(SCH_1):PAGE184',
 PHYS_PAGE='195',
 XY='(2425,2025)',
 ROT='0',
 VER='2',
 PACK_TYPE='0402LF',
 CDS_LIB='pure_quanta',
 CDS_PART_NAME='Q_RES_0402LF-1K,1%,1/16W,EMPTYA',
 WATTAGE='1/16W',
 TOLERANCE='1%',
 MATERIAL='EMPTY',
 VALUE='1K',
 PRIM_FILE='./archive_libs/logical/q_res/chips/chips.prt';

PART_NAME
 R4597 'Q_RES_0402LF-10K,1%,1/16W,EMPTA':;

SECTION_NUMBER 1
 '@S9S_MB_2U_LIB.S9S_MB_2U(SCH_1):PAGE184_I22@PURE_QUANTA.Q_RES(CHIPS)':
 C_PATH='@s9s_mb_2u_lib.s9s_mb_2u(sch_1):page184_i22@pure_quanta.q_res(chips)',
 P_PATH='@s9s_mb_2u_lib.s9s_mb_2u(sch_1):page195_i22@pure_quanta.q_res(chips)',
 PATH='I22',
 DRAWING='@S9S_MB_2U_LIB.S9S_MB_2U(SCH_1):PAGE184',
 PHYS_PAGE='195',
 XY='(-575,2900)',
 ROT='0',
 VER='2',
 PACK_TYPE='0402LF',
 CDS_LIB='pure_quanta',
 CDS_PART_NAME='Q_RES_0402LF-10K,1%,1/16W,EMPTA',
 WATTAGE='1/16W',
 TOLERANCE='1%',
 MATERIAL='EMPTY',
 VALUE='10K',
 PRIM_FILE='./archive_libs/logical/q_res/chips/chips.prt';

PART_NAME
 R4598 'Q_RES_0402LF-1K,1%,1/16W,CHIP,A':;

SECTION_NUMBER 1
 '@S9S_MB_2U_LIB.S9S_MB_2U(SCH_1):PAGE184_I16@PURE_QUANTA.Q_RES(CHIPS)':
 C_PATH='@s9s_mb_2u_lib.s9s_mb_2u(sch_1):page184_i16@pure_quanta.q_res(chips)',
 P_PATH='@s9s_mb_2u_lib.s9s_mb_2u(sch_1):page195_i16@pure_quanta.q_res(chips)',
 PATH='I16',
 DRAWING='@S9S_MB_2U_LIB.S9S_MB_2U(SCH_1):PAGE184',
 PHYS_PAGE='195',
 XY='(-575,2075)',
 ROT='0',
 VER='2',
 PACK_TYPE='0402LF',
 CDS_LIB='pure_quanta',
 CDS_PART_NAME='Q_RES_0402LF-1K,1%,1/16W,CHIP,A',
 WATTAGE='1/16W',
 TOLERANCE='1%',
 MATERIAL='CHIP',
 VALUE='1K',
 PRIM_FILE='./archive_libs/logical/q_res/chips/chips.prt';

PART_NAME
 R4599 'Q_RES_0402LF-0,5%,1/16W,CHIP,CA':;

SECTION_NUMBER 1
 '@S9S_MB_2U_LIB.S9S_MB_2U(SCH_1):PAGE313_I159@PURE_QUANTA.Q_RES(CHIPS)':
 C_PATH='@s9s_mb_2u_lib.s9s_mb_2u(sch_1):page313_i159@pure_quanta.q_res(chips)',
 P_PATH='@s9s_mb_2u_lib.s9s_mb_2u(sch_1):page214_i159@pure_quanta.q_res(chips)',
 PATH='I159',
 DRAWING='@S9S_MB_2U_LIB.S9S_MB_2U(SCH_1):PAGE313',
 PHYS_PAGE='214',
 XY='(2700,-1000)',
 ROT='0',
 VER='1',
 PACK_TYPE='0402LF',
 CDS_LIB='pure_quanta',
 CDS_PART_NAME='Q_RES_0402LF-0,5%,1/16W,CHIP,CA',
 WATTAGE='1/16W',
 TOLERANCE='5%',
 MATERIAL='CHIP',
 VALUE='0',
 PRIM_FILE='./archive_libs/logical/q_res/chips/chips.prt';

PART_NAME
 R4600 'Q_RES_0402LF-0,5%,1/16W,CHIP,CA':;

SECTION_NUMBER 1
 '@S9S_MB_2U_LIB.S9S_MB_2U(SCH_1):PAGE313_I160@PURE_QUANTA.Q_RES(CHIPS)':
 C_PATH='@s9s_mb_2u_lib.s9s_mb_2u(sch_1):page313_i160@pure_quanta.q_res(chips)',
 P_PATH='@s9s_mb_2u_lib.s9s_mb_2u(sch_1):page214_i160@pure_quanta.q_res(chips)',
 PATH='I160',
 DRAWING='@S9S_MB_2U_LIB.S9S_MB_2U(SCH_1):PAGE313',
 PHYS_PAGE='214',
 XY='(2700,-1175)',
 ROT='0',
 VER='1',
 PACK_TYPE='0402LF',
 CDS_LIB='pure_quanta',
 CDS_PART_NAME='Q_RES_0402LF-0,5%,1/16W,CHIP,CA',
 WATTAGE='1/16W',
 TOLERANCE='5%',
 MATERIAL='CHIP',
 VALUE='0',
 PRIM_FILE='./archive_libs/logical/q_res/chips/chips.prt';

PART_NAME
 R4601 'Q_RES_0402LF-0,5%,1/16W,CHIP,CA':;

SECTION_NUMBER 1
 '@S9S_MB_2U_LIB.S9S_MB_2U(SCH_1):PAGE152_I90@PURE_QUANTA.Q_RES(CHIPS)':
 C_PATH='@s9s_mb_2u_lib.s9s_mb_2u(sch_1):page152_i90@pure_quanta.q_res(chips)',
 P_PATH='@s9s_mb_2u_lib.s9s_mb_2u(sch_1):page155_i90@pure_quanta.q_res(chips)',
 PATH='I90',
 DRAWING='@S9S_MB_2U_LIB.S9S_MB_2U(SCH_1):PAGE152',
 PHYS_PAGE='155',
 XY='(-4800,3125)',
 ROT='0',
 VER='1',
 PACK_TYPE='0402LF',
 CDS_LIB='pure_quanta',
 CDS_PART_NAME='Q_RES_0402LF-0,5%,1/16W,CHIP,CA',
 WATTAGE='1/16W',
 TOLERANCE='5%',
 MATERIAL='CHIP',
 VALUE='0',
 PRIM_FILE='./archive_libs/logical/q_res/chips/chips.prt';

PART_NAME
 R4602 'Q_RES_0402LF-0,5%,1/16W,CHIP,CA':;

SECTION_NUMBER 1
 '@S9S_MB_2U_LIB.S9S_MB_2U(SCH_1):PAGE156_I90@PURE_QUANTA.Q_RES(CHIPS)':
 C_PATH='@s9s_mb_2u_lib.s9s_mb_2u(sch_1):page156_i90@pure_quanta.q_res(chips)',
 P_PATH='@s9s_mb_2u_lib.s9s_mb_2u(sch_1):page161_i90@pure_quanta.q_res(chips)',
 PATH='I90',
 DRAWING='@S9S_MB_2U_LIB.S9S_MB_2U(SCH_1):PAGE156',
 PHYS_PAGE='161',
 XY='(8625,-3475)',
 ROT='0',
 VER='1',
 PACK_TYPE='0402LF',
 CDS_LIB='pure_quanta',
 CDS_PART_NAME='Q_RES_0402LF-0,5%,1/16W,CHIP,CA',
 WATTAGE='1/16W',
 TOLERANCE='5%',
 MATERIAL='CHIP',
 VALUE='0',
 PRIM_FILE='./archive_libs/logical/q_res/chips/chips.prt';

PART_NAME
 R4603 'Q_RES_0402LF-10K,1%,1/16W,CHIPA':;

SECTION_NUMBER 1
 '@S9S_MB_2U_LIB.S9S_MB_2U(SCH_1):PAGE222_I48@PURE_QUANTA.Q_RES(CHIPS)':
 C_PATH='@s9s_mb_2u_lib.s9s_mb_2u(sch_1):page222_i48@pure_quanta.q_res(chips)',
 P_PATH='@s9s_mb_2u_lib.s9s_mb_2u(sch_1):page234_i48@pure_quanta.q_res(chips)',
 PATH='I48',
 DRAWING='@S9S_MB_2U_LIB.S9S_MB_2U(SCH_1):PAGE222',
 PHYS_PAGE='234',
 XY='(-5050,7100)',
 ROT='0',
 VER='2',
 PACK_TYPE='0402LF',
 CDS_LIB='pure_quanta',
 CDS_PART_NAME='Q_RES_0402LF-10K,1%,1/16W,CHIPA',
 WATTAGE='1/16W',
 TOLERANCE='1%',
 MATERIAL='CHIP',
 VALUE='10K',
 PRIM_FILE='./archive_libs/logical/q_res/chips/chips.prt';

PART_NAME
 R4604 'Q_RES_0402LF-4.7K,5%,1/16W,CHIA':;

SECTION_NUMBER 1
 '@S9S_MB_2U_LIB.S9S_MB_2U(SCH_1):PAGE213_I18@PURE_QUANTA.Q_RES(CHIPS)':
 C_PATH='@s9s_mb_2u_lib.s9s_mb_2u(sch_1):page213_i18@pure_quanta.q_res(chips)',
 P_PATH='@s9s_mb_2u_lib.s9s_mb_2u(sch_1):page224_i18@pure_quanta.q_res(chips)',
 PATH='I18',
 DRAWING='@S9S_MB_2U_LIB.S9S_MB_2U(SCH_1):PAGE213',
 PHYS_PAGE='224',
 XY='(-8275,2950)',
 ROT='0',
 VER='2',
 PACK_TYPE='0402LF',
 CDS_LIB='pure_quanta',
 CDS_PART_NAME='Q_RES_0402LF-4.7K,5%,1/16W,CHIA',
 WATTAGE='1/16W',
 TOLERANCE='5%',
 MATERIAL='CHIP',
 VALUE='4.7K',
 PRIM_FILE='./archive_libs/logical/q_res/chips/chips.prt';

PART_NAME
 R4605 'Q_RES_0402LF-4.7K,5%,1/16W,CHIA':;

SECTION_NUMBER 1
 '@S9S_MB_2U_LIB.S9S_MB_2U(SCH_1):PAGE213_I22@PURE_QUANTA.Q_RES(CHIPS)':
 C_PATH='@s9s_mb_2u_lib.s9s_mb_2u(sch_1):page213_i22@pure_quanta.q_res(chips)',
 P_PATH='@s9s_mb_2u_lib.s9s_mb_2u(sch_1):page224_i22@pure_quanta.q_res(chips)',
 PATH='I22',
 DRAWING='@S9S_MB_2U_LIB.S9S_MB_2U(SCH_1):PAGE213',
 PHYS_PAGE='224',
 XY='(-7125,3075)',
 ROT='0',
 VER='2',
 PACK_TYPE='0402LF',
 CDS_LIB='pure_quanta',
 CDS_PART_NAME='Q_RES_0402LF-4.7K,5%,1/16W,CHIA',
 WATTAGE='1/16W',
 TOLERANCE='5%',
 MATERIAL='CHIP',
 VALUE='4.7K',
 PRIM_FILE='./archive_libs/logical/q_res/chips/chips.prt';

PART_NAME
 R4606 'Q_RES_0402LF-0,5%,1/16W,CHIP,CA':;

SECTION_NUMBER 1
 '@S9S_MB_2U_LIB.S9S_MB_2U(SCH_1):PAGE313_I180@PURE_QUANTA.Q_RES(CHIPS)':
 C_PATH='@s9s_mb_2u_lib.s9s_mb_2u(sch_1):page313_i180@pure_quanta.q_res(chips)',
 P_PATH='@s9s_mb_2u_lib.s9s_mb_2u(sch_1):page214_i180@pure_quanta.q_res(chips)',
 PATH='I180',
 DRAWING='@S9S_MB_2U_LIB.S9S_MB_2U(SCH_1):PAGE313',
 PHYS_PAGE='214',
 XY='(-1025,-1425)',
 ROT='0',
 VER='1',
 PACK_TYPE='0402LF',
 CDS_LIB='pure_quanta',
 CDS_PART_NAME='Q_RES_0402LF-0,5%,1/16W,CHIP,CA',
 WATTAGE='1/16W',
 TOLERANCE='5%',
 MATERIAL='CHIP',
 VALUE='0',
 PRIM_FILE='./archive_libs/logical/q_res/chips/chips.prt';

PART_NAME
 R4607 'Q_RES_0402LF-0,5%,1/16W,CHIP,CA':;

SECTION_NUMBER 1
 '@S9S_MB_2U_LIB.S9S_MB_2U(SCH_1):PAGE313_I183@PURE_QUANTA.Q_RES(CHIPS)':
 C_PATH='@s9s_mb_2u_lib.s9s_mb_2u(sch_1):page313_i183@pure_quanta.q_res(chips)',
 P_PATH='@s9s_mb_2u_lib.s9s_mb_2u(sch_1):page214_i183@pure_quanta.q_res(chips)',
 PATH='I183',
 DRAWING='@S9S_MB_2U_LIB.S9S_MB_2U(SCH_1):PAGE313',
 PHYS_PAGE='214',
 XY='(-1025,-1625)',
 ROT='0',
 VER='1',
 PACK_TYPE='0402LF',
 CDS_LIB='pure_quanta',
 CDS_PART_NAME='Q_RES_0402LF-0,5%,1/16W,CHIP,CA',
 WATTAGE='1/16W',
 TOLERANCE='5%',
 MATERIAL='CHIP',
 VALUE='0',
 PRIM_FILE='./archive_libs/logical/q_res/chips/chips.prt';

PART_NAME
 R4608 'Q_RES_0402LF-33.2,1%,1/16W,CHIA':;

SECTION_NUMBER 1
 '@S9S_MB_2U_LIB.S9S_MB_2U(SCH_1):PAGE313_I190@PURE_QUANTA.Q_RES(CHIPS)':
 C_PATH='@s9s_mb_2u_lib.s9s_mb_2u(sch_1):page313_i190@pure_quanta.q_res(chips)',
 P_PATH='@s9s_mb_2u_lib.s9s_mb_2u(sch_1):page214_i190@pure_quanta.q_res(chips)',
 PATH='I190',
 DRAWING='@S9S_MB_2U_LIB.S9S_MB_2U(SCH_1):PAGE313',
 PHYS_PAGE='214',
 XY='(-1050,-1900)',
 ROT='0',
 VER='1',
 PACK_TYPE='0402LF',
 CDS_LIB='pure_quanta',
 CDS_PART_NAME='Q_RES_0402LF-33.2,1%,1/16W,CHIA',
 WATTAGE='1/16W',
 TOLERANCE='1%',
 MATERIAL='CHIP',
 VALUE='33.2',
 PRIM_FILE='./archive_libs/logical/q_res/chips/chips.prt';

PART_NAME
 R4609 'Q_RES_0402LF-33.2,1%,1/16W,CHIA':;

SECTION_NUMBER 1
 '@S9S_MB_2U_LIB.S9S_MB_2U(SCH_1):PAGE313_I194@PURE_QUANTA.Q_RES(CHIPS)':
 C_PATH='@s9s_mb_2u_lib.s9s_mb_2u(sch_1):page313_i194@pure_quanta.q_res(chips)',
 P_PATH='@s9s_mb_2u_lib.s9s_mb_2u(sch_1):page214_i194@pure_quanta.q_res(chips)',
 PATH='I194',
 DRAWING='@S9S_MB_2U_LIB.S9S_MB_2U(SCH_1):PAGE313',
 PHYS_PAGE='214',
 XY='(-1050,-2125)',
 ROT='0',
 VER='1',
 PACK_TYPE='0402LF',
 CDS_LIB='pure_quanta',
 CDS_PART_NAME='Q_RES_0402LF-33.2,1%,1/16W,CHIA',
 WATTAGE='1/16W',
 TOLERANCE='1%',
 MATERIAL='CHIP',
 VALUE='33.2',
 PRIM_FILE='./archive_libs/logical/q_res/chips/chips.prt';

PART_NAME
 R4610 'Q_RES_0402LF-33.2,1%,1/16W,CHIA':;

SECTION_NUMBER 1
 '@S9S_MB_2U_LIB.S9S_MB_2U(SCH_1):PAGE313_I200@PURE_QUANTA.Q_RES(CHIPS)':
 C_PATH='@s9s_mb_2u_lib.s9s_mb_2u(sch_1):page313_i200@pure_quanta.q_res(chips)',
 P_PATH='@s9s_mb_2u_lib.s9s_mb_2u(sch_1):page214_i200@pure_quanta.q_res(chips)',
 PATH='I200',
 DRAWING='@S9S_MB_2U_LIB.S9S_MB_2U(SCH_1):PAGE313',
 PHYS_PAGE='214',
 XY='(-1050,-2350)',
 ROT='0',
 VER='1',
 PACK_TYPE='0402LF',
 CDS_LIB='pure_quanta',
 CDS_PART_NAME='Q_RES_0402LF-33.2,1%,1/16W,CHIA',
 WATTAGE='1/16W',
 TOLERANCE='1%',
 MATERIAL='CHIP',
 VALUE='33.2',
 PRIM_FILE='./archive_libs/logical/q_res/chips/chips.prt';

PART_NAME
 R4611 'Q_RES_0402LF-33.2,1%,1/16W,CHIA':;

SECTION_NUMBER 1
 '@S9S_MB_2U_LIB.S9S_MB_2U(SCH_1):PAGE313_I206@PURE_QUANTA.Q_RES(CHIPS)':
 C_PATH='@s9s_mb_2u_lib.s9s_mb_2u(sch_1):page313_i206@pure_quanta.q_res(chips)',
 P_PATH='@s9s_mb_2u_lib.s9s_mb_2u(sch_1):page214_i206@pure_quanta.q_res(chips)',
 PATH='I206',
 DRAWING='@S9S_MB_2U_LIB.S9S_MB_2U(SCH_1):PAGE313',
 PHYS_PAGE='214',
 XY='(-1050,-2525)',
 ROT='0',
 VER='1',
 PACK_TYPE='0402LF',
 CDS_LIB='pure_quanta',
 CDS_PART_NAME='Q_RES_0402LF-33.2,1%,1/16W,CHIA',
 WATTAGE='1/16W',
 TOLERANCE='1%',
 MATERIAL='CHIP',
 VALUE='33.2',
 PRIM_FILE='./archive_libs/logical/q_res/chips/chips.prt';

PART_NAME
 R4612 'Q_RES_0402LF-33.2,1%,1/16W,CHIA':;

SECTION_NUMBER 1
 '@S9S_MB_2U_LIB.S9S_MB_2U(SCH_1):PAGE313_I211@PURE_QUANTA.Q_RES(CHIPS)':
 C_PATH='@s9s_mb_2u_lib.s9s_mb_2u(sch_1):page313_i211@pure_quanta.q_res(chips)',
 P_PATH='@s9s_mb_2u_lib.s9s_mb_2u(sch_1):page214_i211@pure_quanta.q_res(chips)',
 PATH='I211',
 DRAWING='@S9S_MB_2U_LIB.S9S_MB_2U(SCH_1):PAGE313',
 PHYS_PAGE='214',
 XY='(-1050,-2675)',
 ROT='0',
 VER='1',
 PACK_TYPE='0402LF',
 CDS_LIB='pure_quanta',
 CDS_PART_NAME='Q_RES_0402LF-33.2,1%,1/16W,CHIA',
 WATTAGE='1/16W',
 TOLERANCE='1%',
 MATERIAL='CHIP',
 VALUE='33.2',
 PRIM_FILE='./archive_libs/logical/q_res/chips/chips.prt';

PART_NAME
 R4613 'Q_RES_0402LF-0,5%,1/16W,EMPTY,A':;

SECTION_NUMBER 1
 '@S9S_MB_2U_LIB.S9S_MB_2U(SCH_1):PAGE154_I232@PURE_QUANTA.Q_RES(CHIPS)':
 C_PATH='@s9s_mb_2u_lib.s9s_mb_2u(sch_1):page154_i232@pure_quanta.q_res(chips)',
 P_PATH='@s9s_mb_2u_lib.s9s_mb_2u(sch_1):page158_i232@pure_quanta.q_res(chips)',
 PATH='I232',
 DRAWING='@S9S_MB_2U_LIB.S9S_MB_2U(SCH_1):PAGE154',
 PHYS_PAGE='158',
 XY='(-1900,7550)',
 ROT='0',
 VER='1',
 PACK_TYPE='0402LF',
 CDS_LIB='pure_quanta',
 CDS_PART_NAME='Q_RES_0402LF-0,5%,1/16W,EMPTY,A',
 WATTAGE='1/16W',
 TOLERANCE='5%',
 MATERIAL='EMPTY',
 VALUE='0',
 PRIM_FILE='./archive_libs/logical/q_res/chips/chips.prt';

PART_NAME
 R4614 'Q_RES_0402LF-33.2,1%,1/16W,CHIA':;

SECTION_NUMBER 1
 '@S9S_MB_2U_LIB.S9S_MB_2U(SCH_1):PAGE154_I238@PURE_QUANTA.Q_RES(CHIPS)':
 C_PATH='@s9s_mb_2u_lib.s9s_mb_2u(sch_1):page154_i238@pure_quanta.q_res(chips)',
 P_PATH='@s9s_mb_2u_lib.s9s_mb_2u(sch_1):page158_i238@pure_quanta.q_res(chips)',
 PATH='I238',
 DRAWING='@S9S_MB_2U_LIB.S9S_MB_2U(SCH_1):PAGE154',
 PHYS_PAGE='158',
 XY='(-1875,7225)',
 ROT='0',
 VER='1',
 PACK_TYPE='0402LF',
 LOCATION='R4614',
 CDS_LIB='pure_quanta',
 CDS_PART_NAME='Q_RES_0402LF-33.2,1%,1/16W,CHIA',
 WATTAGE='1/16W',
 TOLERANCE='1%',
 MATERIAL='CHIP',
 VALUE='33.2',
 PRIM_FILE='./archive_libs/logical/q_res/chips/chips.prt';

PART_NAME
 R4615 'Q_RES_0402LF-0,5%,1/16W,EMPTY,A':;

SECTION_NUMBER 1
 '@S9S_MB_2U_LIB.S9S_MB_2U(SCH_1):PAGE132_I96@PURE_QUANTA.Q_RES(CHIPS)':
 C_PATH='@s9s_mb_2u_lib.s9s_mb_2u(sch_1):page132_i96@pure_quanta.q_res(chips)',
 P_PATH='@s9s_mb_2u_lib.s9s_mb_2u(sch_1):page164_i96@pure_quanta.q_res(chips)',
 PATH='I96',
 DRAWING='@S9S_MB_2U_LIB.S9S_MB_2U(SCH_1):PAGE132',
 PHYS_PAGE='164',
 XY='(-2225,1425)',
 ROT='0',
 VER='1',
 PACK_TYPE='0402LF',
 CDS_LIB='pure_quanta',
 CDS_PART_NAME='Q_RES_0402LF-0,5%,1/16W,EMPTY,A',
 WATTAGE='1/16W',
 TOLERANCE='5%',
 MATERIAL='EMPTY',
 VALUE='0',
 PRIM_FILE='./archive_libs/logical/q_res/chips/chips.prt';

PART_NAME
 R4616 'Q_RES_0402LF-33.2,1%,1/16W,CHIA':;

SECTION_NUMBER 1
 '@S9S_MB_2U_LIB.S9S_MB_2U(SCH_1):PAGE132_I100@PURE_QUANTA.Q_RES(CHIPS)':
 C_PATH='@s9s_mb_2u_lib.s9s_mb_2u(sch_1):page132_i100@pure_quanta.q_res(chips)',
 P_PATH='@s9s_mb_2u_lib.s9s_mb_2u(sch_1):page164_i100@pure_quanta.q_res(chips)',
 PATH='I100',
 DRAWING='@S9S_MB_2U_LIB.S9S_MB_2U(SCH_1):PAGE132',
 PHYS_PAGE='164',
 XY='(-2200,1100)',
 ROT='0',
 VER='1',
 PACK_TYPE='0402LF',
 LOCATION='R4616',
 CDS_LIB='pure_quanta',
 CDS_PART_NAME='Q_RES_0402LF-33.2,1%,1/16W,CHIA',
 WATTAGE='1/16W',
 TOLERANCE='1%',
 MATERIAL='CHIP',
 VALUE='33.2',
 PRIM_FILE='./archive_libs/logical/q_res/chips/chips.prt';

PART_NAME
 R4617 'Q_RES_0402LF-33.2,1%,1/16W,CHIA':;

SECTION_NUMBER 1
 '@S9S_MB_2U_LIB.S9S_MB_2U(SCH_1):PAGE132_I99@PURE_QUANTA.Q_RES(CHIPS)':
 C_PATH='@s9s_mb_2u_lib.s9s_mb_2u(sch_1):page132_i99@pure_quanta.q_res(chips)',
 P_PATH='@s9s_mb_2u_lib.s9s_mb_2u(sch_1):page164_i99@pure_quanta.q_res(chips)',
 PATH='I99',
 DRAWING='@S9S_MB_2U_LIB.S9S_MB_2U(SCH_1):PAGE132',
 PHYS_PAGE='164',
 XY='(775,950)',
 ROT='0',
 VER='1',
 PACK_TYPE='0402LF',
 CDS_LIB='pure_quanta',
 CDS_PART_NAME='Q_RES_0402LF-33.2,1%,1/16W,CHIA',
 WATTAGE='1/16W',
 TOLERANCE='1%',
 MATERIAL='CHIP',
 VALUE='33.2',
 PRIM_FILE='./archive_libs/logical/q_res/chips/chips.prt';

PART_NAME
 R4618 'Q_RES_0402LF-33.2,1%,1/16W,CHIA':;

SECTION_NUMBER 1
 '@S9S_MB_2U_LIB.S9S_MB_2U(SCH_1):PAGE154_I237@PURE_QUANTA.Q_RES(CHIPS)':
 C_PATH='@s9s_mb_2u_lib.s9s_mb_2u(sch_1):page154_i237@pure_quanta.q_res(chips)',
 P_PATH='@s9s_mb_2u_lib.s9s_mb_2u(sch_1):page158_i237@pure_quanta.q_res(chips)',
 PATH='I237',
 DRAWING='@S9S_MB_2U_LIB.S9S_MB_2U(SCH_1):PAGE154',
 PHYS_PAGE='158',
 XY='(1075,7075)',
 ROT='0',
 VER='1',
 PACK_TYPE='0402LF',
 CDS_LIB='pure_quanta',
 CDS_PART_NAME='Q_RES_0402LF-33.2,1%,1/16W,CHIA',
 WATTAGE='1/16W',
 TOLERANCE='1%',
 MATERIAL='CHIP',
 VALUE='33.2',
 PRIM_FILE='./archive_libs/logical/q_res/chips/chips.prt';

PART_NAME
 R4620 'Q_RES_0402LF-4.7K,5%,1/16W,CHIA':;

SECTION_NUMBER 1
 '@S9S_MB_2U_LIB.S9S_MB_2U(SCH_1):PAGE326_I45@PURE_QUANTA.Q_RES(CHIPS)':
 C_PATH='@s9s_mb_2u_lib.s9s_mb_2u(sch_1):page326_i45@pure_quanta.q_res(chips)',
 P_PATH='@s9s_mb_2u_lib.s9s_mb_2u(sch_1):page306_i45@pure_quanta.q_res(chips)',
 PATH='I45',
 DRAWING='@S9S_MB_2U_LIB.S9S_MB_2U(SCH_1):PAGE326',
 PHYS_PAGE='306',
 XY='(4050,450)',
 ROT='0',
 VER='2',
 PACK_TYPE='0402LF',
 CDS_LIB='pure_quanta',
 CDS_PART_NAME='Q_RES_0402LF-4.7K,5%,1/16W,CHIA',
 WATTAGE='1/16W',
 TOLERANCE='5%',
 MATERIAL='CHIP',
 VALUE='4.7K',
 PRIM_FILE='./archive_libs/logical/q_res/chips/chips.prt';

PART_NAME
 R4621 'Q_RES_0402LF-33.2,1%,1/16W,CHIA':;

SECTION_NUMBER 1
 '@S9S_MB_2U_LIB.S9S_MB_2U(SCH_1):PAGE321_I101@PURE_QUANTA.Q_RES(CHIPS)':
 C_PATH='@s9s_mb_2u_lib.s9s_mb_2u(sch_1):page321_i101@pure_quanta.q_res(chips)',
 P_PATH='@s9s_mb_2u_lib.s9s_mb_2u(sch_1):page226_i101@pure_quanta.q_res(chips)',
 PATH='I101',
 DRAWING='@S9S_MB_2U_LIB.S9S_MB_2U(SCH_1):PAGE321',
 PHYS_PAGE='226',
 XY='(1050,1200)',
 ROT='0',
 VER='1',
 PACK_TYPE='0402LF',
 CDS_LIB='pure_quanta',
 CDS_PART_NAME='Q_RES_0402LF-33.2,1%,1/16W,CHIA',
 WATTAGE='1/16W',
 TOLERANCE='1%',
 MATERIAL='CHIP',
 VALUE='33.2',
 PRIM_FILE='./archive_libs/logical/q_res/chips/chips.prt';

PART_NAME
 R4622 'Q_RES_0402LF-2K,1%,1/16W,CHIP,A':;

SECTION_NUMBER 1
 '@S9S_MB_2U_LIB.S9S_MB_2U(SCH_1):PAGE208_I66@PURE_QUANTA.Q_RES(CHIPS)':
 C_PATH='@s9s_mb_2u_lib.s9s_mb_2u(sch_1):page208_i66@pure_quanta.q_res(chips)',
 P_PATH='@s9s_mb_2u_lib.s9s_mb_2u(sch_1):page219_i66@pure_quanta.q_res(chips)',
 PATH='I66',
 DRAWING='@S9S_MB_2U_LIB.S9S_MB_2U(SCH_1):PAGE208',
 PHYS_PAGE='219',
 XY='(-300,2950)',
 ROT='0',
 VER='1',
 PACK_TYPE='0402LF',
 CDS_LIB='pure_quanta',
 CDS_PART_NAME='Q_RES_0402LF-2K,1%,1/16W,CHIP,A',
 WATTAGE='1/16W',
 TOLERANCE='1%',
 MATERIAL='CHIP',
 VALUE='2K',
 PRIM_FILE='./archive_libs/logical/q_res/chips/chips.prt';

PART_NAME
 R4623 'Q_RES_0402LF-1K,1%,1/16W,CHIP,A':;

SECTION_NUMBER 1
 '@S9S_MB_2U_LIB.S9S_MB_2U(SCH_1):PAGE235_I11@PURE_QUANTA.Q_RES(CHIPS)':
 C_PATH='@s9s_mb_2u_lib.s9s_mb_2u(sch_1):page235_i11@pure_quanta.q_res(chips)',
 P_PATH='@s9s_mb_2u_lib.s9s_mb_2u(sch_1):page248_i11@pure_quanta.q_res(chips)',
 PATH='I11',
 DRAWING='@S9S_MB_2U_LIB.S9S_MB_2U(SCH_1):PAGE235',
 PHYS_PAGE='248',
 XY='(-750,4850)',
 ROT='0',
 VER='2',
 PACK_TYPE='0402LF',
 CDS_LIB='pure_quanta',
 CDS_PART_NAME='Q_RES_0402LF-1K,1%,1/16W,CHIP,A',
 WATTAGE='1/16W',
 TOLERANCE='1%',
 MATERIAL='CHIP',
 VALUE='1K',
 PRIM_FILE='./archive_libs/logical/q_res/chips/chips.prt';

PART_NAME
 R4624 'Q_RES_0402LF-0,5%,1/16W,CHIP,CA':;

SECTION_NUMBER 1
 '@S9S_MB_2U_LIB.S9S_MB_2U(SCH_1):PAGE235_I14@PURE_QUANTA.Q_RES(CHIPS)':
 C_PATH='@s9s_mb_2u_lib.s9s_mb_2u(sch_1):page235_i14@pure_quanta.q_res(chips)',
 P_PATH='@s9s_mb_2u_lib.s9s_mb_2u(sch_1):page248_i14@pure_quanta.q_res(chips)',
 PATH='I14',
 DRAWING='@S9S_MB_2U_LIB.S9S_MB_2U(SCH_1):PAGE235',
 PHYS_PAGE='248',
 XY='(-500,5775)',
 ROT='0',
 VER='1',
 PACK_TYPE='0402LF',
 CDS_LIB='pure_quanta',
 CDS_PART_NAME='Q_RES_0402LF-0,5%,1/16W,CHIP,CA',
 WATTAGE='1/16W',
 TOLERANCE='5%',
 MATERIAL='CHIP',
 VALUE='0',
 PRIM_FILE='./archive_libs/logical/q_res/chips/chips.prt';

PART_NAME
 R4625 'Q_RES_0402LF-100,1%,1/16W,CHIPA':;

SECTION_NUMBER 1
 '@S9S_MB_2U_LIB.S9S_MB_2U(SCH_1):PAGE314_I140@PURE_QUANTA.Q_RES(CHIPS)':
 C_PATH='@s9s_mb_2u_lib.s9s_mb_2u(sch_1):page314_i140@pure_quanta.q_res(chips)',
 P_PATH='@s9s_mb_2u_lib.s9s_mb_2u(sch_1):page213_i140@pure_quanta.q_res(chips)',
 PATH='I140',
 DRAWING='@S9S_MB_2U_LIB.S9S_MB_2U(SCH_1):PAGE314',
 PHYS_PAGE='213',
 XY='(2725,950)',
 ROT='0',
 VER='1',
 PACK_TYPE='0402LF',
 CDS_LIB='pure_quanta',
 CDS_PART_NAME='Q_RES_0402LF-100,1%,1/16W,CHIPA',
 WATTAGE='1/16W',
 TOLERANCE='1%',
 MATERIAL='CHIP',
 VALUE='100',
 PRIM_FILE='./archive_libs/logical/q_res/chips/chips.prt';

PART_NAME
 R4626 'Q_RES_0402LF-0,5%,1/16W,CHIP,CA':;

SECTION_NUMBER 1
 '@S9S_MB_2U_LIB.S9S_MB_2U(SCH_1):PAGE235_I18@PURE_QUANTA.Q_RES(CHIPS)':
 C_PATH='@s9s_mb_2u_lib.s9s_mb_2u(sch_1):page235_i18@pure_quanta.q_res(chips)',
 P_PATH='@s9s_mb_2u_lib.s9s_mb_2u(sch_1):page248_i18@pure_quanta.q_res(chips)',
 PATH='I18',
 DRAWING='@S9S_MB_2U_LIB.S9S_MB_2U(SCH_1):PAGE235',
 PHYS_PAGE='248',
 XY='(-250,6675)',
 ROT='0',
 VER='1',
 PACK_TYPE='0402LF',
 CDS_LIB='pure_quanta',
 CDS_PART_NAME='Q_RES_0402LF-0,5%,1/16W,CHIP,CA',
 WATTAGE='1/16W',
 TOLERANCE='5%',
 MATERIAL='CHIP',
 VALUE='0',
 PRIM_FILE='./archive_libs/logical/q_res/chips/chips.prt';

PART_NAME
 R4627 'Q_RES_0402LF-0,5%,1/16W,CHIP,CA':;

SECTION_NUMBER 1
 '@S9S_MB_2U_LIB.S9S_MB_2U(SCH_1):PAGE235_I17@PURE_QUANTA.Q_RES(CHIPS)':
 C_PATH='@s9s_mb_2u_lib.s9s_mb_2u(sch_1):page235_i17@pure_quanta.q_res(chips)',
 P_PATH='@s9s_mb_2u_lib.s9s_mb_2u(sch_1):page248_i17@pure_quanta.q_res(chips)',
 PATH='I17',
 DRAWING='@S9S_MB_2U_LIB.S9S_MB_2U(SCH_1):PAGE235',
 PHYS_PAGE='248',
 XY='(-250,6525)',
 ROT='0',
 VER='1',
 PACK_TYPE='0402LF',
 CDS_LIB='pure_quanta',
 CDS_PART_NAME='Q_RES_0402LF-0,5%,1/16W,CHIP,CA',
 WATTAGE='1/16W',
 TOLERANCE='5%',
 MATERIAL='CHIP',
 VALUE='0',
 PRIM_FILE='./archive_libs/logical/q_res/chips/chips.prt';

PART_NAME
 R4628 'Q_RES_0402LF-0,5%,1/16W,CHIP,CA':;

SECTION_NUMBER 1
 '@S9S_MB_2U_LIB.S9S_MB_2U(SCH_1):PAGE235_I16@PURE_QUANTA.Q_RES(CHIPS)':
 C_PATH='@s9s_mb_2u_lib.s9s_mb_2u(sch_1):page235_i16@pure_quanta.q_res(chips)',
 P_PATH='@s9s_mb_2u_lib.s9s_mb_2u(sch_1):page248_i16@pure_quanta.q_res(chips)',
 PATH='I16',
 DRAWING='@S9S_MB_2U_LIB.S9S_MB_2U(SCH_1):PAGE235',
 PHYS_PAGE='248',
 XY='(-250,6375)',
 ROT='0',
 VER='1',
 PACK_TYPE='0402LF',
 CDS_LIB='pure_quanta',
 CDS_PART_NAME='Q_RES_0402LF-0,5%,1/16W,CHIP,CA',
 WATTAGE='1/16W',
 TOLERANCE='5%',
 MATERIAL='CHIP',
 VALUE='0',
 PRIM_FILE='./archive_libs/logical/q_res/chips/chips.prt';

PART_NAME
 R4629 'Q_RES_0402LF-0,5%,1/16W,CHIP,CA':;

SECTION_NUMBER 1
 '@S9S_MB_2U_LIB.S9S_MB_2U(SCH_1):PAGE235_I15@PURE_QUANTA.Q_RES(CHIPS)':
 C_PATH='@s9s_mb_2u_lib.s9s_mb_2u(sch_1):page235_i15@pure_quanta.q_res(chips)',
 P_PATH='@s9s_mb_2u_lib.s9s_mb_2u(sch_1):page248_i15@pure_quanta.q_res(chips)',
 PATH='I15',
 DRAWING='@S9S_MB_2U_LIB.S9S_MB_2U(SCH_1):PAGE235',
 PHYS_PAGE='248',
 XY='(-250,6225)',
 ROT='0',
 VER='1',
 PACK_TYPE='0402LF',
 CDS_LIB='pure_quanta',
 CDS_PART_NAME='Q_RES_0402LF-0,5%,1/16W,CHIP,CA',
 WATTAGE='1/16W',
 TOLERANCE='5%',
 MATERIAL='CHIP',
 VALUE='0',
 PRIM_FILE='./archive_libs/logical/q_res/chips/chips.prt';

PART_NAME
 R4630 'Q_RES_0402LF-0,5%,1/16W,CHIP,CA':;

SECTION_NUMBER 1
 '@S9S_MB_2U_LIB.S9S_MB_2U(SCH_1):PAGE235_I27@PURE_QUANTA.Q_RES(CHIPS)':
 C_PATH='@s9s_mb_2u_lib.s9s_mb_2u(sch_1):page235_i27@pure_quanta.q_res(chips)',
 P_PATH='@s9s_mb_2u_lib.s9s_mb_2u(sch_1):page248_i27@pure_quanta.q_res(chips)',
 PATH='I27',
 DRAWING='@S9S_MB_2U_LIB.S9S_MB_2U(SCH_1):PAGE235',
 PHYS_PAGE='248',
 XY='(3400,6675)',
 ROT='0',
 VER='1',
 PACK_TYPE='0402LF',
 CDS_LIB='pure_quanta',
 CDS_PART_NAME='Q_RES_0402LF-0,5%,1/16W,CHIP,CA',
 WATTAGE='1/16W',
 TOLERANCE='5%',
 MATERIAL='CHIP',
 VALUE='0',
 PRIM_FILE='./archive_libs/logical/q_res/chips/chips.prt';

PART_NAME
 R4631 'Q_RES_0402LF-0,5%,1/16W,CHIP,CA':;

SECTION_NUMBER 1
 '@S9S_MB_2U_LIB.S9S_MB_2U(SCH_1):PAGE235_I25@PURE_QUANTA.Q_RES(CHIPS)':
 C_PATH='@s9s_mb_2u_lib.s9s_mb_2u(sch_1):page235_i25@pure_quanta.q_res(chips)',
 P_PATH='@s9s_mb_2u_lib.s9s_mb_2u(sch_1):page248_i25@pure_quanta.q_res(chips)',
 PATH='I25',
 DRAWING='@S9S_MB_2U_LIB.S9S_MB_2U(SCH_1):PAGE235',
 PHYS_PAGE='248',
 XY='(3400,6525)',
 ROT='0',
 VER='1',
 PACK_TYPE='0402LF',
 CDS_LIB='pure_quanta',
 CDS_PART_NAME='Q_RES_0402LF-0,5%,1/16W,CHIP,CA',
 WATTAGE='1/16W',
 TOLERANCE='5%',
 MATERIAL='CHIP',
 VALUE='0',
 PRIM_FILE='./archive_libs/logical/q_res/chips/chips.prt';

PART_NAME
 R4632 'Q_RES_0402LF-0,5%,1/16W,CHIP,CA':;

SECTION_NUMBER 1
 '@S9S_MB_2U_LIB.S9S_MB_2U(SCH_1):PAGE235_I26@PURE_QUANTA.Q_RES(CHIPS)':
 C_PATH='@s9s_mb_2u_lib.s9s_mb_2u(sch_1):page235_i26@pure_quanta.q_res(chips)',
 P_PATH='@s9s_mb_2u_lib.s9s_mb_2u(sch_1):page248_i26@pure_quanta.q_res(chips)',
 PATH='I26',
 DRAWING='@S9S_MB_2U_LIB.S9S_MB_2U(SCH_1):PAGE235',
 PHYS_PAGE='248',
 XY='(3400,6375)',
 ROT='0',
 VER='1',
 PACK_TYPE='0402LF',
 CDS_LIB='pure_quanta',
 CDS_PART_NAME='Q_RES_0402LF-0,5%,1/16W,CHIP,CA',
 WATTAGE='1/16W',
 TOLERANCE='5%',
 MATERIAL='CHIP',
 VALUE='0',
 PRIM_FILE='./archive_libs/logical/q_res/chips/chips.prt';

PART_NAME
 R4633 'Q_RES_0402LF-0,5%,1/16W,CHIP,CA':;

SECTION_NUMBER 1
 '@S9S_MB_2U_LIB.S9S_MB_2U(SCH_1):PAGE235_I24@PURE_QUANTA.Q_RES(CHIPS)':
 C_PATH='@s9s_mb_2u_lib.s9s_mb_2u(sch_1):page235_i24@pure_quanta.q_res(chips)',
 P_PATH='@s9s_mb_2u_lib.s9s_mb_2u(sch_1):page248_i24@pure_quanta.q_res(chips)',
 PATH='I24',
 DRAWING='@S9S_MB_2U_LIB.S9S_MB_2U(SCH_1):PAGE235',
 PHYS_PAGE='248',
 XY='(3400,6225)',
 ROT='0',
 VER='1',
 PACK_TYPE='0402LF',
 CDS_LIB='pure_quanta',
 CDS_PART_NAME='Q_RES_0402LF-0,5%,1/16W,CHIP,CA',
 WATTAGE='1/16W',
 TOLERANCE='5%',
 MATERIAL='CHIP',
 VALUE='0',
 PRIM_FILE='./archive_libs/logical/q_res/chips/chips.prt';

PART_NAME
 R4634 'Q_RES_0402LF-1K,1%,1/16W,EMPTYA':;

SECTION_NUMBER 1
 '@S9S_MB_2U_LIB.S9S_MB_2U(SCH_1):PAGE235_I4@PURE_QUANTA.Q_RES(CHIPS)':
 C_PATH='@s9s_mb_2u_lib.s9s_mb_2u(sch_1):page235_i4@pure_quanta.q_res(chips)',
 P_PATH='@s9s_mb_2u_lib.s9s_mb_2u(sch_1):page248_i4@pure_quanta.q_res(chips)',
 PATH='I4',
 DRAWING='@S9S_MB_2U_LIB.S9S_MB_2U(SCH_1):PAGE235',
 PHYS_PAGE='248',
 XY='(-2250,6000)',
 ROT='0',
 VER='2',
 PACK_TYPE='0402LF',
 CDS_LIB='pure_quanta',
 CDS_PART_NAME='Q_RES_0402LF-1K,1%,1/16W,EMPTYA',
 WATTAGE='1/16W',
 TOLERANCE='1%',
 MATERIAL='EMPTY',
 VALUE='1K',
 PRIM_FILE='./archive_libs/logical/q_res/chips/chips.prt';

PART_NAME
 R4635 'Q_RES_0402LF-10K,1%,1/16W,CHIPA':;

SECTION_NUMBER 1
 '@S9S_MB_2U_LIB.S9S_MB_2U(SCH_1):PAGE235_I3@PURE_QUANTA.Q_RES(CHIPS)':
 C_PATH='@s9s_mb_2u_lib.s9s_mb_2u(sch_1):page235_i3@pure_quanta.q_res(chips)',
 P_PATH='@s9s_mb_2u_lib.s9s_mb_2u(sch_1):page248_i3@pure_quanta.q_res(chips)',
 PATH='I3',
 DRAWING='@S9S_MB_2U_LIB.S9S_MB_2U(SCH_1):PAGE235',
 PHYS_PAGE='248',
 XY='(-2225,5475)',
 ROT='0',
 VER='2',
 PACK_TYPE='0402LF',
 CDS_LIB='pure_quanta',
 CDS_PART_NAME='Q_RES_0402LF-10K,1%,1/16W,CHIPA',
 WATTAGE='1/16W',
 TOLERANCE='1%',
 MATERIAL='CHIP',
 VALUE='10K',
 PRIM_FILE='./archive_libs/logical/q_res/chips/chips.prt';

PART_NAME
 R4636 'Q_RES_0402LF-200K,1%,1/16W,CHIA':;

SECTION_NUMBER 1
 '@S9S_MB_2U_LIB.S9S_MB_2U(SCH_1):PAGE162_I23@PURE_QUANTA.Q_RES(CHIPS)':
 C_PATH='@s9s_mb_2u_lib.s9s_mb_2u(sch_1):page162_i23@pure_quanta.q_res(chips)',
 P_PATH='@s9s_mb_2u_lib.s9s_mb_2u(sch_1):page169_i23@pure_quanta.q_res(chips)',
 PATH='I23',
 DRAWING='@S9S_MB_2U_LIB.S9S_MB_2U(SCH_1):PAGE162',
 PHYS_PAGE='169',
 XY='(-4250,2900)',
 ROT='0',
 VER='2',
 PACK_TYPE='0402LF',
 CDS_LIB='pure_quanta',
 CDS_PART_NAME='Q_RES_0402LF-200K,1%,1/16W,CHIA',
 WATTAGE='1/16W',
 TOLERANCE='1%',
 MATERIAL='CHIP',
 VALUE='200K',
 PRIM_FILE='./archive_libs/logical/q_res/chips/chips.prt';

PART_NAME
 R4637 'Q_RES_0402LF-200K,1%,1/16W,CHIA':;

SECTION_NUMBER 1
 '@S9S_MB_2U_LIB.S9S_MB_2U(SCH_1):PAGE162_I24@PURE_QUANTA.Q_RES(CHIPS)':
 C_PATH='@s9s_mb_2u_lib.s9s_mb_2u(sch_1):page162_i24@pure_quanta.q_res(chips)',
 P_PATH='@s9s_mb_2u_lib.s9s_mb_2u(sch_1):page169_i24@pure_quanta.q_res(chips)',
 PATH='I24',
 DRAWING='@S9S_MB_2U_LIB.S9S_MB_2U(SCH_1):PAGE162',
 PHYS_PAGE='169',
 XY='(-3850,2900)',
 ROT='0',
 VER='2',
 PACK_TYPE='0402LF',
 CDS_LIB='pure_quanta',
 CDS_PART_NAME='Q_RES_0402LF-200K,1%,1/16W,CHIA',
 WATTAGE='1/16W',
 TOLERANCE='1%',
 MATERIAL='CHIP',
 VALUE='200K',
 PRIM_FILE='./archive_libs/logical/q_res/chips/chips.prt';

PART_NAME
 R4638 'Q_RES_1206LF-243,1%,1/4W,CHIP,A':;

SECTION_NUMBER 1
 '@S9S_MB_2U_LIB.S9S_MB_2U(SCH_1):PAGE246_I77@PURE_QUANTA.Q_RES(CHIPS)':
 C_PATH='@s9s_mb_2u_lib.s9s_mb_2u(sch_1):page246_i77@pure_quanta.q_res(chips)',
 P_PATH='@s9s_mb_2u_lib.s9s_mb_2u(sch_1):page260_i77@pure_quanta.q_res(chips)',
 PATH='I77',
 DRAWING='@S9S_MB_2U_LIB.S9S_MB_2U(SCH_1):PAGE246',
 PHYS_PAGE='260',
 XY='(-2350,7225)',
 ROT='0',
 VER='2',
 PACK_TYPE='1206LF',
 LOCATION='R4638',
 CDS_LIB='pure_quanta',
 CDS_PART_NAME='Q_RES_1206LF-243,1%,1/4W,CHIP,A',
 WATTAGE='1/4W',
 TOLERANCE='1%',
 MATERIAL='CHIP',
 VALUE='243',
 PRIM_FILE='./archive_libs/logical/q_res/chips/chips.prt';

PART_NAME
 R4639 'Q_RES_1206LF-243,1%,1/4W,CHIP,A':;

SECTION_NUMBER 1
 '@S9S_MB_2U_LIB.S9S_MB_2U(SCH_1):PAGE246_I78@PURE_QUANTA.Q_RES(CHIPS)':
 C_PATH='@s9s_mb_2u_lib.s9s_mb_2u(sch_1):page246_i78@pure_quanta.q_res(chips)',
 P_PATH='@s9s_mb_2u_lib.s9s_mb_2u(sch_1):page260_i78@pure_quanta.q_res(chips)',
 PATH='I78',
 DRAWING='@S9S_MB_2U_LIB.S9S_MB_2U(SCH_1):PAGE246',
 PHYS_PAGE='260',
 XY='(-1800,7225)',
 ROT='0',
 VER='2',
 PACK_TYPE='1206LF',
 LOCATION='R4639',
 CDS_LIB='pure_quanta',
 CDS_PART_NAME='Q_RES_1206LF-243,1%,1/4W,CHIP,A',
 WATTAGE='1/4W',
 TOLERANCE='1%',
 MATERIAL='CHIP',
 VALUE='243',
 PRIM_FILE='./archive_libs/logical/q_res/chips/chips.prt';

PART_NAME
 R4640 'Q_RES_1206LF-243,1%,1/4W,CHIP,A':;

SECTION_NUMBER 1
 '@S9S_MB_2U_LIB.S9S_MB_2U(SCH_1):PAGE246_I79@PURE_QUANTA.Q_RES(CHIPS)':
 C_PATH='@s9s_mb_2u_lib.s9s_mb_2u(sch_1):page246_i79@pure_quanta.q_res(chips)',
 P_PATH='@s9s_mb_2u_lib.s9s_mb_2u(sch_1):page260_i79@pure_quanta.q_res(chips)',
 PATH='I79',
 DRAWING='@S9S_MB_2U_LIB.S9S_MB_2U(SCH_1):PAGE246',
 PHYS_PAGE='260',
 XY='(-1275,7225)',
 ROT='0',
 VER='2',
 PACK_TYPE='1206LF',
 LOCATION='R4640',
 CDS_LIB='pure_quanta',
 CDS_PART_NAME='Q_RES_1206LF-243,1%,1/4W,CHIP,A',
 WATTAGE='1/4W',
 TOLERANCE='1%',
 MATERIAL='CHIP',
 VALUE='243',
 PRIM_FILE='./archive_libs/logical/q_res/chips/chips.prt';

PART_NAME
 R4641 'Q_RES_1206LF-243,1%,1/4W,CHIP,A':;

SECTION_NUMBER 1
 '@S9S_MB_2U_LIB.S9S_MB_2U(SCH_1):PAGE246_I80@PURE_QUANTA.Q_RES(CHIPS)':
 C_PATH='@s9s_mb_2u_lib.s9s_mb_2u(sch_1):page246_i80@pure_quanta.q_res(chips)',
 P_PATH='@s9s_mb_2u_lib.s9s_mb_2u(sch_1):page260_i80@pure_quanta.q_res(chips)',
 PATH='I80',
 DRAWING='@S9S_MB_2U_LIB.S9S_MB_2U(SCH_1):PAGE246',
 PHYS_PAGE='260',
 XY='(-750,7225)',
 ROT='0',
 VER='2',
 PACK_TYPE='1206LF',
 LOCATION='R4641',
 CDS_LIB='pure_quanta',
 CDS_PART_NAME='Q_RES_1206LF-243,1%,1/4W,CHIP,A',
 WATTAGE='1/4W',
 TOLERANCE='1%',
 MATERIAL='CHIP',
 VALUE='243',
 PRIM_FILE='./archive_libs/logical/q_res/chips/chips.prt';

PART_NAME
 R4642 'Q_RES_0402LF-1K,1%,1/16W,EMPTYA':;

SECTION_NUMBER 1
 '@S9S_MB_2U_LIB.S9S_MB_2U(SCH_1):PAGE159_I7@PURE_QUANTA.Q_RES(CHIPS)':
 C_PATH='@s9s_mb_2u_lib.s9s_mb_2u(sch_1):page159_i7@pure_quanta.q_res(chips)',
 P_PATH='@s9s_mb_2u_lib.s9s_mb_2u(sch_1):page167_i7@pure_quanta.q_res(chips)',
 PATH='I7',
 DRAWING='@S9S_MB_2U_LIB.S9S_MB_2U(SCH_1):PAGE159',
 PHYS_PAGE='167',
 XY='(-1550,-1925)',
 ROT='0',
 VER='2',
 PACK_TYPE='0402LF',
 CDS_LIB='pure_quanta',
 CDS_PART_NAME='Q_RES_0402LF-1K,1%,1/16W,EMPTYA',
 WATTAGE='1/16W',
 TOLERANCE='1%',
 MATERIAL='EMPTY',
 VALUE='1K',
 PRIM_FILE='./archive_libs/logical/q_res/chips/chips.prt';

PART_NAME
 R4643 'Q_RES_0402LF-1K,1%,1/16W,EMPTYA':;

SECTION_NUMBER 1
 '@S9S_MB_2U_LIB.S9S_MB_2U(SCH_1):PAGE159_I13@PURE_QUANTA.Q_RES(CHIPS)':
 C_PATH='@s9s_mb_2u_lib.s9s_mb_2u(sch_1):page159_i13@pure_quanta.q_res(chips)',
 P_PATH='@s9s_mb_2u_lib.s9s_mb_2u(sch_1):page167_i13@pure_quanta.q_res(chips)',
 PATH='I13',
 DRAWING='@S9S_MB_2U_LIB.S9S_MB_2U(SCH_1):PAGE159',
 PHYS_PAGE='167',
 XY='(-1125,-1925)',
 ROT='0',
 VER='2',
 PACK_TYPE='0402LF',
 CDS_LIB='pure_quanta',
 CDS_PART_NAME='Q_RES_0402LF-1K,1%,1/16W,EMPTYA',
 WATTAGE='1/16W',
 TOLERANCE='1%',
 MATERIAL='EMPTY',
 VALUE='1K',
 PRIM_FILE='./archive_libs/logical/q_res/chips/chips.prt';

PART_NAME
 R4644 'Q_RES_0402LF-1K,1%,1/16W,EMPTYA':;

SECTION_NUMBER 1
 '@S9S_MB_2U_LIB.S9S_MB_2U(SCH_1):PAGE159_I11@PURE_QUANTA.Q_RES(CHIPS)':
 C_PATH='@s9s_mb_2u_lib.s9s_mb_2u(sch_1):page159_i11@pure_quanta.q_res(chips)',
 P_PATH='@s9s_mb_2u_lib.s9s_mb_2u(sch_1):page167_i11@pure_quanta.q_res(chips)',
 PATH='I11',
 DRAWING='@S9S_MB_2U_LIB.S9S_MB_2U(SCH_1):PAGE159',
 PHYS_PAGE='167',
 XY='(-1550,-450)',
 ROT='0',
 VER='2',
 PACK_TYPE='0402LF',
 CDS_LIB='pure_quanta',
 CDS_PART_NAME='Q_RES_0402LF-1K,1%,1/16W,EMPTYA',
 WATTAGE='1/16W',
 TOLERANCE='1%',
 MATERIAL='EMPTY',
 VALUE='1K',
 PRIM_FILE='./archive_libs/logical/q_res/chips/chips.prt';

PART_NAME
 R4645 'Q_RES_0402LF-1K,1%,1/16W,EMPTYA':;

SECTION_NUMBER 1
 '@S9S_MB_2U_LIB.S9S_MB_2U(SCH_1):PAGE159_I16@PURE_QUANTA.Q_RES(CHIPS)':
 C_PATH='@s9s_mb_2u_lib.s9s_mb_2u(sch_1):page159_i16@pure_quanta.q_res(chips)',
 P_PATH='@s9s_mb_2u_lib.s9s_mb_2u(sch_1):page167_i16@pure_quanta.q_res(chips)',
 PATH='I16',
 DRAWING='@S9S_MB_2U_LIB.S9S_MB_2U(SCH_1):PAGE159',
 PHYS_PAGE='167',
 XY='(-1125,-450)',
 ROT='0',
 VER='2',
 PACK_TYPE='0402LF',
 CDS_LIB='pure_quanta',
 CDS_PART_NAME='Q_RES_0402LF-1K,1%,1/16W,EMPTYA',
 WATTAGE='1/16W',
 TOLERANCE='1%',
 MATERIAL='EMPTY',
 VALUE='1K',
 PRIM_FILE='./archive_libs/logical/q_res/chips/chips.prt';

PART_NAME
 R4646 'Q_RES_0402LF-1K,1%,1/16W,EMPTYA':;

SECTION_NUMBER 1
 '@S9S_MB_2U_LIB.S9S_MB_2U(SCH_1):PAGE159_I15@PURE_QUANTA.Q_RES(CHIPS)':
 C_PATH='@s9s_mb_2u_lib.s9s_mb_2u(sch_1):page159_i15@pure_quanta.q_res(chips)',
 P_PATH='@s9s_mb_2u_lib.s9s_mb_2u(sch_1):page167_i15@pure_quanta.q_res(chips)',
 PATH='I15',
 DRAWING='@S9S_MB_2U_LIB.S9S_MB_2U(SCH_1):PAGE159',
 PHYS_PAGE='167',
 XY='(-1125,-1000)',
 ROT='0',
 VER='2',
 PACK_TYPE='0402LF',
 CDS_LIB='pure_quanta',
 CDS_PART_NAME='Q_RES_0402LF-1K,1%,1/16W,EMPTYA',
 WATTAGE='1/16W',
 TOLERANCE='1%',
 MATERIAL='EMPTY',
 VALUE='1K',
 PRIM_FILE='./archive_libs/logical/q_res/chips/chips.prt';

PART_NAME
 R4647 'Q_RES_0402LF-1K,1%,1/16W,CHIP,A':
 ROOM='PCIE REDRIVER1_BOM2';

SECTION_NUMBER 1
 '@S9S_MB_2U_LIB.S9S_MB_2U(SCH_1):PAGE159_I4@PURE_QUANTA.Q_RES(CHIPS)':
 C_PATH='@s9s_mb_2u_lib.s9s_mb_2u(sch_1):page159_i4@pure_quanta.q_res(chips)',
 P_PATH='@s9s_mb_2u_lib.s9s_mb_2u(sch_1):page167_i4@pure_quanta.q_res(chips)',
 PATH='I4',
 DRAWING='@S9S_MB_2U_LIB.S9S_MB_2U(SCH_1):PAGE159',
 PHYS_PAGE='167',
 XY='(-1125,-2475)',
 ROT='0',
 VER='2',
 PACK_TYPE='0402LF',
 CDS_LIB='pure_quanta',
 CDS_PART_NAME='Q_RES_0402LF-1K,1%,1/16W,CHIP,A',
 WATTAGE='1/16W',
 TOLERANCE='1%',
 MATERIAL='CHIP',
 ROOM='PCIE REDRIVER1_BOM2',
 VALUE='1K',
 PRIM_FILE='./archive_libs/logical/q_res/chips/chips.prt';

PART_NAME
 R4648 'Q_RES_0402LF-1K,1%,1/16W,EMPTYA':;

SECTION_NUMBER 1
 '@S9S_MB_2U_LIB.S9S_MB_2U(SCH_1):PAGE159_I72@PURE_QUANTA.Q_RES(CHIPS)':
 C_PATH='@s9s_mb_2u_lib.s9s_mb_2u(sch_1):page159_i72@pure_quanta.q_res(chips)',
 P_PATH='@s9s_mb_2u_lib.s9s_mb_2u(sch_1):page167_i72@pure_quanta.q_res(chips)',
 PATH='I72',
 DRAWING='@S9S_MB_2U_LIB.S9S_MB_2U(SCH_1):PAGE159',
 PHYS_PAGE='167',
 XY='(-50,-475)',
 ROT='0',
 VER='2',
 PACK_TYPE='0402LF',
 CDS_LIB='pure_quanta',
 CDS_PART_NAME='Q_RES_0402LF-1K,1%,1/16W,EMPTYA',
 WATTAGE='1/16W',
 TOLERANCE='1%',
 MATERIAL='EMPTY',
 VALUE='1K',
 PRIM_FILE='./archive_libs/logical/q_res/chips/chips.prt';

PART_NAME
 R4649 'Q_RES_0402LF-1K,1%,1/16W,EMPTYA':;

SECTION_NUMBER 1
 '@S9S_MB_2U_LIB.S9S_MB_2U(SCH_1):PAGE159_I74@PURE_QUANTA.Q_RES(CHIPS)':
 C_PATH='@s9s_mb_2u_lib.s9s_mb_2u(sch_1):page159_i74@pure_quanta.q_res(chips)',
 P_PATH='@s9s_mb_2u_lib.s9s_mb_2u(sch_1):page167_i74@pure_quanta.q_res(chips)',
 PATH='I74',
 DRAWING='@S9S_MB_2U_LIB.S9S_MB_2U(SCH_1):PAGE159',
 PHYS_PAGE='167',
 XY='(375,-475)',
 ROT='0',
 VER='2',
 PACK_TYPE='0402LF',
 CDS_LIB='pure_quanta',
 CDS_PART_NAME='Q_RES_0402LF-1K,1%,1/16W,EMPTYA',
 WATTAGE='1/16W',
 TOLERANCE='1%',
 MATERIAL='EMPTY',
 VALUE='1K',
 PRIM_FILE='./archive_libs/logical/q_res/chips/chips.prt';

PART_NAME
 R4650 'Q_RES_0402LF-1K,1%,1/16W,EMPTYA':;

SECTION_NUMBER 1
 '@S9S_MB_2U_LIB.S9S_MB_2U(SCH_1):PAGE159_I71@PURE_QUANTA.Q_RES(CHIPS)':
 C_PATH='@s9s_mb_2u_lib.s9s_mb_2u(sch_1):page159_i71@pure_quanta.q_res(chips)',
 P_PATH='@s9s_mb_2u_lib.s9s_mb_2u(sch_1):page167_i71@pure_quanta.q_res(chips)',
 PATH='I71',
 DRAWING='@S9S_MB_2U_LIB.S9S_MB_2U(SCH_1):PAGE159',
 PHYS_PAGE='167',
 XY='(375,-1025)',
 ROT='0',
 VER='2',
 PACK_TYPE='0402LF',
 CDS_LIB='pure_quanta',
 CDS_PART_NAME='Q_RES_0402LF-1K,1%,1/16W,EMPTYA',
 WATTAGE='1/16W',
 TOLERANCE='1%',
 MATERIAL='EMPTY',
 VALUE='1K',
 PRIM_FILE='./archive_libs/logical/q_res/chips/chips.prt';

PART_NAME
 R4651 'Q_RES_0402LF-0,5%,1/16W,CHIP,CA':
 ROOM='PCIE REDRIVER1_BOM2';

SECTION_NUMBER 1
 '@S9S_MB_2U_LIB.S9S_MB_2U(SCH_1):PAGE159_I102@PURE_QUANTA.Q_RES(CHIPS)':
 C_PATH='@s9s_mb_2u_lib.s9s_mb_2u(sch_1):page159_i102@pure_quanta.q_res(chips)',
 P_PATH='@s9s_mb_2u_lib.s9s_mb_2u(sch_1):page167_i102@pure_quanta.q_res(chips)',
 PATH='I102',
 DRAWING='@S9S_MB_2U_LIB.S9S_MB_2U(SCH_1):PAGE159',
 PHYS_PAGE='167',
 XY='(2825,1450)',
 ROT='0',
 VER='1',
 PACK_TYPE='0402LF',
 CDS_LIB='pure_quanta',
 CDS_PART_NAME='Q_RES_0402LF-0,5%,1/16W,CHIP,CA',
 WATTAGE='1/16W',
 TOLERANCE='5%',
 MATERIAL='CHIP',
 ROOM='PCIE REDRIVER1_BOM2',
 VALUE='0',
 PRIM_FILE='./archive_libs/logical/q_res/chips/chips.prt';

PART_NAME
 R4652 'Q_RES_0402LF-0,5%,1/16W,EMPTY,A':;

SECTION_NUMBER 1
 '@S9S_MB_2U_LIB.S9S_MB_2U(SCH_1):PAGE326_I48@PURE_QUANTA.Q_RES(CHIPS)':
 C_PATH='@s9s_mb_2u_lib.s9s_mb_2u(sch_1):page326_i48@pure_quanta.q_res(chips)',
 P_PATH='@s9s_mb_2u_lib.s9s_mb_2u(sch_1):page306_i48@pure_quanta.q_res(chips)',
 PATH='I48',
 DRAWING='@S9S_MB_2U_LIB.S9S_MB_2U(SCH_1):PAGE326',
 PHYS_PAGE='306',
 XY='(3575,3975)',
 ROT='0',
 VER='2',
 PACK_TYPE='0402LF',
 LOCATION='R4652',
 CDS_LIB='pure_quanta',
 CDS_PART_NAME='Q_RES_0402LF-0,5%,1/16W,EMPTY,A',
 WATTAGE='1/16W',
 TOLERANCE='5%',
 MATERIAL='EMPTY',
 VALUE='0',
 PRIM_FILE='./archive_libs/logical/q_res/chips/chips.prt';

PART_NAME
 R4653 'Q_RES_0402LF-1K,1%,1/16W,CHIP,A':
 ROOM='PCIE REDRIVER1_BOM2';

SECTION_NUMBER 1
 '@S9S_MB_2U_LIB.S9S_MB_2U(SCH_1):PAGE159_I2@PURE_QUANTA.Q_RES(CHIPS)':
 C_PATH='@s9s_mb_2u_lib.s9s_mb_2u(sch_1):page159_i2@pure_quanta.q_res(chips)',
 P_PATH='@s9s_mb_2u_lib.s9s_mb_2u(sch_1):page167_i2@pure_quanta.q_res(chips)',
 PATH='I2',
 DRAWING='@S9S_MB_2U_LIB.S9S_MB_2U(SCH_1):PAGE159',
 PHYS_PAGE='167',
 XY='(-1550,-2475)',
 ROT='0',
 VER='2',
 PACK_TYPE='0402LF',
 CDS_LIB='pure_quanta',
 CDS_PART_NAME='Q_RES_0402LF-1K,1%,1/16W,CHIP,A',
 WATTAGE='1/16W',
 TOLERANCE='1%',
 MATERIAL='CHIP',
 ROOM='PCIE REDRIVER1_BOM2',
 VALUE='1K',
 PRIM_FILE='./archive_libs/logical/q_res/chips/chips.prt';

PART_NAME
 R4654 'Q_RES_0402LF-1K,1%,1/16W,CHIP,A':
 ROOM='PCIE REDRIVER1_BOM2';

SECTION_NUMBER 1
 '@S9S_MB_2U_LIB.S9S_MB_2U(SCH_1):PAGE159_I67@PURE_QUANTA.Q_RES(CHIPS)':
 C_PATH='@s9s_mb_2u_lib.s9s_mb_2u(sch_1):page159_i67@pure_quanta.q_res(chips)',
 P_PATH='@s9s_mb_2u_lib.s9s_mb_2u(sch_1):page167_i67@pure_quanta.q_res(chips)',
 PATH='I67',
 DRAWING='@S9S_MB_2U_LIB.S9S_MB_2U(SCH_1):PAGE159',
 PHYS_PAGE='167',
 XY='(-50,-1025)',
 ROT='0',
 VER='2',
 PACK_TYPE='0402LF',
 CDS_LIB='pure_quanta',
 CDS_PART_NAME='Q_RES_0402LF-1K,1%,1/16W,CHIP,A',
 WATTAGE='1/16W',
 TOLERANCE='1%',
 MATERIAL='CHIP',
 ROOM='PCIE REDRIVER1_BOM2',
 VALUE='1K',
 PRIM_FILE='./archive_libs/logical/q_res/chips/chips.prt';

PART_NAME
 R4655 'Q_RES_0402LF-1K,1%,1/16W,EMPTYA':;

SECTION_NUMBER 1
 '@S9S_MB_2U_LIB.S9S_MB_2U(SCH_1):PAGE159_I62@PURE_QUANTA.Q_RES(CHIPS)':
 C_PATH='@s9s_mb_2u_lib.s9s_mb_2u(sch_1):page159_i62@pure_quanta.q_res(chips)',
 P_PATH='@s9s_mb_2u_lib.s9s_mb_2u(sch_1):page167_i62@pure_quanta.q_res(chips)',
 PATH='I62',
 DRAWING='@S9S_MB_2U_LIB.S9S_MB_2U(SCH_1):PAGE159',
 PHYS_PAGE='167',
 XY='(375,-2125)',
 ROT='0',
 VER='2',
 PACK_TYPE='0402LF',
 CDS_LIB='pure_quanta',
 CDS_PART_NAME='Q_RES_0402LF-1K,1%,1/16W,EMPTYA',
 WATTAGE='1/16W',
 TOLERANCE='1%',
 MATERIAL='EMPTY',
 VALUE='1K',
 PRIM_FILE='./archive_libs/logical/q_res/chips/chips.prt';

PART_NAME
 R4656 'Q_RES_0402LF-1K,1%,1/16W,CHIP,A':
 ROOM='PCIE REDRIVER1_BOM2';

SECTION_NUMBER 1
 '@S9S_MB_2U_LIB.S9S_MB_2U(SCH_1):PAGE159_I66@PURE_QUANTA.Q_RES(CHIPS)':
 C_PATH='@s9s_mb_2u_lib.s9s_mb_2u(sch_1):page159_i66@pure_quanta.q_res(chips)',
 P_PATH='@s9s_mb_2u_lib.s9s_mb_2u(sch_1):page167_i66@pure_quanta.q_res(chips)',
 PATH='I66',
 DRAWING='@S9S_MB_2U_LIB.S9S_MB_2U(SCH_1):PAGE159',
 PHYS_PAGE='167',
 XY='(1575,-2150)',
 ROT='0',
 VER='2',
 PACK_TYPE='0402LF',
 CDS_LIB='pure_quanta',
 CDS_PART_NAME='Q_RES_0402LF-1K,1%,1/16W,CHIP,A',
 WATTAGE='1/16W',
 TOLERANCE='1%',
 MATERIAL='CHIP',
 ROOM='PCIE REDRIVER1_BOM2',
 VALUE='1K',
 PRIM_FILE='./archive_libs/logical/q_res/chips/chips.prt';

PART_NAME
 R4657 'Q_RES_0402LF-1K,1%,1/16W,EMPTYA':;

SECTION_NUMBER 1
 '@S9S_MB_2U_LIB.S9S_MB_2U(SCH_1):PAGE159_I65@PURE_QUANTA.Q_RES(CHIPS)':
 C_PATH='@s9s_mb_2u_lib.s9s_mb_2u(sch_1):page159_i65@pure_quanta.q_res(chips)',
 P_PATH='@s9s_mb_2u_lib.s9s_mb_2u(sch_1):page167_i65@pure_quanta.q_res(chips)',
 PATH='I65',
 DRAWING='@S9S_MB_2U_LIB.S9S_MB_2U(SCH_1):PAGE159',
 PHYS_PAGE='167',
 XY='(1575,-2675)',
 ROT='0',
 VER='2',
 PACK_TYPE='0402LF',
 CDS_LIB='pure_quanta',
 CDS_PART_NAME='Q_RES_0402LF-1K,1%,1/16W,EMPTYA',
 WATTAGE='1/16W',
 TOLERANCE='1%',
 MATERIAL='EMPTY',
 VALUE='1K',
 PRIM_FILE='./archive_libs/logical/q_res/chips/chips.prt';

PART_NAME
 R4658 'Q_RES_0402LF-1K,1%,1/16W,EMPTYA':;

SECTION_NUMBER 1
 '@S9S_MB_2U_LIB.S9S_MB_2U(SCH_1):PAGE159_I80@PURE_QUANTA.Q_RES(CHIPS)':
 C_PATH='@s9s_mb_2u_lib.s9s_mb_2u(sch_1):page159_i80@pure_quanta.q_res(chips)',
 P_PATH='@s9s_mb_2u_lib.s9s_mb_2u(sch_1):page167_i80@pure_quanta.q_res(chips)',
 PATH='I80',
 DRAWING='@S9S_MB_2U_LIB.S9S_MB_2U(SCH_1):PAGE159',
 PHYS_PAGE='167',
 XY='(2750,-2650)',
 ROT='0',
 VER='2',
 PACK_TYPE='0402LF',
 CDS_LIB='pure_quanta',
 CDS_PART_NAME='Q_RES_0402LF-1K,1%,1/16W,EMPTYA',
 WATTAGE='1/16W',
 TOLERANCE='1%',
 MATERIAL='EMPTY',
 VALUE='1K',
 PRIM_FILE='./archive_libs/logical/q_res/chips/chips.prt';

PART_NAME
 R4659 'Q_RES_0402LF-0,5%,1/16W,CHIP,CA':
 ROOM='PCIE REDRIVER1_BOM1';

SECTION_NUMBER 1
 '@S9S_MB_2U_LIB.S9S_MB_2U(SCH_1):PAGE159_I46@PURE_QUANTA.Q_RES(CHIPS)':
 C_PATH='@s9s_mb_2u_lib.s9s_mb_2u(sch_1):page159_i46@pure_quanta.q_res(chips)',
 P_PATH='@s9s_mb_2u_lib.s9s_mb_2u(sch_1):page167_i46@pure_quanta.q_res(chips)',
 PATH='I46',
 DRAWING='@S9S_MB_2U_LIB.S9S_MB_2U(SCH_1):PAGE159',
 PHYS_PAGE='167',
 XY='(-2725,2825)',
 ROT='0',
 VER='1',
 PACK_TYPE='0402LF',
 CDS_LIB='pure_quanta',
 CDS_PART_NAME='Q_RES_0402LF-0,5%,1/16W,CHIP,CA',
 WATTAGE='1/16W',
 TOLERANCE='5%',
 MATERIAL='CHIP',
 ROOM='PCIE REDRIVER1_BOM1',
 VALUE='0',
 PRIM_FILE='./archive_libs/logical/q_res/chips/chips.prt';

PART_NAME
 R4660 'Q_RES_0402LF-0,5%,1/16W,CHIP,CA':
 ROOM='PCIE REDRIVER1_BOM1';

SECTION_NUMBER 1
 '@S9S_MB_2U_LIB.S9S_MB_2U(SCH_1):PAGE159_I45@PURE_QUANTA.Q_RES(CHIPS)':
 C_PATH='@s9s_mb_2u_lib.s9s_mb_2u(sch_1):page159_i45@pure_quanta.q_res(chips)',
 P_PATH='@s9s_mb_2u_lib.s9s_mb_2u(sch_1):page167_i45@pure_quanta.q_res(chips)',
 PATH='I45',
 DRAWING='@S9S_MB_2U_LIB.S9S_MB_2U(SCH_1):PAGE159',
 PHYS_PAGE='167',
 XY='(-2725,2775)',
 ROT='0',
 VER='1',
 PACK_TYPE='0402LF',
 CDS_LIB='pure_quanta',
 CDS_PART_NAME='Q_RES_0402LF-0,5%,1/16W,CHIP,CA',
 WATTAGE='1/16W',
 TOLERANCE='5%',
 MATERIAL='CHIP',
 ROOM='PCIE REDRIVER1_BOM1',
 VALUE='0',
 PRIM_FILE='./archive_libs/logical/q_res/chips/chips.prt';

PART_NAME
 R4661 'Q_RES_0402LF-0,5%,1/16W,EMPTY,A':
 ROOM='PCIE REDRIVER1_BOM2';

SECTION_NUMBER 1
 '@S9S_MB_2U_LIB.S9S_MB_2U(SCH_1):PAGE159_I44@PURE_QUANTA.Q_RES(CHIPS)':
 C_PATH='@s9s_mb_2u_lib.s9s_mb_2u(sch_1):page159_i44@pure_quanta.q_res(chips)',
 P_PATH='@s9s_mb_2u_lib.s9s_mb_2u(sch_1):page167_i44@pure_quanta.q_res(chips)',
 PATH='I44',
 DRAWING='@S9S_MB_2U_LIB.S9S_MB_2U(SCH_1):PAGE159',
 PHYS_PAGE='167',
 XY='(-2725,2550)',
 ROT='0',
 VER='1',
 PACK_TYPE='0402LF',
 CDS_LIB='pure_quanta',
 CDS_PART_NAME='Q_RES_0402LF-0,5%,1/16W,EMPTY,A',
 WATTAGE='1/16W',
 TOLERANCE='5%',
 MATERIAL='EMPTY',
 ROOM='PCIE REDRIVER1_BOM2',
 VALUE='0',
 PRIM_FILE='./archive_libs/logical/q_res/chips/chips.prt';

PART_NAME
 R4662 'Q_RES_0402LF-0,5%,1/16W,EMPTY,A':
 ROOM='PCIE REDRIVER1_BOM2';

SECTION_NUMBER 1
 '@S9S_MB_2U_LIB.S9S_MB_2U(SCH_1):PAGE159_I43@PURE_QUANTA.Q_RES(CHIPS)':
 C_PATH='@s9s_mb_2u_lib.s9s_mb_2u(sch_1):page159_i43@pure_quanta.q_res(chips)',
 P_PATH='@s9s_mb_2u_lib.s9s_mb_2u(sch_1):page167_i43@pure_quanta.q_res(chips)',
 PATH='I43',
 DRAWING='@S9S_MB_2U_LIB.S9S_MB_2U(SCH_1):PAGE159',
 PHYS_PAGE='167',
 XY='(-2725,2500)',
 ROT='0',
 VER='1',
 PACK_TYPE='0402LF',
 CDS_LIB='pure_quanta',
 CDS_PART_NAME='Q_RES_0402LF-0,5%,1/16W,EMPTY,A',
 WATTAGE='1/16W',
 TOLERANCE='5%',
 MATERIAL='EMPTY',
 ROOM='PCIE REDRIVER1_BOM2',
 VALUE='0',
 PRIM_FILE='./archive_libs/logical/q_res/chips/chips.prt';

PART_NAME
 R4663 'Q_RES_0402LF-0,5%,1/16W,CHIP,CA':
 ROOM='PCIE REDRIVER1_BOM1';

SECTION_NUMBER 1
 '@S9S_MB_2U_LIB.S9S_MB_2U(SCH_1):PAGE159_I41@PURE_QUANTA.Q_RES(CHIPS)':
 C_PATH='@s9s_mb_2u_lib.s9s_mb_2u(sch_1):page159_i41@pure_quanta.q_res(chips)',
 P_PATH='@s9s_mb_2u_lib.s9s_mb_2u(sch_1):page167_i41@pure_quanta.q_res(chips)',
 PATH='I41',
 DRAWING='@S9S_MB_2U_LIB.S9S_MB_2U(SCH_1):PAGE159',
 PHYS_PAGE='167',
 XY='(-2725,2200)',
 ROT='0',
 VER='1',
 PACK_TYPE='0402LF',
 CDS_LIB='pure_quanta',
 CDS_PART_NAME='Q_RES_0402LF-0,5%,1/16W,CHIP,CA',
 WATTAGE='1/16W',
 TOLERANCE='5%',
 MATERIAL='CHIP',
 ROOM='PCIE REDRIVER1_BOM1',
 VALUE='0',
 PRIM_FILE='./archive_libs/logical/q_res/chips/chips.prt';

PART_NAME
 R4664 'Q_RES_0402LF-0,5%,1/16W,CHIP,CA':
 ROOM='PCIE REDRIVER1_BOM1';

SECTION_NUMBER 1
 '@S9S_MB_2U_LIB.S9S_MB_2U(SCH_1):PAGE159_I42@PURE_QUANTA.Q_RES(CHIPS)':
 C_PATH='@s9s_mb_2u_lib.s9s_mb_2u(sch_1):page159_i42@pure_quanta.q_res(chips)',
 P_PATH='@s9s_mb_2u_lib.s9s_mb_2u(sch_1):page167_i42@pure_quanta.q_res(chips)',
 PATH='I42',
 DRAWING='@S9S_MB_2U_LIB.S9S_MB_2U(SCH_1):PAGE159',
 PHYS_PAGE='167',
 XY='(-2725,2150)',
 ROT='0',
 VER='1',
 PACK_TYPE='0402LF',
 CDS_LIB='pure_quanta',
 CDS_PART_NAME='Q_RES_0402LF-0,5%,1/16W,CHIP,CA',
 WATTAGE='1/16W',
 TOLERANCE='5%',
 MATERIAL='CHIP',
 ROOM='PCIE REDRIVER1_BOM1',
 VALUE='0',
 PRIM_FILE='./archive_libs/logical/q_res/chips/chips.prt';

PART_NAME
 R4665 'Q_RES_0402LF-0,5%,1/16W,EMPTY,A':
 ROOM='PCIE REDRIVER1_BOM2';

SECTION_NUMBER 1
 '@S9S_MB_2U_LIB.S9S_MB_2U(SCH_1):PAGE159_I36@PURE_QUANTA.Q_RES(CHIPS)':
 C_PATH='@s9s_mb_2u_lib.s9s_mb_2u(sch_1):page159_i36@pure_quanta.q_res(chips)',
 P_PATH='@s9s_mb_2u_lib.s9s_mb_2u(sch_1):page167_i36@pure_quanta.q_res(chips)',
 PATH='I36',
 DRAWING='@S9S_MB_2U_LIB.S9S_MB_2U(SCH_1):PAGE159',
 PHYS_PAGE='167',
 XY='(-2725,1925)',
 ROT='0',
 VER='1',
 PACK_TYPE='0402LF',
 CDS_LIB='pure_quanta',
 CDS_PART_NAME='Q_RES_0402LF-0,5%,1/16W,EMPTY,A',
 WATTAGE='1/16W',
 TOLERANCE='5%',
 MATERIAL='EMPTY',
 ROOM='PCIE REDRIVER1_BOM2',
 VALUE='0',
 PRIM_FILE='./archive_libs/logical/q_res/chips/chips.prt';

PART_NAME
 R4666 'Q_RES_0402LF-0,5%,1/16W,EMPTY,A':
 ROOM='PCIE REDRIVER1_BOM2';

SECTION_NUMBER 1
 '@S9S_MB_2U_LIB.S9S_MB_2U(SCH_1):PAGE159_I35@PURE_QUANTA.Q_RES(CHIPS)':
 C_PATH='@s9s_mb_2u_lib.s9s_mb_2u(sch_1):page159_i35@pure_quanta.q_res(chips)',
 P_PATH='@s9s_mb_2u_lib.s9s_mb_2u(sch_1):page167_i35@pure_quanta.q_res(chips)',
 PATH='I35',
 DRAWING='@S9S_MB_2U_LIB.S9S_MB_2U(SCH_1):PAGE159',
 PHYS_PAGE='167',
 XY='(-2725,1875)',
 ROT='0',
 VER='1',
 PACK_TYPE='0402LF',
 CDS_LIB='pure_quanta',
 CDS_PART_NAME='Q_RES_0402LF-0,5%,1/16W,EMPTY,A',
 WATTAGE='1/16W',
 TOLERANCE='5%',
 MATERIAL='EMPTY',
 ROOM='PCIE REDRIVER1_BOM2',
 VALUE='0',
 PRIM_FILE='./archive_libs/logical/q_res/chips/chips.prt';

PART_NAME
 R4667 'Q_RES_0402LF-160K,1%,1/16W,EMPA':;

SECTION_NUMBER 1
 '@S9S_MB_2U_LIB.S9S_MB_2U(SCH_1):PAGE326_I14@PURE_QUANTA.Q_RES(CHIPS)':
 C_PATH='@s9s_mb_2u_lib.s9s_mb_2u(sch_1):page326_i14@pure_quanta.q_res(chips)',
 P_PATH='@s9s_mb_2u_lib.s9s_mb_2u(sch_1):page306_i14@pure_quanta.q_res(chips)',
 PATH='I14',
 DRAWING='@S9S_MB_2U_LIB.S9S_MB_2U(SCH_1):PAGE326',
 PHYS_PAGE='306',
 XY='(-1100,4050)',
 ROT='0',
 VER='2',
 PACK_TYPE='0402LF',
 CDS_LIB='pure_quanta',
 CDS_PART_NAME='Q_RES_0402LF-160K,1%,1/16W,EMPA',
 WATTAGE='1/16W',
 TOLERANCE='1%',
 MATERIAL='EMPTY',
 VALUE='160K',
 PRIM_FILE='./archive_libs/logical/q_res/chips/chips.prt';

PART_NAME
 R4668 'Q_RES_0402LF-10K,1%,1/16W,EMPTA':;

SECTION_NUMBER 1
 '@S9S_MB_2U_LIB.S9S_MB_2U(SCH_1):PAGE326_I13@PURE_QUANTA.Q_RES(CHIPS)':
 C_PATH='@s9s_mb_2u_lib.s9s_mb_2u(sch_1):page326_i13@pure_quanta.q_res(chips)',
 P_PATH='@s9s_mb_2u_lib.s9s_mb_2u(sch_1):page306_i13@pure_quanta.q_res(chips)',
 PATH='I13',
 DRAWING='@S9S_MB_2U_LIB.S9S_MB_2U(SCH_1):PAGE326',
 PHYS_PAGE='306',
 XY='(-1100,3450)',
 ROT='0',
 VER='2',
 PACK_TYPE='0402LF',
 CDS_LIB='pure_quanta',
 CDS_PART_NAME='Q_RES_0402LF-10K,1%,1/16W,EMPTA',
 WATTAGE='1/16W',
 TOLERANCE='1%',
 MATERIAL='EMPTY',
 VALUE='10K',
 PRIM_FILE='./archive_libs/logical/q_res/chips/chips.prt';

PART_NAME
 R4669 'Q_RES_0402LF-160K,1%,1/16W,EMPA':;

SECTION_NUMBER 1
 '@S9S_MB_2U_LIB.S9S_MB_2U(SCH_1):PAGE326_I25@PURE_QUANTA.Q_RES(CHIPS)':
 C_PATH='@s9s_mb_2u_lib.s9s_mb_2u(sch_1):page326_i25@pure_quanta.q_res(chips)',
 P_PATH='@s9s_mb_2u_lib.s9s_mb_2u(sch_1):page306_i25@pure_quanta.q_res(chips)',
 PATH='I25',
 DRAWING='@S9S_MB_2U_LIB.S9S_MB_2U(SCH_1):PAGE326',
 PHYS_PAGE='306',
 XY='(-550,4050)',
 ROT='0',
 VER='2',
 PACK_TYPE='0402LF',
 CDS_LIB='pure_quanta',
 CDS_PART_NAME='Q_RES_0402LF-160K,1%,1/16W,EMPA',
 WATTAGE='1/16W',
 TOLERANCE='1%',
 MATERIAL='EMPTY',
 VALUE='160K',
 PRIM_FILE='./archive_libs/logical/q_res/chips/chips.prt';

PART_NAME
 R4670 'Q_RES_0402LF-10K,1%,1/16W,EMPTA':;

SECTION_NUMBER 1
 '@S9S_MB_2U_LIB.S9S_MB_2U(SCH_1):PAGE326_I24@PURE_QUANTA.Q_RES(CHIPS)':
 C_PATH='@s9s_mb_2u_lib.s9s_mb_2u(sch_1):page326_i24@pure_quanta.q_res(chips)',
 P_PATH='@s9s_mb_2u_lib.s9s_mb_2u(sch_1):page306_i24@pure_quanta.q_res(chips)',
 PATH='I24',
 DRAWING='@S9S_MB_2U_LIB.S9S_MB_2U(SCH_1):PAGE326',
 PHYS_PAGE='306',
 XY='(-550,3450)',
 ROT='0',
 VER='2',
 PACK_TYPE='0402LF',
 CDS_LIB='pure_quanta',
 CDS_PART_NAME='Q_RES_0402LF-10K,1%,1/16W,EMPTA',
 WATTAGE='1/16W',
 TOLERANCE='1%',
 MATERIAL='EMPTY',
 VALUE='10K',
 PRIM_FILE='./archive_libs/logical/q_res/chips/chips.prt';

PART_NAME
 R4671 'Q_RES_0402LF-10K,1%,1/16W,EMPTA':;

SECTION_NUMBER 1
 '@S9S_MB_2U_LIB.S9S_MB_2U(SCH_1):PAGE326_I51@PURE_QUANTA.Q_RES(CHIPS)':
 C_PATH='@s9s_mb_2u_lib.s9s_mb_2u(sch_1):page326_i51@pure_quanta.q_res(chips)',
 P_PATH='@s9s_mb_2u_lib.s9s_mb_2u(sch_1):page306_i51@pure_quanta.q_res(chips)',
 PATH='I51',
 DRAWING='@S9S_MB_2U_LIB.S9S_MB_2U(SCH_1):PAGE326',
 PHYS_PAGE='306',
 XY='(1675,4125)',
 ROT='0',
 VER='2',
 PACK_TYPE='0402LF',
 CDS_LIB='pure_quanta',
 CDS_PART_NAME='Q_RES_0402LF-10K,1%,1/16W,EMPTA',
 WATTAGE='1/16W',
 TOLERANCE='1%',
 MATERIAL='EMPTY',
 VALUE='10K',
 PRIM_FILE='./archive_libs/logical/q_res/chips/chips.prt';

PART_NAME
 R4672 'Q_RES_0402LF-10K,1%,1/16W,EMPTA':;

SECTION_NUMBER 1
 '@S9S_MB_2U_LIB.S9S_MB_2U(SCH_1):PAGE326_I53@PURE_QUANTA.Q_RES(CHIPS)':
 C_PATH='@s9s_mb_2u_lib.s9s_mb_2u(sch_1):page326_i53@pure_quanta.q_res(chips)',
 P_PATH='@s9s_mb_2u_lib.s9s_mb_2u(sch_1):page306_i53@pure_quanta.q_res(chips)',
 PATH='I53',
 DRAWING='@S9S_MB_2U_LIB.S9S_MB_2U(SCH_1):PAGE326',
 PHYS_PAGE='306',
 XY='(1950,4125)',
 ROT='0',
 VER='2',
 PACK_TYPE='0402LF',
 CDS_LIB='pure_quanta',
 CDS_PART_NAME='Q_RES_0402LF-10K,1%,1/16W,EMPTA',
 WATTAGE='1/16W',
 TOLERANCE='1%',
 MATERIAL='EMPTY',
 VALUE='10K',
 PRIM_FILE='./archive_libs/logical/q_res/chips/chips.prt';

PART_NAME
 R4673 'Q_RES_0402LF-0,5%,1/16W,EMPTY,A':;

SECTION_NUMBER 1
 '@S9S_MB_2U_LIB.S9S_MB_2U(SCH_1):PAGE326_I44@PURE_QUANTA.Q_RES(CHIPS)':
 C_PATH='@s9s_mb_2u_lib.s9s_mb_2u(sch_1):page326_i44@pure_quanta.q_res(chips)',
 P_PATH='@s9s_mb_2u_lib.s9s_mb_2u(sch_1):page306_i44@pure_quanta.q_res(chips)',
 PATH='I44',
 DRAWING='@S9S_MB_2U_LIB.S9S_MB_2U(SCH_1):PAGE326',
 PHYS_PAGE='306',
 XY='(1975,3400)',
 ROT='0',
 VER='2',
 PACK_TYPE='0402LF',
 CDS_LIB='pure_quanta',
 CDS_PART_NAME='Q_RES_0402LF-0,5%,1/16W,EMPTY,A',
 WATTAGE='1/16W',
 TOLERANCE='5%',
 MATERIAL='EMPTY',
 VALUE='0',
 PRIM_FILE='./archive_libs/logical/q_res/chips/chips.prt';

PART_NAME
 R4674 'Q_RES_0402LF-10K,1%,1/16W,CHIPA':;

SECTION_NUMBER 1
 '@S9S_MB_2U_LIB.S9S_MB_2U(SCH_1):PAGE209_I46@PURE_QUANTA.Q_RES(CHIPS)':
 C_PATH='@s9s_mb_2u_lib.s9s_mb_2u(sch_1):page209_i46@pure_quanta.q_res(chips)',
 P_PATH='@s9s_mb_2u_lib.s9s_mb_2u(sch_1):page220_i46@pure_quanta.q_res(chips)',
 PATH='I46',
 DRAWING='@S9S_MB_2U_LIB.S9S_MB_2U(SCH_1):PAGE209',
 PHYS_PAGE='220',
 XY='(-2325,-850)',
 ROT='0',
 VER='2',
 PACK_TYPE='0402LF',
 CDS_LIB='pure_quanta',
 CDS_PART_NAME='Q_RES_0402LF-10K,1%,1/16W,CHIPA',
 WATTAGE='1/16W',
 TOLERANCE='1%',
 MATERIAL='CHIP',
 VALUE='10K',
 PRIM_FILE='./archive_libs/logical/q_res/chips/chips.prt';

PART_NAME
 R4677 'Q_RES_0402LF-33.2,1%,1/16W,CHIA':;

SECTION_NUMBER 1
 '@S9S_MB_2U_LIB.S9S_MB_2U(SCH_1):PAGE246_I91@PURE_QUANTA.Q_RES(CHIPS)':
 C_PATH='@s9s_mb_2u_lib.s9s_mb_2u(sch_1):page246_i91@pure_quanta.q_res(chips)',
 P_PATH='@s9s_mb_2u_lib.s9s_mb_2u(sch_1):page260_i91@pure_quanta.q_res(chips)',
 PATH='I91',
 DRAWING='@S9S_MB_2U_LIB.S9S_MB_2U(SCH_1):PAGE246',
 PHYS_PAGE='260',
 XY='(-5325,3100)',
 ROT='0',
 VER='1',
 PACK_TYPE='0402LF',
 CDS_LIB='pure_quanta',
 CDS_PART_NAME='Q_RES_0402LF-33.2,1%,1/16W,CHIA',
 WATTAGE='1/16W',
 TOLERANCE='1%',
 MATERIAL='CHIP',
 VALUE='33.2',
 PRIM_FILE='./archive_libs/logical/q_res/chips/chips.prt';

PART_NAME
 R4678 'Q_RES_0402LF-1K,1%,1/16W,CHIP,A':
 REUSE_ID='3';

SECTION_NUMBER 1
 '@S9S_MB_2U_LIB.S9S_MB_2U(SCH_1):PAGE246_I104@PURE_QUANTA.Q_RES(CHIPS)':
 C_PATH='@s9s_mb_2u_lib.s9s_mb_2u(sch_1):page246_i104@pure_quanta.q_res(chips)',
 P_PATH='@s9s_mb_2u_lib.s9s_mb_2u(sch_1):page260_i104@pure_quanta.q_res(chips)',
 PATH='I104',
 DRAWING='@S9S_MB_2U_LIB.S9S_MB_2U(SCH_1):PAGE246',
 PHYS_PAGE='260',
 XY='(-1200,4400)',
 ROT='0',
 VER='2',
 PACK_TYPE='0402LF',
 CDS_LIB='pure_quanta',
 CDS_PART_NAME='Q_RES_0402LF-1K,1%,1/16W,CHIP,A',
 WATTAGE='1/16W',
 TOLERANCE='1%',
 MATERIAL='CHIP',
 REUSE_ID='3',
 VALUE='1K',
 PRIM_FILE='./archive_libs/logical/q_res/chips/chips.prt';

PART_NAME
 R4679 'Q_RES_0402LF-10K,1%,1/16W,CHIPA':;

SECTION_NUMBER 1
 '@S9S_MB_2U_LIB.S9S_MB_2U(SCH_1):PAGE246_I96@PURE_QUANTA.Q_RES(CHIPS)':
 C_PATH='@s9s_mb_2u_lib.s9s_mb_2u(sch_1):page246_i96@pure_quanta.q_res(chips)',
 P_PATH='@s9s_mb_2u_lib.s9s_mb_2u(sch_1):page260_i96@pure_quanta.q_res(chips)',
 PATH='I96',
 DRAWING='@S9S_MB_2U_LIB.S9S_MB_2U(SCH_1):PAGE246',
 PHYS_PAGE='260',
 XY='(-2700,3975)',
 ROT='0',
 VER='2',
 PACK_TYPE='0402LF',
 CDS_LIB='pure_quanta',
 CDS_PART_NAME='Q_RES_0402LF-10K,1%,1/16W,CHIPA',
 WATTAGE='1/16W',
 TOLERANCE='1%',
 MATERIAL='CHIP',
 VALUE='10K',
 PRIM_FILE='./archive_libs/logical/q_res/chips/chips.prt';

PART_NAME
 R4680 'Q_RES_0402LF-100K,1%,1/16W,CHIA':
 REUSE_ID='1';

SECTION_NUMBER 1
 '@S9S_MB_2U_LIB.S9S_MB_2U(SCH_1):PAGE246_I102@PURE_QUANTA.Q_RES(CHIPS)':
 C_PATH='@s9s_mb_2u_lib.s9s_mb_2u(sch_1):page246_i102@pure_quanta.q_res(chips)',
 P_PATH='@s9s_mb_2u_lib.s9s_mb_2u(sch_1):page260_i102@pure_quanta.q_res(chips)',
 PATH='I102',
 DRAWING='@S9S_MB_2U_LIB.S9S_MB_2U(SCH_1):PAGE246',
 BOM_COST='VR_SYSTEM ',
 PHYS_PAGE='260',
 XY='(-2025,4275)',
 ROT='0',
 VER='2',
 PACK_TYPE='0402LF',
 CDS_LIB='pure_quanta',
 CDS_PART_NAME='Q_RES_0402LF-100K,1%,1/16W,CHIA',
 WATTAGE='1/16W',
 TOLERANCE='1%',
 MATERIAL='CHIP',
 REUSE_ID='1',
 VALUE='100K',
 PRIM_FILE='./archive_libs/logical/q_res/chips/chips.prt';

PART_NAME
 R4681 'Q_RES_0402LF-100K,1%,1/16W,CHIA':;

SECTION_NUMBER 1
 '@S9S_MB_2U_LIB.S9S_MB_2U(SCH_1):PAGE246_I109@PURE_QUANTA.Q_RES(CHIPS)':
 C_PATH='@s9s_mb_2u_lib.s9s_mb_2u(sch_1):page246_i109@pure_quanta.q_res(chips)',
 P_PATH='@s9s_mb_2u_lib.s9s_mb_2u(sch_1):page260_i109@pure_quanta.q_res(chips)',
 PATH='I109',
 DRAWING='@S9S_MB_2U_LIB.S9S_MB_2U(SCH_1):PAGE246',
 PHYS_PAGE='260',
 XY='(-5875,2900)',
 ROT='0',
 VER='2',
 PACK_TYPE='0402LF',
 CDS_LIB='pure_quanta',
 CDS_PART_NAME='Q_RES_0402LF-100K,1%,1/16W,CHIA',
 WATTAGE='1/16W',
 TOLERANCE='1%',
 MATERIAL='CHIP',
 VALUE='100K',
 PRIM_FILE='./archive_libs/logical/q_res/chips/chips.prt';

PART_NAME
 R4682 'Q_RES_0402LF-100K,1%,1/16W,CHIA':;

SECTION_NUMBER 1
 '@S9S_MB_2U_LIB.S9S_MB_2U(SCH_1):PAGE246_I112@PURE_QUANTA.Q_RES(CHIPS)':
 C_PATH='@s9s_mb_2u_lib.s9s_mb_2u(sch_1):page246_i112@pure_quanta.q_res(chips)',
 P_PATH='@s9s_mb_2u_lib.s9s_mb_2u(sch_1):page260_i112@pure_quanta.q_res(chips)',
 PATH='I112',
 DRAWING='@S9S_MB_2U_LIB.S9S_MB_2U(SCH_1):PAGE246',
 PHYS_PAGE='260',
 XY='(-2625,3525)',
 ROT='0',
 VER='2',
 PACK_TYPE='0402LF',
 CDS_LIB='pure_quanta',
 CDS_PART_NAME='Q_RES_0402LF-100K,1%,1/16W,CHIA',
 WATTAGE='1/16W',
 TOLERANCE='1%',
 MATERIAL='CHIP',
 VALUE='100K',
 PRIM_FILE='./archive_libs/logical/q_res/chips/chips.prt';

PART_NAME
 R4684 'Q_RES_0402LF-0,5%,1/16W,EMPTY,A':
 ROOM='HSC1_BOM2';

SECTION_NUMBER 1
 '@S9S_MB_2U_LIB.S9S_MB_2U(SCH_1):PAGE327_I14@PURE_QUANTA.Q_RES(CHIPS)':
 C_PATH='@s9s_mb_2u_lib.s9s_mb_2u(sch_1):page327_i14@pure_quanta.q_res(chips)',
 P_PATH='@s9s_mb_2u_lib.s9s_mb_2u(sch_1):page305_i14@pure_quanta.q_res(chips)',
 PATH='I14',
 DRAWING='@S9S_MB_2U_LIB.S9S_MB_2U(SCH_1):PAGE327',
 PHYS_PAGE='305',
 XY='(4475,200)',
 ROT='0',
 VER='1',
 PACK_TYPE='0402LF',
 CDS_LIB='pure_quanta',
 CDS_PART_NAME='Q_RES_0402LF-0,5%,1/16W,EMPTY,A',
 WATTAGE='1/16W',
 TOLERANCE='5%',
 MATERIAL='EMPTY',
 ROOM='HSC1_BOM2',
 VALUE='0',
 PRIM_FILE='./archive_libs/logical/q_res/chips/chips.prt';

PART_NAME
 R4685 'Q_RES_0402LF-10.5K,1%,1/16W,EMA':
 ROOM='HSC1_BOM2';

SECTION_NUMBER 1
 '@S9S_MB_2U_LIB.S9S_MB_2U(SCH_1):PAGE327_I23@PURE_QUANTA.Q_RES(CHIPS)':
 C_PATH='@s9s_mb_2u_lib.s9s_mb_2u(sch_1):page327_i23@pure_quanta.q_res(chips)',
 P_PATH='@s9s_mb_2u_lib.s9s_mb_2u(sch_1):page305_i23@pure_quanta.q_res(chips)',
 PATH='I23',
 DRAWING='@S9S_MB_2U_LIB.S9S_MB_2U(SCH_1):PAGE327',
 PHYS_PAGE='305',
 XY='(4800,750)',
 ROT='0',
 VER='2',
 PACK_TYPE='0402LF',
 CDS_LIB='pure_quanta',
 CDS_PART_NAME='Q_RES_0402LF-10.5K,1%,1/16W,EMA',
 WATTAGE='1/16W',
 TOLERANCE='1%',
 MATERIAL='EMPTY',
 ROOM='HSC1_BOM2',
 VALUE='10.5K',
 PRIM_FILE='./archive_libs/logical/q_res/chips/chips.prt';

PART_NAME
 R4686 'Q_RES_0402LF-10.5K,1%,1/16W,EMA':
 ROOM='HSC1_BOM2';

SECTION_NUMBER 1
 '@S9S_MB_2U_LIB.S9S_MB_2U(SCH_1):PAGE327_I17@PURE_QUANTA.Q_RES(CHIPS)':
 C_PATH='@s9s_mb_2u_lib.s9s_mb_2u(sch_1):page327_i17@pure_quanta.q_res(chips)',
 P_PATH='@s9s_mb_2u_lib.s9s_mb_2u(sch_1):page305_i17@pure_quanta.q_res(chips)',
 PATH='I17',
 DRAWING='@S9S_MB_2U_LIB.S9S_MB_2U(SCH_1):PAGE327',
 PHYS_PAGE='305',
 XY='(4800,-100)',
 ROT='0',
 VER='2',
 PACK_TYPE='0402LF',
 CDS_LIB='pure_quanta',
 CDS_PART_NAME='Q_RES_0402LF-10.5K,1%,1/16W,EMA',
 WATTAGE='1/16W',
 TOLERANCE='1%',
 MATERIAL='EMPTY',
 ROOM='HSC1_BOM2',
 VALUE='10.5K',
 PRIM_FILE='./archive_libs/logical/q_res/chips/chips.prt';

PART_NAME
 R4687 'Q_RES_0402LF-4.7K,1%,1/16W,EMPA':
 ROOM='HSC1_BOM2';

SECTION_NUMBER 1
 '@S9S_MB_2U_LIB.S9S_MB_2U(SCH_1):PAGE240_I19@PURE_QUANTA.Q_RES(CHIPS)':
 C_PATH='@s9s_mb_2u_lib.s9s_mb_2u(sch_1):page240_i19@pure_quanta.q_res(chips)',
 P_PATH='@s9s_mb_2u_lib.s9s_mb_2u(sch_1):page251_i19@pure_quanta.q_res(chips)',
 PATH='I19',
 DRAWING='@S9S_MB_2U_LIB.S9S_MB_2U(SCH_1):PAGE240',
 PHYS_PAGE='251',
 XY='(-2125,800)',
 ROT='0',
 VER='1',
 PACK_TYPE='0402LF',
 CDS_LIB='pure_quanta',
 CDS_PART_NAME='Q_RES_0402LF-4.7K,1%,1/16W,EMPA',
 WATTAGE='1/16W',
 TOLERANCE='1%',
 MATERIAL='EMPTY',
 ROOM='HSC1_BOM2',
 VALUE='4.7K',
 PRIM_FILE='./archive_libs/logical/q_res/chips/chips.prt';

PART_NAME
 R4688 'Q_RES_0402LF-4.7K,1%,1/16W,EMPA':;

SECTION_NUMBER 1
 '@S9S_MB_2U_LIB.S9S_MB_2U(SCH_1):PAGE240_I18@PURE_QUANTA.Q_RES(CHIPS)':
 C_PATH='@s9s_mb_2u_lib.s9s_mb_2u(sch_1):page240_i18@pure_quanta.q_res(chips)',
 P_PATH='@s9s_mb_2u_lib.s9s_mb_2u(sch_1):page251_i18@pure_quanta.q_res(chips)',
 PATH='I18',
 DRAWING='@S9S_MB_2U_LIB.S9S_MB_2U(SCH_1):PAGE240',
 PHYS_PAGE='251',
 XY='(-2125,725)',
 ROT='0',
 VER='1',
 PACK_TYPE='0402LF',
 CDS_LIB='pure_quanta',
 CDS_PART_NAME='Q_RES_0402LF-4.7K,1%,1/16W,EMPA',
 WATTAGE='1/16W',
 TOLERANCE='1%',
 MATERIAL='EMPTY',
 VALUE='4.7K',
 PRIM_FILE='./archive_libs/logical/q_res/chips/chips.prt';

PART_NAME
 R4689 'Q_RES_0402LF-33.2,1%,1/16W,EMPA':
 ROOM='HSC1_BOM2';

SECTION_NUMBER 1
 '@S9S_MB_2U_LIB.S9S_MB_2U(SCH_1):PAGE240_I38@PURE_QUANTA.Q_RES(CHIPS)':
 C_PATH='@s9s_mb_2u_lib.s9s_mb_2u(sch_1):page240_i38@pure_quanta.q_res(chips)',
 P_PATH='@s9s_mb_2u_lib.s9s_mb_2u(sch_1):page251_i38@pure_quanta.q_res(chips)',
 PATH='I38',
 DRAWING='@S9S_MB_2U_LIB.S9S_MB_2U(SCH_1):PAGE240',
 PHYS_PAGE='251',
 XY='(-1775,250)',
 ROT='0',
 VER='1',
 PACK_TYPE='0402LF',
 CDS_LIB='pure_quanta',
 CDS_PART_NAME='Q_RES_0402LF-33.2,1%,1/16W,EMPA',
 WATTAGE='1/16W',
 TOLERANCE='1%',
 MATERIAL='EMPTY',
 ROOM='HSC1_BOM2',
 VALUE='33.2',
 PRIM_FILE='./archive_libs/logical/q_res/chips/chips.prt';

PART_NAME
 R4690 'Q_RES_0402LF-33.2,1%,1/16W,EMPA':
 ROOM='HSC1_BOM2';

SECTION_NUMBER 1
 '@S9S_MB_2U_LIB.S9S_MB_2U(SCH_1):PAGE240_I37@PURE_QUANTA.Q_RES(CHIPS)':
 C_PATH='@s9s_mb_2u_lib.s9s_mb_2u(sch_1):page240_i37@pure_quanta.q_res(chips)',
 P_PATH='@s9s_mb_2u_lib.s9s_mb_2u(sch_1):page251_i37@pure_quanta.q_res(chips)',
 PATH='I37',
 DRAWING='@S9S_MB_2U_LIB.S9S_MB_2U(SCH_1):PAGE240',
 PHYS_PAGE='251',
 XY='(-1775,200)',
 ROT='0',
 VER='1',
 PACK_TYPE='0402LF',
 CDS_LIB='pure_quanta',
 CDS_PART_NAME='Q_RES_0402LF-33.2,1%,1/16W,EMPA',
 WATTAGE='1/16W',
 TOLERANCE='1%',
 MATERIAL='EMPTY',
 ROOM='HSC1_BOM2',
 VALUE='33.2',
 PRIM_FILE='./archive_libs/logical/q_res/chips/chips.prt';

PART_NAME
 R4691 'Q_RES_0402LF-0,5%,1/16W,EMPTY,A':
 ROOM='HSC1_BOM2';

SECTION_NUMBER 1
 '@S9S_MB_2U_LIB.S9S_MB_2U(SCH_1):PAGE240_I16@PURE_QUANTA.Q_RES(CHIPS)':
 C_PATH='@s9s_mb_2u_lib.s9s_mb_2u(sch_1):page240_i16@pure_quanta.q_res(chips)',
 P_PATH='@s9s_mb_2u_lib.s9s_mb_2u(sch_1):page251_i16@pure_quanta.q_res(chips)',
 PATH='I16',
 DRAWING='@S9S_MB_2U_LIB.S9S_MB_2U(SCH_1):PAGE240',
 PHYS_PAGE='251',
 XY='(-1325,550)',
 ROT='0',
 VER='2',
 PACK_TYPE='0402LF',
 CDS_LIB='pure_quanta',
 CDS_PART_NAME='Q_RES_0402LF-0,5%,1/16W,EMPTY,A',
 WATTAGE='1/16W',
 TOLERANCE='5%',
 MATERIAL='EMPTY',
 ROOM='HSC1_BOM2',
 VALUE='0',
 PRIM_FILE='./archive_libs/logical/q_res/chips/chips.prt';

PART_NAME
 R4692 'Q_RES_0402LF-4.7K,1%,1/16W,EMPA':
 ROOM='HSC1_BOM2';

SECTION_NUMBER 1
 '@S9S_MB_2U_LIB.S9S_MB_2U(SCH_1):PAGE240_I35@PURE_QUANTA.Q_RES(CHIPS)':
 C_PATH='@s9s_mb_2u_lib.s9s_mb_2u(sch_1):page240_i35@pure_quanta.q_res(chips)',
 P_PATH='@s9s_mb_2u_lib.s9s_mb_2u(sch_1):page251_i35@pure_quanta.q_res(chips)',
 PATH='I35',
 DRAWING='@S9S_MB_2U_LIB.S9S_MB_2U(SCH_1):PAGE240',
 PHYS_PAGE='251',
 XY='(1350,900)',
 ROT='0',
 VER='2',
 PACK_TYPE='0402LF',
 CDS_LIB='pure_quanta',
 CDS_PART_NAME='Q_RES_0402LF-4.7K,1%,1/16W,EMPA',
 WATTAGE='1/16W',
 TOLERANCE='1%',
 MATERIAL='EMPTY',
 ROOM='HSC1_BOM2',
 VALUE='4.7K',
 PRIM_FILE='./archive_libs/logical/q_res/chips/chips.prt';

PART_NAME
 R4693 'Q_RES_0402LF-0,5%,1/16W,EMPTY,A':
 ROOM='HSC1_BOM2';

SECTION_NUMBER 1
 '@S9S_MB_2U_LIB.S9S_MB_2U(SCH_1):PAGE326_I29@PURE_QUANTA.Q_RES(CHIPS)':
 C_PATH='@s9s_mb_2u_lib.s9s_mb_2u(sch_1):page326_i29@pure_quanta.q_res(chips)',
 P_PATH='@s9s_mb_2u_lib.s9s_mb_2u(sch_1):page306_i29@pure_quanta.q_res(chips)',
 PATH='I29',
 DRAWING='@S9S_MB_2U_LIB.S9S_MB_2U(SCH_1):PAGE326',
 PHYS_PAGE='306',
 XY='(1000,3050)',
 ROT='0',
 VER='1',
 PACK_TYPE='0402LF',
 CDS_LIB='pure_quanta',
 CDS_PART_NAME='Q_RES_0402LF-0,5%,1/16W,EMPTY,A',
 WATTAGE='1/16W',
 TOLERANCE='5%',
 MATERIAL='EMPTY',
 ROOM='HSC1_BOM2',
 VALUE='0',
 PRIM_FILE='./archive_libs/logical/q_res/chips/chips.prt';

PART_NAME
 R4694 'Q_RES_0402LF-1K,1%,1/16W,CHIP,A':
 ROOM='PCIE REDRIVER1_BOM2';

SECTION_NUMBER 1
 '@S9S_MB_2U_LIB.S9S_MB_2U(SCH_1):PAGE159_I10@PURE_QUANTA.Q_RES(CHIPS)':
 C_PATH='@s9s_mb_2u_lib.s9s_mb_2u(sch_1):page159_i10@pure_quanta.q_res(chips)',
 P_PATH='@s9s_mb_2u_lib.s9s_mb_2u(sch_1):page167_i10@pure_quanta.q_res(chips)',
 PATH='I10',
 DRAWING='@S9S_MB_2U_LIB.S9S_MB_2U(SCH_1):PAGE159',
 PHYS_PAGE='167',
 XY='(-1550,-1000)',
 ROT='0',
 VER='2',
 PACK_TYPE='0402LF',
 CDS_LIB='pure_quanta',
 CDS_PART_NAME='Q_RES_0402LF-1K,1%,1/16W,CHIP,A',
 WATTAGE='1/16W',
 TOLERANCE='1%',
 MATERIAL='CHIP',
 ROOM='PCIE REDRIVER1_BOM2',
 VALUE='1K',
 PRIM_FILE='./archive_libs/logical/q_res/chips/chips.prt';

PART_NAME
 R4695 'Q_RES_0402LF-0,5%,1/16W,CHIP,CA':;

SECTION_NUMBER 1
 '@S9S_MB_2U_LIB.S9S_MB_2U(SCH_1):PAGE327_I26@PURE_QUANTA.Q_RES(CHIPS)':
 C_PATH='@s9s_mb_2u_lib.s9s_mb_2u(sch_1):page327_i26@pure_quanta.q_res(chips)',
 P_PATH='@s9s_mb_2u_lib.s9s_mb_2u(sch_1):page305_i26@pure_quanta.q_res(chips)',
 PATH='I26',
 DRAWING='@S9S_MB_2U_LIB.S9S_MB_2U(SCH_1):PAGE327',
 PHYS_PAGE='305',
 XY='(1925,2375)',
 ROT='0',
 VER='1',
 PACK_TYPE='0402LF',
 CDS_LIB='pure_quanta',
 CDS_PART_NAME='Q_RES_0402LF-0,5%,1/16W,CHIP,CA',
 WATTAGE='1/16W',
 TOLERANCE='5%',
 MATERIAL='CHIP',
 VALUE='0',
 PRIM_FILE='./archive_libs/logical/q_res/chips/chips.prt';

PART_NAME
 R4696 'Q_RES_0402LF-0,5%,1/16W,CHIP,CA':;

SECTION_NUMBER 1
 '@S9S_MB_2U_LIB.S9S_MB_2U(SCH_1):PAGE327_I25@PURE_QUANTA.Q_RES(CHIPS)':
 C_PATH='@s9s_mb_2u_lib.s9s_mb_2u(sch_1):page327_i25@pure_quanta.q_res(chips)',
 P_PATH='@s9s_mb_2u_lib.s9s_mb_2u(sch_1):page305_i25@pure_quanta.q_res(chips)',
 PATH='I25',
 DRAWING='@S9S_MB_2U_LIB.S9S_MB_2U(SCH_1):PAGE327',
 PHYS_PAGE='305',
 XY='(1925,2325)',
 ROT='0',
 VER='1',
 PACK_TYPE='0402LF',
 CDS_LIB='pure_quanta',
 CDS_PART_NAME='Q_RES_0402LF-0,5%,1/16W,CHIP,CA',
 WATTAGE='1/16W',
 TOLERANCE='5%',
 MATERIAL='CHIP',
 VALUE='0',
 PRIM_FILE='./archive_libs/logical/q_res/chips/chips.prt';

PART_NAME
 R4697 'Q_RES_0402LF-0,5%,1/16W,CHIP,CA':;

SECTION_NUMBER 1
 '@S9S_MB_2U_LIB.S9S_MB_2U(SCH_1):PAGE314_I14@PURE_QUANTA.Q_RES(CHIPS)':
 C_PATH='@s9s_mb_2u_lib.s9s_mb_2u(sch_1):page314_i14@pure_quanta.q_res(chips)',
 P_PATH='@s9s_mb_2u_lib.s9s_mb_2u(sch_1):page213_i14@pure_quanta.q_res(chips)',
 PATH='I14',
 DRAWING='@S9S_MB_2U_LIB.S9S_MB_2U(SCH_1):PAGE314',
 PHYS_PAGE='213',
 XY='(-2275,-1675)',
 ROT='0',
 VER='1',
 PACK_TYPE='0402LF',
 CDS_LIB='pure_quanta',
 CDS_PART_NAME='Q_RES_0402LF-0,5%,1/16W,CHIP,CA',
 WATTAGE='1/16W',
 TOLERANCE='5%',
 MATERIAL='CHIP',
 VALUE='0',
 PRIM_FILE='./archive_libs/logical/q_res/chips/chips.prt';

PART_NAME
 R4701 'Q_RES_0402LF-4.7K,5%,1/16W,CHIA':;

SECTION_NUMBER 1
 '@S9S_MB_2U_LIB.S9S_MB_2U(SCH_1):PAGE233_I41@PURE_QUANTA.Q_RES(CHIPS)':
 C_PATH='@s9s_mb_2u_lib.s9s_mb_2u(sch_1):page233_i41@pure_quanta.q_res(chips)',
 P_PATH='@s9s_mb_2u_lib.s9s_mb_2u(sch_1):page245_i41@pure_quanta.q_res(chips)',
 PATH='I41',
 DRAWING='@S9S_MB_2U_LIB.S9S_MB_2U(SCH_1):PAGE233',
 PHYS_PAGE='245',
 XY='(-1175,2350)',
 ROT='0',
 VER='2',
 PACK_TYPE='0402LF',
 CDS_LIB='pure_quanta',
 CDS_PART_NAME='Q_RES_0402LF-4.7K,5%,1/16W,CHIA',
 WATTAGE='1/16W',
 TOLERANCE='5%',
 MATERIAL='CHIP',
 VALUE='4.7K',
 PRIM_FILE='./archive_libs/logical/q_res/chips/chips.prt';

PART_NAME
 R4702 'Q_RES_0402LF-560,1%,1/16W,CHIPA':;

SECTION_NUMBER 1
 '@S9S_MB_2U_LIB.S9S_MB_2U(SCH_1):PAGE241_I64@PURE_QUANTA.Q_RES(CHIPS)':
 C_PATH='@s9s_mb_2u_lib.s9s_mb_2u(sch_1):page241_i64@pure_quanta.q_res(chips)',
 P_PATH='@s9s_mb_2u_lib.s9s_mb_2u(sch_1):page255_i64@pure_quanta.q_res(chips)',
 PATH='I64',
 DRAWING='@S9S_MB_2U_LIB.S9S_MB_2U(SCH_1):PAGE241',
 PHYS_PAGE='255',
 XY='(-8400,3400)',
 ROT='0',
 VER='1',
 PACK_TYPE='0402LF',
 CDS_LIB='pure_quanta',
 CDS_PART_NAME='Q_RES_0402LF-560,1%,1/16W,CHIPA',
 WATTAGE='1/16W',
 TOLERANCE='1%',
 MATERIAL='CHIP',
 VALUE='560',
 PRIM_FILE='./archive_libs/logical/q_res/chips/chips.prt';

PART_NAME
 R4703 'Q_RES_0402LF-560,1%,1/16W,CHIPA':;

SECTION_NUMBER 1
 '@S9S_MB_2U_LIB.S9S_MB_2U(SCH_1):PAGE241_I61@PURE_QUANTA.Q_RES(CHIPS)':
 C_PATH='@s9s_mb_2u_lib.s9s_mb_2u(sch_1):page241_i61@pure_quanta.q_res(chips)',
 P_PATH='@s9s_mb_2u_lib.s9s_mb_2u(sch_1):page255_i61@pure_quanta.q_res(chips)',
 PATH='I61',
 DRAWING='@S9S_MB_2U_LIB.S9S_MB_2U(SCH_1):PAGE241',
 PHYS_PAGE='255',
 XY='(-8400,2150)',
 ROT='0',
 VER='1',
 PACK_TYPE='0402LF',
 CDS_LIB='pure_quanta',
 CDS_PART_NAME='Q_RES_0402LF-560,1%,1/16W,CHIPA',
 WATTAGE='1/16W',
 TOLERANCE='1%',
 MATERIAL='CHIP',
 VALUE='560',
 PRIM_FILE='./archive_libs/logical/q_res/chips/chips.prt';

PART_NAME
 R4704 'Q_RES_0402LF-560,1%,1/16W,CHIPA':;

SECTION_NUMBER 1
 '@S9S_MB_2U_LIB.S9S_MB_2U(SCH_1):PAGE241_I65@PURE_QUANTA.Q_RES(CHIPS)':
 C_PATH='@s9s_mb_2u_lib.s9s_mb_2u(sch_1):page241_i65@pure_quanta.q_res(chips)',
 P_PATH='@s9s_mb_2u_lib.s9s_mb_2u(sch_1):page255_i65@pure_quanta.q_res(chips)',
 PATH='I65',
 DRAWING='@S9S_MB_2U_LIB.S9S_MB_2U(SCH_1):PAGE241',
 PHYS_PAGE='255',
 XY='(-7725,3400)',
 ROT='0',
 VER='1',
 PACK_TYPE='0402LF',
 CDS_LIB='pure_quanta',
 CDS_PART_NAME='Q_RES_0402LF-560,1%,1/16W,CHIPA',
 WATTAGE='1/16W',
 TOLERANCE='1%',
 MATERIAL='CHIP',
 VALUE='560',
 PRIM_FILE='./archive_libs/logical/q_res/chips/chips.prt';

PART_NAME
 R4705 'Q_RES_0402LF-560,1%,1/16W,CHIPA':;

SECTION_NUMBER 1
 '@S9S_MB_2U_LIB.S9S_MB_2U(SCH_1):PAGE241_I62@PURE_QUANTA.Q_RES(CHIPS)':
 C_PATH='@s9s_mb_2u_lib.s9s_mb_2u(sch_1):page241_i62@pure_quanta.q_res(chips)',
 P_PATH='@s9s_mb_2u_lib.s9s_mb_2u(sch_1):page255_i62@pure_quanta.q_res(chips)',
 PATH='I62',
 DRAWING='@S9S_MB_2U_LIB.S9S_MB_2U(SCH_1):PAGE241',
 PHYS_PAGE='255',
 XY='(-7700,2150)',
 ROT='0',
 VER='1',
 PACK_TYPE='0402LF',
 CDS_LIB='pure_quanta',
 CDS_PART_NAME='Q_RES_0402LF-560,1%,1/16W,CHIPA',
 WATTAGE='1/16W',
 TOLERANCE='1%',
 MATERIAL='CHIP',
 VALUE='560',
 PRIM_FILE='./archive_libs/logical/q_res/chips/chips.prt';

PART_NAME
 R4706 'Q_RES_0402LF-560,1%,1/16W,CHIPA':;

SECTION_NUMBER 1
 '@S9S_MB_2U_LIB.S9S_MB_2U(SCH_1):PAGE241_I66@PURE_QUANTA.Q_RES(CHIPS)':
 C_PATH='@s9s_mb_2u_lib.s9s_mb_2u(sch_1):page241_i66@pure_quanta.q_res(chips)',
 P_PATH='@s9s_mb_2u_lib.s9s_mb_2u(sch_1):page255_i66@pure_quanta.q_res(chips)',
 PATH='I66',
 DRAWING='@S9S_MB_2U_LIB.S9S_MB_2U(SCH_1):PAGE241',
 PHYS_PAGE='255',
 XY='(-6825,3400)',
 ROT='0',
 VER='1',
 PACK_TYPE='0402LF',
 CDS_LIB='pure_quanta',
 CDS_PART_NAME='Q_RES_0402LF-560,1%,1/16W,CHIPA',
 WATTAGE='1/16W',
 TOLERANCE='1%',
 MATERIAL='CHIP',
 VALUE='560',
 PRIM_FILE='./archive_libs/logical/q_res/chips/chips.prt';

PART_NAME
 R4707 'Q_RES_0402LF-560,1%,1/16W,CHIPA':;

SECTION_NUMBER 1
 '@S9S_MB_2U_LIB.S9S_MB_2U(SCH_1):PAGE241_I63@PURE_QUANTA.Q_RES(CHIPS)':
 C_PATH='@s9s_mb_2u_lib.s9s_mb_2u(sch_1):page241_i63@pure_quanta.q_res(chips)',
 P_PATH='@s9s_mb_2u_lib.s9s_mb_2u(sch_1):page255_i63@pure_quanta.q_res(chips)',
 PATH='I63',
 DRAWING='@S9S_MB_2U_LIB.S9S_MB_2U(SCH_1):PAGE241',
 PHYS_PAGE='255',
 XY='(-6825,2150)',
 ROT='0',
 VER='1',
 PACK_TYPE='0402LF',
 CDS_LIB='pure_quanta',
 CDS_PART_NAME='Q_RES_0402LF-560,1%,1/16W,CHIPA',
 WATTAGE='1/16W',
 TOLERANCE='1%',
 MATERIAL='CHIP',
 VALUE='560',
 PRIM_FILE='./archive_libs/logical/q_res/chips/chips.prt';

PART_NAME
 R4708 'Q_RES_0402LF-0,5%,1/16W,EMPTY,A':
 ROOM='SCM_P12V_BOM1';

SECTION_NUMBER 1
 '@S9S_MB_2U_LIB.S9S_MB_2U(SCH_1):PAGE229_I77@PURE_QUANTA.Q_RES(CHIPS)':
 C_PATH='@s9s_mb_2u_lib.s9s_mb_2u(sch_1):page229_i77@pure_quanta.q_res(chips)',
 P_PATH='@s9s_mb_2u_lib.s9s_mb_2u(sch_1):page242_i77@pure_quanta.q_res(chips)',
 PATH='I77',
 DRAWING='@S9S_MB_2U_LIB.S9S_MB_2U(SCH_1):PAGE229',
 PHYS_PAGE='242',
 XY='(3225,1400)',
 ROT='0',
 VER='1',
 PACK_TYPE='0402LF',
 CDS_LIB='pure_quanta',
 CDS_PART_NAME='Q_RES_0402LF-0,5%,1/16W,EMPTY,A',
 WATTAGE='1/16W',
 TOLERANCE='5%',
 MATERIAL='EMPTY',
 ROOM='SCM_P12V_BOM1',
 VALUE='0',
 PRIM_FILE='./archive_libs/logical/q_res/chips/chips.prt';

PART_NAME
 R4709 'Q_RES_0402LF-0,5%,1/16W,CHIP,CA':
 ROOM='SCM_P12V_BOM2';

SECTION_NUMBER 1
 '@S9S_MB_2U_LIB.S9S_MB_2U(SCH_1):PAGE229_I44@PURE_QUANTA.Q_RES(CHIPS)':
 C_PATH='@s9s_mb_2u_lib.s9s_mb_2u(sch_1):page229_i44@pure_quanta.q_res(chips)',
 P_PATH='@s9s_mb_2u_lib.s9s_mb_2u(sch_1):page242_i44@pure_quanta.q_res(chips)',
 PATH='I44',
 DRAWING='@S9S_MB_2U_LIB.S9S_MB_2U(SCH_1):PAGE229',
 PHYS_PAGE='242',
 XY='(2700,-2300)',
 ROT='0',
 VER='1',
 PACK_TYPE='0402LF',
 CDS_LIB='pure_quanta',
 CDS_PART_NAME='Q_RES_0402LF-0,5%,1/16W,CHIP,CA',
 WATTAGE='1/16W',
 TOLERANCE='5%',
 MATERIAL='CHIP',
 ROOM='SCM_P12V_BOM2',
 VALUE='0',
 PRIM_FILE='./archive_libs/logical/q_res/chips/chips.prt';

PART_NAME
 R4710 'Q_RES_0402LF-4.7K,5%,1/16W,CHIA':;

SECTION_NUMBER 1
 '@S9S_MB_2U_LIB.S9S_MB_2U(SCH_1):PAGE241_I74@PURE_QUANTA.Q_RES(CHIPS)':
 C_PATH='@s9s_mb_2u_lib.s9s_mb_2u(sch_1):page241_i74@pure_quanta.q_res(chips)',
 P_PATH='@s9s_mb_2u_lib.s9s_mb_2u(sch_1):page255_i74@pure_quanta.q_res(chips)',
 PATH='I74',
 DRAWING='@S9S_MB_2U_LIB.S9S_MB_2U(SCH_1):PAGE241',
 PHYS_PAGE='255',
 XY='(-9025,425)',
 ROT='0',
 VER='2',
 PACK_TYPE='0402LF',
 CDS_LIB='pure_quanta',
 CDS_PART_NAME='Q_RES_0402LF-4.7K,5%,1/16W,CHIA',
 WATTAGE='1/16W',
 TOLERANCE='5%',
 MATERIAL='CHIP',
 VALUE='4.7K',
 PRIM_FILE='./archive_libs/logical/q_res/chips/chips.prt';

PART_NAME
 R4711 'Q_RES_0402LF-249,1%,1/16W,CHIPA':;

SECTION_NUMBER 1
 '@S9S_MB_2U_LIB.S9S_MB_2U(SCH_1):PAGE241_I68@PURE_QUANTA.Q_RES(CHIPS)':
 C_PATH='@s9s_mb_2u_lib.s9s_mb_2u(sch_1):page241_i68@pure_quanta.q_res(chips)',
 P_PATH='@s9s_mb_2u_lib.s9s_mb_2u(sch_1):page255_i68@pure_quanta.q_res(chips)',
 PATH='I68',
 DRAWING='@S9S_MB_2U_LIB.S9S_MB_2U(SCH_1):PAGE241',
 PHYS_PAGE='255',
 XY='(-6525,425)',
 ROT='0',
 VER='1',
 PACK_TYPE='0402LF',
 CDS_LIB='pure_quanta',
 CDS_PART_NAME='Q_RES_0402LF-249,1%,1/16W,CHIPA',
 WATTAGE='1/16W',
 TOLERANCE='1%',
 MATERIAL='CHIP',
 VALUE='249',
 PRIM_FILE='./archive_libs/logical/q_res/chips/chips.prt';

PART_NAME
 R4712 'Q_RES_0402LF-100K,1%,1/16W,CHIA':;

SECTION_NUMBER 1
 '@S9S_MB_2U_LIB.S9S_MB_2U(SCH_1):PAGE177_I125@PURE_QUANTA.Q_RES(CHIPS)':
 C_PATH='@s9s_mb_2u_lib.s9s_mb_2u(sch_1):page177_i125@pure_quanta.q_res(chips)',
 P_PATH='@s9s_mb_2u_lib.s9s_mb_2u(sch_1):page185_i125@pure_quanta.q_res(chips)',
 PATH='I125',
 DRAWING='@S9S_MB_2U_LIB.S9S_MB_2U(SCH_1):PAGE177',
 PHYS_PAGE='185',
 XY='(-1125,-625)',
 ROT='0',
 VER='2',
 PACK_TYPE='0402LF',
 CDS_LIB='pure_quanta',
 CDS_PART_NAME='Q_RES_0402LF-100K,1%,1/16W,CHIA',
 WATTAGE='1/16W',
 TOLERANCE='1%',
 MATERIAL='CHIP',
 VALUE='100K',
 PRIM_FILE='./archive_libs/logical/q_res/chips/chips.prt';

PART_NAME
 R4713 'Q_RES_0402LF-100K,1%,1/16W,CHIA':;

SECTION_NUMBER 1
 '@S9S_MB_2U_LIB.S9S_MB_2U(SCH_1):PAGE177_I127@PURE_QUANTA.Q_RES(CHIPS)':
 C_PATH='@s9s_mb_2u_lib.s9s_mb_2u(sch_1):page177_i127@pure_quanta.q_res(chips)',
 P_PATH='@s9s_mb_2u_lib.s9s_mb_2u(sch_1):page185_i127@pure_quanta.q_res(chips)',
 PATH='I127',
 DRAWING='@S9S_MB_2U_LIB.S9S_MB_2U(SCH_1):PAGE177',
 PHYS_PAGE='185',
 XY='(-1125,-1525)',
 ROT='0',
 VER='2',
 PACK_TYPE='0402LF',
 CDS_LIB='pure_quanta',
 CDS_PART_NAME='Q_RES_0402LF-100K,1%,1/16W,CHIA',
 WATTAGE='1/16W',
 TOLERANCE='1%',
 MATERIAL='CHIP',
 VALUE='100K',
 PRIM_FILE='./archive_libs/logical/q_res/chips/chips.prt';

PART_NAME
 R4714 'Q_RES_0402LF-33.2,1%,1/16W,CHIA':;

SECTION_NUMBER 1
 '@S9S_MB_2U_LIB.S9S_MB_2U(SCH_1):PAGE314_I197@PURE_QUANTA.Q_RES(CHIPS)':
 C_PATH='@s9s_mb_2u_lib.s9s_mb_2u(sch_1):page314_i197@pure_quanta.q_res(chips)',
 P_PATH='@s9s_mb_2u_lib.s9s_mb_2u(sch_1):page213_i197@pure_quanta.q_res(chips)',
 PATH='I197',
 DRAWING='@S9S_MB_2U_LIB.S9S_MB_2U(SCH_1):PAGE314',
 PHYS_PAGE='213',
 XY='(-2225,100)',
 ROT='0',
 VER='1',
 PACK_TYPE='0402LF',
 LOCATION='R4714',
 CDS_LIB='pure_quanta',
 CDS_PART_NAME='Q_RES_0402LF-33.2,1%,1/16W,CHIA',
 WATTAGE='1/16W',
 TOLERANCE='1%',
 MATERIAL='CHIP',
 VALUE='33.2',
 PRIM_FILE='./archive_libs/logical/q_res/chips/chips.prt';

PART_NAME
 R4715 'Q_RES_0402LF-33.2,1%,1/16W,CHIA':;

SECTION_NUMBER 1
 '@S9S_MB_2U_LIB.S9S_MB_2U(SCH_1):PAGE314_I198@PURE_QUANTA.Q_RES(CHIPS)':
 C_PATH='@s9s_mb_2u_lib.s9s_mb_2u(sch_1):page314_i198@pure_quanta.q_res(chips)',
 P_PATH='@s9s_mb_2u_lib.s9s_mb_2u(sch_1):page213_i198@pure_quanta.q_res(chips)',
 PATH='I198',
 DRAWING='@S9S_MB_2U_LIB.S9S_MB_2U(SCH_1):PAGE314',
 PHYS_PAGE='213',
 XY='(-2225,25)',
 ROT='0',
 VER='1',
 PACK_TYPE='0402LF',
 LOCATION='R4715',
 CDS_LIB='pure_quanta',
 CDS_PART_NAME='Q_RES_0402LF-33.2,1%,1/16W,CHIA',
 WATTAGE='1/16W',
 TOLERANCE='1%',
 MATERIAL='CHIP',
 VALUE='33.2',
 PRIM_FILE='./archive_libs/logical/q_res/chips/chips.prt';

PART_NAME
 R4716 'Q_RES_0402LF-8.45K,1%,1/16W,EMA':;

SECTION_NUMBER 1
 '@S9S_MB_2U_LIB.S9S_MB_2U(SCH_1):PAGE213_I40@PURE_QUANTA.Q_RES(CHIPS)':
 C_PATH='@s9s_mb_2u_lib.s9s_mb_2u(sch_1):page213_i40@pure_quanta.q_res(chips)',
 P_PATH='@s9s_mb_2u_lib.s9s_mb_2u(sch_1):page224_i40@pure_quanta.q_res(chips)',
 PATH='I40',
 DRAWING='@S9S_MB_2U_LIB.S9S_MB_2U(SCH_1):PAGE213',
 PHYS_PAGE='224',
 XY='(-8850,1375)',
 ROT='0',
 VER='2',
 PACK_TYPE='0402LF',
 CDS_LIB='pure_quanta',
 CDS_PART_NAME='Q_RES_0402LF-8.45K,1%,1/16W,EMA',
 WATTAGE='1/16W',
 TOLERANCE='1%',
 MATERIAL='EMPTY',
 VALUE='8.45K',
 PRIM_FILE='./archive_libs/logical/q_res/chips/chips.prt';

PART_NAME
 R4717 'Q_RES_0402LF-0,5%,1/16W,EMPTY,A':;

SECTION_NUMBER 1
 '@S9S_MB_2U_LIB.S9S_MB_2U(SCH_1):PAGE213_I41@PURE_QUANTA.Q_RES(CHIPS)':
 C_PATH='@s9s_mb_2u_lib.s9s_mb_2u(sch_1):page213_i41@pure_quanta.q_res(chips)',
 P_PATH='@s9s_mb_2u_lib.s9s_mb_2u(sch_1):page224_i41@pure_quanta.q_res(chips)',
 PATH='I41',
 DRAWING='@S9S_MB_2U_LIB.S9S_MB_2U(SCH_1):PAGE213',
 PHYS_PAGE='224',
 XY='(-8650,1050)',
 ROT='0',
 VER='1',
 PACK_TYPE='0402LF',
 CDS_LIB='pure_quanta',
 CDS_PART_NAME='Q_RES_0402LF-0,5%,1/16W,EMPTY,A',
 WATTAGE='1/16W',
 TOLERANCE='5%',
 MATERIAL='EMPTY',
 VALUE='0',
 PRIM_FILE='./archive_libs/logical/q_res/chips/chips.prt';

PART_NAME
 R4718 'Q_RES_0402LF-33.2,1%,1/16W,EMPA':;

SECTION_NUMBER 1
 '@S9S_MB_2U_LIB.S9S_MB_2U(SCH_1):PAGE213_I33@PURE_QUANTA.Q_RES(CHIPS)':
 C_PATH='@s9s_mb_2u_lib.s9s_mb_2u(sch_1):page213_i33@pure_quanta.q_res(chips)',
 P_PATH='@s9s_mb_2u_lib.s9s_mb_2u(sch_1):page224_i33@pure_quanta.q_res(chips)',
 PATH='I33',
 DRAWING='@S9S_MB_2U_LIB.S9S_MB_2U(SCH_1):PAGE213',
 PHYS_PAGE='224',
 XY='(-5800,1050)',
 ROT='0',
 VER='1',
 PACK_TYPE='0402LF',
 CDS_LIB='pure_quanta',
 CDS_PART_NAME='Q_RES_0402LF-33.2,1%,1/16W,EMPA',
 WATTAGE='1/16W',
 TOLERANCE='1%',
 MATERIAL='EMPTY',
 VALUE='33.2',
 PRIM_FILE='./archive_libs/logical/q_res/chips/chips.prt';

PART_NAME
 R4719 'Q_RES_0402LF-10K,1%,1/16W,CHIPA':;

SECTION_NUMBER 1
 '@S9S_MB_2U_LIB.S9S_MB_2U(SCH_1):PAGE213_I32@PURE_QUANTA.Q_RES(CHIPS)':
 C_PATH='@s9s_mb_2u_lib.s9s_mb_2u(sch_1):page213_i32@pure_quanta.q_res(chips)',
 P_PATH='@s9s_mb_2u_lib.s9s_mb_2u(sch_1):page224_i32@pure_quanta.q_res(chips)',
 PATH='I32',
 DRAWING='@S9S_MB_2U_LIB.S9S_MB_2U(SCH_1):PAGE213',
 PHYS_PAGE='224',
 XY='(-5300,1375)',
 ROT='0',
 VER='2',
 PACK_TYPE='0402LF',
 CDS_LIB='pure_quanta',
 CDS_PART_NAME='Q_RES_0402LF-10K,1%,1/16W,CHIPA',
 WATTAGE='1/16W',
 TOLERANCE='1%',
 MATERIAL='CHIP',
 VALUE='10K',
 PRIM_FILE='./archive_libs/logical/q_res/chips/chips.prt';

PART_NAME
 R4720 'Q_RES_0402LF-0,5%,1/16W,CHIP,CA':;

SECTION_NUMBER 1
 '@S9S_MB_2U_LIB.S9S_MB_2U(SCH_1):PAGE227_I57@PURE_QUANTA.Q_RES(CHIPS)':
 C_PATH='@s9s_mb_2u_lib.s9s_mb_2u(sch_1):page227_i57@pure_quanta.q_res(chips)',
 P_PATH='@s9s_mb_2u_lib.s9s_mb_2u(sch_1):page240_i57@pure_quanta.q_res(chips)',
 PATH='I57',
 DRAWING='@S9S_MB_2U_LIB.S9S_MB_2U(SCH_1):PAGE227',
 PHYS_PAGE='240',
 XY='(-7800,-775)',
 ROT='0',
 VER='1',
 PACK_TYPE='0402LF',
 CDS_LIB='pure_quanta',
 CDS_PART_NAME='Q_RES_0402LF-0,5%,1/16W,CHIP,CA',
 WATTAGE='1/16W',
 TOLERANCE='5%',
 MATERIAL='CHIP',
 VALUE='0',
 PRIM_FILE='./archive_libs/logical/q_res/chips/chips.prt';

PART_NAME
 R4721 'Q_RES_0402LF-0,5%,1/16W,CHIP,CA':;

SECTION_NUMBER 1
 '@S9S_MB_2U_LIB.S9S_MB_2U(SCH_1):PAGE233_I35@PURE_QUANTA.Q_RES(CHIPS)':
 C_PATH='@s9s_mb_2u_lib.s9s_mb_2u(sch_1):page233_i35@pure_quanta.q_res(chips)',
 P_PATH='@s9s_mb_2u_lib.s9s_mb_2u(sch_1):page245_i35@pure_quanta.q_res(chips)',
 PATH='I35',
 DRAWING='@S9S_MB_2U_LIB.S9S_MB_2U(SCH_1):PAGE233',
 PHYS_PAGE='245',
 XY='(-5200,2000)',
 ROT='0',
 VER='1',
 PACK_TYPE='0402LF',
 CDS_LIB='pure_quanta',
 CDS_PART_NAME='Q_RES_0402LF-0,5%,1/16W,CHIP,CA',
 WATTAGE='1/16W',
 TOLERANCE='5%',
 MATERIAL='CHIP',
 VALUE='0',
 PRIM_FILE='./archive_libs/logical/q_res/chips/chips.prt';

PART_NAME
 R4722 'Q_RES_0402LF-10K,1%,1/16W,CHIPA':;

SECTION_NUMBER 1
 '@S9S_MB_2U_LIB.S9S_MB_2U(SCH_1):PAGE176_I246@PURE_QUANTA.Q_RES(CHIPS)':
 C_PATH='@s9s_mb_2u_lib.s9s_mb_2u(sch_1):page176_i246@pure_quanta.q_res(chips)',
 P_PATH='@s9s_mb_2u_lib.s9s_mb_2u(sch_1):page184_i246@pure_quanta.q_res(chips)',
 PATH='I246',
 DRAWING='@S9S_MB_2U_LIB.S9S_MB_2U(SCH_1):PAGE176',
 PHYS_PAGE='184',
 XY='(4675,500)',
 ROT='0',
 VER='1',
 PACK_TYPE='0402LF',
 CDS_LIB='pure_quanta',
 CDS_PART_NAME='Q_RES_0402LF-10K,1%,1/16W,CHIPA',
 WATTAGE='1/16W',
 TOLERANCE='1%',
 MATERIAL='CHIP',
 VALUE='10K',
 PRIM_FILE='./archive_libs/logical/q_res/chips/chips.prt';

PART_NAME
 R4723 'Q_RES_0402LF-33.2,1%,1/16W,CHIA':;

SECTION_NUMBER 1
 '@S9S_MB_2U_LIB.S9S_MB_2U(SCH_1):PAGE312_I213@PURE_QUANTA.Q_RES(CHIPS)':
 C_PATH='@s9s_mb_2u_lib.s9s_mb_2u(sch_1):page312_i213@pure_quanta.q_res(chips)',
 P_PATH='@s9s_mb_2u_lib.s9s_mb_2u(sch_1):page215_i213@pure_quanta.q_res(chips)',
 PATH='I213',
 DRAWING='@S9S_MB_2U_LIB.S9S_MB_2U(SCH_1):PAGE312',
 PHYS_PAGE='215',
 XY='(-4550,-1775)',
 ROT='0',
 VER='1',
 PACK_TYPE='0402LF',
 CDS_LIB='pure_quanta',
 CDS_PART_NAME='Q_RES_0402LF-33.2,1%,1/16W,CHIA',
 WATTAGE='1/16W',
 TOLERANCE='1%',
 MATERIAL='CHIP',
 VALUE='33.2',
 PRIM_FILE='./archive_libs/logical/q_res/chips/chips.prt';

PART_NAME
 R4724 'Q_RES_0402LF-100K,1%,1/16W,EMPA':;

SECTION_NUMBER 1
 '@S9S_MB_2U_LIB.S9S_MB_2U(SCH_1):PAGE147_I34@PURE_QUANTA.Q_RES(CHIPS)':
 C_PATH='@s9s_mb_2u_lib.s9s_mb_2u(sch_1):page147_i34@pure_quanta.q_res(chips)',
 P_PATH='@s9s_mb_2u_lib.s9s_mb_2u(sch_1):page144_i34@pure_quanta.q_res(chips)',
 PATH='I34',
 DRAWING='@S9S_MB_2U_LIB.S9S_MB_2U(SCH_1):PAGE147',
 PHYS_PAGE='144',
 XY='(-6700,7700)',
 ROT='0',
 VER='2',
 PACK_TYPE='0402LF',
 CDS_LIB='pure_quanta',
 CDS_PART_NAME='Q_RES_0402LF-100K,1%,1/16W,EMPA',
 WATTAGE='1/16W',
 TOLERANCE='1%',
 MATERIAL='EMPTY',
 VALUE='100K',
 PRIM_FILE='./archive_libs/logical/q_res/chips/chips.prt';

PART_NAME
 R4725 'Q_RES_0402LF-4.7K,5%,1/16W,CHIA':;

SECTION_NUMBER 1
 '@S9S_MB_2U_LIB.S9S_MB_2U(SCH_1):PAGE147_I28@PURE_QUANTA.Q_RES(CHIPS)':
 C_PATH='@s9s_mb_2u_lib.s9s_mb_2u(sch_1):page147_i28@pure_quanta.q_res(chips)',
 P_PATH='@s9s_mb_2u_lib.s9s_mb_2u(sch_1):page144_i28@pure_quanta.q_res(chips)',
 PATH='I28',
 DRAWING='@S9S_MB_2U_LIB.S9S_MB_2U(SCH_1):PAGE147',
 PHYS_PAGE='144',
 XY='(-5550,8550)',
 ROT='0',
 VER='2',
 PACK_TYPE='0402LF',
 CDS_LIB='pure_quanta',
 CDS_PART_NAME='Q_RES_0402LF-4.7K,5%,1/16W,CHIA',
 WATTAGE='1/16W',
 TOLERANCE='5%',
 MATERIAL='CHIP',
 VALUE='4.7K',
 PRIM_FILE='./archive_libs/logical/q_res/chips/chips.prt';

PART_NAME
 R4726 'Q_RES_0402LF-4.7K,5%,1/16W,CHIA':;

SECTION_NUMBER 1
 '@S9S_MB_2U_LIB.S9S_MB_2U(SCH_1):PAGE147_I18@PURE_QUANTA.Q_RES(CHIPS)':
 C_PATH='@s9s_mb_2u_lib.s9s_mb_2u(sch_1):page147_i18@pure_quanta.q_res(chips)',
 P_PATH='@s9s_mb_2u_lib.s9s_mb_2u(sch_1):page144_i18@pure_quanta.q_res(chips)',
 PATH='I18',
 DRAWING='@S9S_MB_2U_LIB.S9S_MB_2U(SCH_1):PAGE147',
 PHYS_PAGE='144',
 XY='(-4400,8675)',
 ROT='0',
 VER='2',
 PACK_TYPE='0402LF',
 CDS_LIB='pure_quanta',
 CDS_PART_NAME='Q_RES_0402LF-4.7K,5%,1/16W,CHIA',
 WATTAGE='1/16W',
 TOLERANCE='5%',
 MATERIAL='CHIP',
 VALUE='4.7K',
 PRIM_FILE='./archive_libs/logical/q_res/chips/chips.prt';

PART_NAME
 R4727 'Q_RES_0402LF-10K,1%,1/16W,CHIPA':;

SECTION_NUMBER 1
 '@S9S_MB_2U_LIB.S9S_MB_2U(SCH_1):PAGE147_I33@PURE_QUANTA.Q_RES(CHIPS)':
 C_PATH='@s9s_mb_2u_lib.s9s_mb_2u(sch_1):page147_i33@pure_quanta.q_res(chips)',
 P_PATH='@s9s_mb_2u_lib.s9s_mb_2u(sch_1):page144_i33@pure_quanta.q_res(chips)',
 PATH='I33',
 DRAWING='@S9S_MB_2U_LIB.S9S_MB_2U(SCH_1):PAGE147',
 PHYS_PAGE='144',
 XY='(-6725,8175)',
 ROT='0',
 VER='2',
 PACK_TYPE='0402LF',
 CDS_LIB='pure_quanta',
 CDS_PART_NAME='Q_RES_0402LF-10K,1%,1/16W,CHIPA',
 WATTAGE='1/16W',
 TOLERANCE='1%',
 MATERIAL='CHIP',
 VALUE='10K',
 PRIM_FILE='./archive_libs/logical/q_res/chips/chips.prt';

PART_NAME
 R4728 'Q_RES_0402LF-0,5%,1/16W,CHIP,CA':;

SECTION_NUMBER 1
 '@S9S_MB_2U_LIB.S9S_MB_2U(SCH_1):PAGE214_I137@PURE_QUANTA.Q_RES(CHIPS)':
 C_PATH='@s9s_mb_2u_lib.s9s_mb_2u(sch_1):page214_i137@pure_quanta.q_res(chips)',
 P_PATH='@s9s_mb_2u_lib.s9s_mb_2u(sch_1):page227_i137@pure_quanta.q_res(chips)',
 PATH='I137',
 DRAWING='@S9S_MB_2U_LIB.S9S_MB_2U(SCH_1):PAGE214',
 PHYS_PAGE='227',
 XY='(8650,2200)',
 ROT='0',
 VER='1',
 PACK_TYPE='0402LF',
 CDS_LIB='pure_quanta',
 CDS_PART_NAME='Q_RES_0402LF-0,5%,1/16W,CHIP,CA',
 WATTAGE='1/16W',
 TOLERANCE='5%',
 MATERIAL='CHIP',
 VALUE='0',
 PRIM_FILE='./archive_libs/logical/q_res/chips/chips.prt';

PART_NAME
 R4729 'Q_RES_0402LF-0,5%,1/16W,CHIP,CA':;

SECTION_NUMBER 1
 '@S9S_MB_2U_LIB.S9S_MB_2U(SCH_1):PAGE214_I140@PURE_QUANTA.Q_RES(CHIPS)':
 C_PATH='@s9s_mb_2u_lib.s9s_mb_2u(sch_1):page214_i140@pure_quanta.q_res(chips)',
 P_PATH='@s9s_mb_2u_lib.s9s_mb_2u(sch_1):page227_i140@pure_quanta.q_res(chips)',
 PATH='I140',
 DRAWING='@S9S_MB_2U_LIB.S9S_MB_2U(SCH_1):PAGE214',
 PHYS_PAGE='227',
 XY='(8650,2050)',
 ROT='0',
 VER='1',
 PACK_TYPE='0402LF',
 CDS_LIB='pure_quanta',
 CDS_PART_NAME='Q_RES_0402LF-0,5%,1/16W,CHIP,CA',
 WATTAGE='1/16W',
 TOLERANCE='5%',
 MATERIAL='CHIP',
 VALUE='0',
 PRIM_FILE='./archive_libs/logical/q_res/chips/chips.prt';

PART_NAME
 R4730 'Q_RES_0402LF-10K,1%,1/16W,CHIPA':;

SECTION_NUMBER 1
 '@S9S_MB_2U_LIB.S9S_MB_2U(SCH_1):PAGE147_I41@PURE_QUANTA.Q_RES(CHIPS)':
 C_PATH='@s9s_mb_2u_lib.s9s_mb_2u(sch_1):page147_i41@pure_quanta.q_res(chips)',
 P_PATH='@s9s_mb_2u_lib.s9s_mb_2u(sch_1):page144_i41@pure_quanta.q_res(chips)',
 PATH='I41',
 DRAWING='@S9S_MB_2U_LIB.S9S_MB_2U(SCH_1):PAGE147',
 PHYS_PAGE='144',
 XY='(-6600,6650)',
 ROT='0',
 VER='2',
 PACK_TYPE='0402LF',
 CDS_LIB='pure_quanta',
 CDS_PART_NAME='Q_RES_0402LF-10K,1%,1/16W,CHIPA',
 WATTAGE='1/16W',
 TOLERANCE='1%',
 MATERIAL='CHIP',
 VALUE='10K',
 PRIM_FILE='./archive_libs/logical/q_res/chips/chips.prt';

PART_NAME
 R4731 'Q_RES_0402LF-100K,1%,1/16W,EMPA':;

SECTION_NUMBER 1
 '@S9S_MB_2U_LIB.S9S_MB_2U(SCH_1):PAGE147_I42@PURE_QUANTA.Q_RES(CHIPS)':
 C_PATH='@s9s_mb_2u_lib.s9s_mb_2u(sch_1):page147_i42@pure_quanta.q_res(chips)',
 P_PATH='@s9s_mb_2u_lib.s9s_mb_2u(sch_1):page144_i42@pure_quanta.q_res(chips)',
 PATH='I42',
 DRAWING='@S9S_MB_2U_LIB.S9S_MB_2U(SCH_1):PAGE147',
 PHYS_PAGE='144',
 XY='(-6575,6175)',
 ROT='0',
 VER='2',
 PACK_TYPE='0402LF',
 CDS_LIB='pure_quanta',
 CDS_PART_NAME='Q_RES_0402LF-100K,1%,1/16W,EMPA',
 WATTAGE='1/16W',
 TOLERANCE='1%',
 MATERIAL='EMPTY',
 VALUE='100K',
 PRIM_FILE='./archive_libs/logical/q_res/chips/chips.prt';

PART_NAME
 R4732 'Q_RES_0402LF-4.7K,5%,1/16W,CHIA':;

SECTION_NUMBER 1
 '@S9S_MB_2U_LIB.S9S_MB_2U(SCH_1):PAGE147_I36@PURE_QUANTA.Q_RES(CHIPS)':
 C_PATH='@s9s_mb_2u_lib.s9s_mb_2u(sch_1):page147_i36@pure_quanta.q_res(chips)',
 P_PATH='@s9s_mb_2u_lib.s9s_mb_2u(sch_1):page144_i36@pure_quanta.q_res(chips)',
 PATH='I36',
 DRAWING='@S9S_MB_2U_LIB.S9S_MB_2U(SCH_1):PAGE147',
 PHYS_PAGE='144',
 XY='(-5425,7025)',
 ROT='0',
 VER='2',
 PACK_TYPE='0402LF',
 CDS_LIB='pure_quanta',
 CDS_PART_NAME='Q_RES_0402LF-4.7K,5%,1/16W,CHIA',
 WATTAGE='1/16W',
 TOLERANCE='5%',
 MATERIAL='CHIP',
 VALUE='4.7K',
 PRIM_FILE='./archive_libs/logical/q_res/chips/chips.prt';

PART_NAME
 R4733 'Q_RES_0402LF-4.7K,5%,1/16W,CHIA':;

SECTION_NUMBER 1
 '@S9S_MB_2U_LIB.S9S_MB_2U(SCH_1):PAGE147_I25@PURE_QUANTA.Q_RES(CHIPS)':
 C_PATH='@s9s_mb_2u_lib.s9s_mb_2u(sch_1):page147_i25@pure_quanta.q_res(chips)',
 P_PATH='@s9s_mb_2u_lib.s9s_mb_2u(sch_1):page144_i25@pure_quanta.q_res(chips)',
 PATH='I25',
 DRAWING='@S9S_MB_2U_LIB.S9S_MB_2U(SCH_1):PAGE147',
 PHYS_PAGE='144',
 XY='(-4275,7150)',
 ROT='0',
 VER='2',
 PACK_TYPE='0402LF',
 CDS_LIB='pure_quanta',
 CDS_PART_NAME='Q_RES_0402LF-4.7K,5%,1/16W,CHIA',
 WATTAGE='1/16W',
 TOLERANCE='5%',
 MATERIAL='CHIP',
 VALUE='4.7K',
 PRIM_FILE='./archive_libs/logical/q_res/chips/chips.prt';

PART_NAME
 R4734 'Q_RES_0402LF-0,5%,1/16W,CHIP,CA':;

SECTION_NUMBER 1
 '@S9S_MB_2U_LIB.S9S_MB_2U(SCH_1):PAGE214_I144@PURE_QUANTA.Q_RES(CHIPS)':
 C_PATH='@s9s_mb_2u_lib.s9s_mb_2u(sch_1):page214_i144@pure_quanta.q_res(chips)',
 P_PATH='@s9s_mb_2u_lib.s9s_mb_2u(sch_1):page227_i144@pure_quanta.q_res(chips)',
 PATH='I144',
 DRAWING='@S9S_MB_2U_LIB.S9S_MB_2U(SCH_1):PAGE214',
 PHYS_PAGE='227',
 XY='(8650,1900)',
 ROT='0',
 VER='1',
 PACK_TYPE='0402LF',
 CDS_LIB='pure_quanta',
 CDS_PART_NAME='Q_RES_0402LF-0,5%,1/16W,CHIP,CA',
 WATTAGE='1/16W',
 TOLERANCE='5%',
 MATERIAL='CHIP',
 VALUE='0',
 PRIM_FILE='./archive_libs/logical/q_res/chips/chips.prt';

PART_NAME
 R4735 'Q_RES_0402LF-0,5%,1/16W,CHIP,CA':;

SECTION_NUMBER 1
 '@S9S_MB_2U_LIB.S9S_MB_2U(SCH_1):PAGE214_I148@PURE_QUANTA.Q_RES(CHIPS)':
 C_PATH='@s9s_mb_2u_lib.s9s_mb_2u(sch_1):page214_i148@pure_quanta.q_res(chips)',
 P_PATH='@s9s_mb_2u_lib.s9s_mb_2u(sch_1):page227_i148@pure_quanta.q_res(chips)',
 PATH='I148',
 DRAWING='@S9S_MB_2U_LIB.S9S_MB_2U(SCH_1):PAGE214',
 PHYS_PAGE='227',
 XY='(8650,1750)',
 ROT='0',
 VER='1',
 PACK_TYPE='0402LF',
 CDS_LIB='pure_quanta',
 CDS_PART_NAME='Q_RES_0402LF-0,5%,1/16W,CHIP,CA',
 WATTAGE='1/16W',
 TOLERANCE='5%',
 MATERIAL='CHIP',
 VALUE='0',
 PRIM_FILE='./archive_libs/logical/q_res/chips/chips.prt';

PART_NAME
 R4736 'Q_RES_0402LF-0,5%,1/16W,CHIP,CA':;

SECTION_NUMBER 1
 '@S9S_MB_2U_LIB.S9S_MB_2U(SCH_1):PAGE214_I153@PURE_QUANTA.Q_RES(CHIPS)':
 C_PATH='@s9s_mb_2u_lib.s9s_mb_2u(sch_1):page214_i153@pure_quanta.q_res(chips)',
 P_PATH='@s9s_mb_2u_lib.s9s_mb_2u(sch_1):page227_i153@pure_quanta.q_res(chips)',
 PATH='I153',
 DRAWING='@S9S_MB_2U_LIB.S9S_MB_2U(SCH_1):PAGE214',
 PHYS_PAGE='227',
 XY='(8650,1600)',
 ROT='0',
 VER='1',
 PACK_TYPE='0402LF',
 CDS_LIB='pure_quanta',
 CDS_PART_NAME='Q_RES_0402LF-0,5%,1/16W,CHIP,CA',
 WATTAGE='1/16W',
 TOLERANCE='5%',
 MATERIAL='CHIP',
 VALUE='0',
 PRIM_FILE='./archive_libs/logical/q_res/chips/chips.prt';

PART_NAME
 R4737 'Q_RES_0402LF-10K,1%,1/16W,CHIPA':;

SECTION_NUMBER 1
 '@S9S_MB_2U_LIB.S9S_MB_2U(SCH_1):PAGE147_I58@PURE_QUANTA.Q_RES(CHIPS)':
 C_PATH='@s9s_mb_2u_lib.s9s_mb_2u(sch_1):page147_i58@pure_quanta.q_res(chips)',
 P_PATH='@s9s_mb_2u_lib.s9s_mb_2u(sch_1):page144_i58@pure_quanta.q_res(chips)',
 PATH='I58',
 DRAWING='@S9S_MB_2U_LIB.S9S_MB_2U(SCH_1):PAGE147',
 PHYS_PAGE='144',
 XY='(-6375,5000)',
 ROT='0',
 VER='2',
 PACK_TYPE='0402LF',
 CDS_LIB='pure_quanta',
 CDS_PART_NAME='Q_RES_0402LF-10K,1%,1/16W,CHIPA',
 WATTAGE='1/16W',
 TOLERANCE='1%',
 MATERIAL='CHIP',
 VALUE='10K',
 PRIM_FILE='./archive_libs/logical/q_res/chips/chips.prt';

PART_NAME
 R4738 'Q_RES_0402LF-100K,1%,1/16W,EMPA':;

SECTION_NUMBER 1
 '@S9S_MB_2U_LIB.S9S_MB_2U(SCH_1):PAGE147_I60@PURE_QUANTA.Q_RES(CHIPS)':
 C_PATH='@s9s_mb_2u_lib.s9s_mb_2u(sch_1):page147_i60@pure_quanta.q_res(chips)',
 P_PATH='@s9s_mb_2u_lib.s9s_mb_2u(sch_1):page144_i60@pure_quanta.q_res(chips)',
 PATH='I60',
 DRAWING='@S9S_MB_2U_LIB.S9S_MB_2U(SCH_1):PAGE147',
 PHYS_PAGE='144',
 XY='(-6350,4525)',
 ROT='0',
 VER='2',
 PACK_TYPE='0402LF',
 CDS_LIB='pure_quanta',
 CDS_PART_NAME='Q_RES_0402LF-100K,1%,1/16W,EMPA',
 WATTAGE='1/16W',
 TOLERANCE='1%',
 MATERIAL='EMPTY',
 VALUE='100K',
 PRIM_FILE='./archive_libs/logical/q_res/chips/chips.prt';

PART_NAME
 R4739 'Q_RES_0402LF-4.7K,5%,1/16W,CHIA':;

SECTION_NUMBER 1
 '@S9S_MB_2U_LIB.S9S_MB_2U(SCH_1):PAGE147_I54@PURE_QUANTA.Q_RES(CHIPS)':
 C_PATH='@s9s_mb_2u_lib.s9s_mb_2u(sch_1):page147_i54@pure_quanta.q_res(chips)',
 P_PATH='@s9s_mb_2u_lib.s9s_mb_2u(sch_1):page144_i54@pure_quanta.q_res(chips)',
 PATH='I54',
 DRAWING='@S9S_MB_2U_LIB.S9S_MB_2U(SCH_1):PAGE147',
 PHYS_PAGE='144',
 XY='(-5200,5375)',
 ROT='0',
 VER='2',
 PACK_TYPE='0402LF',
 CDS_LIB='pure_quanta',
 CDS_PART_NAME='Q_RES_0402LF-4.7K,5%,1/16W,CHIA',
 WATTAGE='1/16W',
 TOLERANCE='5%',
 MATERIAL='CHIP',
 VALUE='4.7K',
 PRIM_FILE='./archive_libs/logical/q_res/chips/chips.prt';

PART_NAME
 R4740 'Q_RES_0402LF-4.7K,5%,1/16W,CHIA':;

SECTION_NUMBER 1
 '@S9S_MB_2U_LIB.S9S_MB_2U(SCH_1):PAGE147_I50@PURE_QUANTA.Q_RES(CHIPS)':
 C_PATH='@s9s_mb_2u_lib.s9s_mb_2u(sch_1):page147_i50@pure_quanta.q_res(chips)',
 P_PATH='@s9s_mb_2u_lib.s9s_mb_2u(sch_1):page144_i50@pure_quanta.q_res(chips)',
 PATH='I50',
 DRAWING='@S9S_MB_2U_LIB.S9S_MB_2U(SCH_1):PAGE147',
 PHYS_PAGE='144',
 XY='(-4050,5500)',
 ROT='0',
 VER='2',
 PACK_TYPE='0402LF',
 CDS_LIB='pure_quanta',
 CDS_PART_NAME='Q_RES_0402LF-4.7K,5%,1/16W,CHIA',
 WATTAGE='1/16W',
 TOLERANCE='5%',
 MATERIAL='CHIP',
 VALUE='4.7K',
 PRIM_FILE='./archive_libs/logical/q_res/chips/chips.prt';

PART_NAME
 R4741 'Q_RES_0402LF-0,5%,1/16W,CHIP,CA':;

SECTION_NUMBER 1
 '@S9S_MB_2U_LIB.S9S_MB_2U(SCH_1):PAGE214_I156@PURE_QUANTA.Q_RES(CHIPS)':
 C_PATH='@s9s_mb_2u_lib.s9s_mb_2u(sch_1):page214_i156@pure_quanta.q_res(chips)',
 P_PATH='@s9s_mb_2u_lib.s9s_mb_2u(sch_1):page227_i156@pure_quanta.q_res(chips)',
 PATH='I156',
 DRAWING='@S9S_MB_2U_LIB.S9S_MB_2U(SCH_1):PAGE214',
 PHYS_PAGE='227',
 XY='(8650,1450)',
 ROT='0',
 VER='1',
 PACK_TYPE='0402LF',
 CDS_LIB='pure_quanta',
 CDS_PART_NAME='Q_RES_0402LF-0,5%,1/16W,CHIP,CA',
 WATTAGE='1/16W',
 TOLERANCE='5%',
 MATERIAL='CHIP',
 VALUE='0',
 PRIM_FILE='./archive_libs/logical/q_res/chips/chips.prt';

PART_NAME
 R4742 'Q_RES_0402LF-0,5%,1/16W,CHIP,CA':;

SECTION_NUMBER 1
 '@S9S_MB_2U_LIB.S9S_MB_2U(SCH_1):PAGE214_I161@PURE_QUANTA.Q_RES(CHIPS)':
 C_PATH='@s9s_mb_2u_lib.s9s_mb_2u(sch_1):page214_i161@pure_quanta.q_res(chips)',
 P_PATH='@s9s_mb_2u_lib.s9s_mb_2u(sch_1):page227_i161@pure_quanta.q_res(chips)',
 PATH='I161',
 DRAWING='@S9S_MB_2U_LIB.S9S_MB_2U(SCH_1):PAGE214',
 PHYS_PAGE='227',
 XY='(8650,1300)',
 ROT='0',
 VER='1',
 PACK_TYPE='0402LF',
 CDS_LIB='pure_quanta',
 CDS_PART_NAME='Q_RES_0402LF-0,5%,1/16W,CHIP,CA',
 WATTAGE='1/16W',
 TOLERANCE='5%',
 MATERIAL='CHIP',
 VALUE='0',
 PRIM_FILE='./archive_libs/logical/q_res/chips/chips.prt';

PART_NAME
 R4745 'Q_RES_0402LF-10K,1%,1/16W,CHIPA':;

SECTION_NUMBER 1
 '@S9S_MB_2U_LIB.S9S_MB_2U(SCH_1):PAGE154_I256@PURE_QUANTA.Q_RES(CHIPS)':
 C_PATH='@s9s_mb_2u_lib.s9s_mb_2u(sch_1):page154_i256@pure_quanta.q_res(chips)',
 P_PATH='@s9s_mb_2u_lib.s9s_mb_2u(sch_1):page158_i256@pure_quanta.q_res(chips)',
 PATH='I256',
 DRAWING='@S9S_MB_2U_LIB.S9S_MB_2U(SCH_1):PAGE154',
 PHYS_PAGE='158',
 XY='(-350,6200)',
 ROT='0',
 VER='2',
 PACK_TYPE='0402LF',
 CDS_LIB='pure_quanta',
 CDS_PART_NAME='Q_RES_0402LF-10K,1%,1/16W,CHIPA',
 WATTAGE='1/16W',
 TOLERANCE='1%',
 MATERIAL='CHIP',
 VALUE='10K',
 PRIM_FILE='./archive_libs/logical/q_res/chips/chips.prt';

PART_NAME
 R4746 'Q_RES_0402LF-33.2,1%,1/16W,CHIA':;

SECTION_NUMBER 1
 '@S9S_MB_2U_LIB.S9S_MB_2U(SCH_1):PAGE154_I245@PURE_QUANTA.Q_RES(CHIPS)':
 C_PATH='@s9s_mb_2u_lib.s9s_mb_2u(sch_1):page154_i245@pure_quanta.q_res(chips)',
 P_PATH='@s9s_mb_2u_lib.s9s_mb_2u(sch_1):page158_i245@pure_quanta.q_res(chips)',
 PATH='I245',
 DRAWING='@S9S_MB_2U_LIB.S9S_MB_2U(SCH_1):PAGE154',
 PHYS_PAGE='158',
 XY='(-625,5850)',
 ROT='0',
 VER='1',
 PACK_TYPE='0402LF',
 CDS_LIB='pure_quanta',
 CDS_PART_NAME='Q_RES_0402LF-33.2,1%,1/16W,CHIA',
 WATTAGE='1/16W',
 TOLERANCE='1%',
 MATERIAL='CHIP',
 VALUE='33.2',
 PRIM_FILE='./archive_libs/logical/q_res/chips/chips.prt';

PART_NAME
 R4747 'Q_RES_0402LF-33.2,1%,1/16W,CHIA':;

SECTION_NUMBER 1
 '@S9S_MB_2U_LIB.S9S_MB_2U(SCH_1):PAGE154_I249@PURE_QUANTA.Q_RES(CHIPS)':
 C_PATH='@s9s_mb_2u_lib.s9s_mb_2u(sch_1):page154_i249@pure_quanta.q_res(chips)',
 P_PATH='@s9s_mb_2u_lib.s9s_mb_2u(sch_1):page158_i249@pure_quanta.q_res(chips)',
 PATH='I249',
 DRAWING='@S9S_MB_2U_LIB.S9S_MB_2U(SCH_1):PAGE154',
 PHYS_PAGE='158',
 XY='(-625,5750)',
 ROT='0',
 VER='1',
 PACK_TYPE='0402LF',
 CDS_LIB='pure_quanta',
 CDS_PART_NAME='Q_RES_0402LF-33.2,1%,1/16W,CHIA',
 WATTAGE='1/16W',
 TOLERANCE='1%',
 MATERIAL='CHIP',
 VALUE='33.2',
 PRIM_FILE='./archive_libs/logical/q_res/chips/chips.prt';

PART_NAME
 R4748 'Q_RES_0402LF-0,5%,1/16W,EMPTY,A':;

SECTION_NUMBER 1
 '@S9S_MB_2U_LIB.S9S_MB_2U(SCH_1):PAGE154_I253@PURE_QUANTA.Q_RES(CHIPS)':
 C_PATH='@s9s_mb_2u_lib.s9s_mb_2u(sch_1):page154_i253@pure_quanta.q_res(chips)',
 P_PATH='@s9s_mb_2u_lib.s9s_mb_2u(sch_1):page158_i253@pure_quanta.q_res(chips)',
 PATH='I253',
 DRAWING='@S9S_MB_2U_LIB.S9S_MB_2U(SCH_1):PAGE154',
 PHYS_PAGE='158',
 XY='(1050,6450)',
 ROT='0',
 VER='1',
 PACK_TYPE='0402LF',
 CDS_LIB='pure_quanta',
 CDS_PART_NAME='Q_RES_0402LF-0,5%,1/16W,EMPTY,A',
 WATTAGE='1/16W',
 TOLERANCE='5%',
 MATERIAL='EMPTY',
 VALUE='0',
 PRIM_FILE='./archive_libs/logical/q_res/chips/chips.prt';

PART_NAME
 R4749 'Q_RES_0402LF-0,5%,1/16W,EMPTY,A':;

SECTION_NUMBER 1
 '@S9S_MB_2U_LIB.S9S_MB_2U(SCH_1):PAGE154_I254@PURE_QUANTA.Q_RES(CHIPS)':
 C_PATH='@s9s_mb_2u_lib.s9s_mb_2u(sch_1):page154_i254@pure_quanta.q_res(chips)',
 P_PATH='@s9s_mb_2u_lib.s9s_mb_2u(sch_1):page158_i254@pure_quanta.q_res(chips)',
 PATH='I254',
 DRAWING='@S9S_MB_2U_LIB.S9S_MB_2U(SCH_1):PAGE154',
 PHYS_PAGE='158',
 XY='(1100,5375)',
 ROT='0',
 VER='1',
 PACK_TYPE='0402LF',
 CDS_LIB='pure_quanta',
 CDS_PART_NAME='Q_RES_0402LF-0,5%,1/16W,EMPTY,A',
 WATTAGE='1/16W',
 TOLERANCE='5%',
 MATERIAL='EMPTY',
 VALUE='0',
 PRIM_FILE='./archive_libs/logical/q_res/chips/chips.prt';

PART_NAME
 R4750 'Q_RES_0402LF-49.9,1%,1/16W,CHIA':;

SECTION_NUMBER 1
 '@S9S_MB_2U_LIB.S9S_MB_2U(SCH_1):PAGE154_I247@PURE_QUANTA.Q_RES(CHIPS)':
 C_PATH='@s9s_mb_2u_lib.s9s_mb_2u(sch_1):page154_i247@pure_quanta.q_res(chips)',
 P_PATH='@s9s_mb_2u_lib.s9s_mb_2u(sch_1):page158_i247@pure_quanta.q_res(chips)',
 PATH='I247',
 DRAWING='@S9S_MB_2U_LIB.S9S_MB_2U(SCH_1):PAGE154',
 PHYS_PAGE='158',
 XY='(2100,5700)',
 ROT='0',
 VER='1',
 PACK_TYPE='0402LF',
 CDS_LIB='pure_quanta',
 CDS_PART_NAME='Q_RES_0402LF-49.9,1%,1/16W,CHIA',
 WATTAGE='1/16W',
 TOLERANCE='1%',
 MATERIAL='CHIP',
 VALUE='49.9',
 PRIM_FILE='./archive_libs/logical/q_res/chips/chips.prt';

PART_NAME
 R4751 'Q_RES_0402LF-33.2,1%,1/16W,CHIA':;

SECTION_NUMBER 1
 '@S9S_MB_2U_LIB.S9S_MB_2U(SCH_1):PAGE311_I79@PURE_QUANTA.Q_RES(CHIPS)':
 C_PATH='@s9s_mb_2u_lib.s9s_mb_2u(sch_1):page311_i79@pure_quanta.q_res(chips)',
 P_PATH='@s9s_mb_2u_lib.s9s_mb_2u(sch_1):page216_i79@pure_quanta.q_res(chips)',
 PATH='I79',
 DRAWING='@S9S_MB_2U_LIB.S9S_MB_2U(SCH_1):PAGE311',
 PHYS_PAGE='216',
 XY='(-975,-1150)',
 ROT='0',
 VER='1',
 PACK_TYPE='0402LF',
 CDS_LIB='pure_quanta',
 CDS_PART_NAME='Q_RES_0402LF-33.2,1%,1/16W,CHIA',
 WATTAGE='1/16W',
 TOLERANCE='1%',
 MATERIAL='CHIP',
 VALUE='33.2',
 PRIM_FILE='./archive_libs/logical/q_res/chips/chips.prt';

PART_NAME
 R4752 'Q_RES_0402LF-0,5%,1/16W,CHIP,CA':;

SECTION_NUMBER 1
 '@S9S_MB_2U_LIB.S9S_MB_2U(SCH_1):PAGE153_I45@PURE_QUANTA.Q_RES(CHIPS)':
 C_PATH='@s9s_mb_2u_lib.s9s_mb_2u(sch_1):page153_i45@pure_quanta.q_res(chips)',
 P_PATH='@s9s_mb_2u_lib.s9s_mb_2u(sch_1):page156_i45@pure_quanta.q_res(chips)',
 PATH='I45',
 DRAWING='@S9S_MB_2U_LIB.S9S_MB_2U(SCH_1):PAGE153',
 PHYS_PAGE='156',
 XY='(6750,8725)',
 ROT='0',
 VER='1',
 PACK_TYPE='0402LF',
 CDS_LIB='pure_quanta',
 CDS_PART_NAME='Q_RES_0402LF-0,5%,1/16W,CHIP,CA',
 WATTAGE='1/16W',
 TOLERANCE='5%',
 MATERIAL='CHIP',
 VALUE='0',
 PRIM_FILE='./archive_libs/logical/q_res/chips/chips.prt';

PART_NAME
 R4753 'Q_RES_0402LF-0,5%,1/16W,CHIP,CA':;

SECTION_NUMBER 1
 '@S9S_MB_2U_LIB.S9S_MB_2U(SCH_1):PAGE131_I55@PURE_QUANTA.Q_RES(CHIPS)':
 C_PATH='@s9s_mb_2u_lib.s9s_mb_2u(sch_1):page131_i55@pure_quanta.q_res(chips)',
 P_PATH='@s9s_mb_2u_lib.s9s_mb_2u(sch_1):page162_i55@pure_quanta.q_res(chips)',
 PATH='I55',
 DRAWING='@S9S_MB_2U_LIB.S9S_MB_2U(SCH_1):PAGE131',
 PHYS_PAGE='162',
 XY='(375,-2475)',
 ROT='0',
 VER='1',
 PACK_TYPE='0402LF',
 CDS_LIB='pure_quanta',
 CDS_PART_NAME='Q_RES_0402LF-0,5%,1/16W,CHIP,CA',
 WATTAGE='1/16W',
 TOLERANCE='5%',
 MATERIAL='CHIP',
 VALUE='0',
 PRIM_FILE='./archive_libs/logical/q_res/chips/chips.prt';

PART_NAME
 R4754 'Q_RES_0402LF-33.2,1%,1/16W,CHIA':;

SECTION_NUMBER 1
 '@S9S_MB_2U_LIB.S9S_MB_2U(SCH_1):PAGE132_I104@PURE_QUANTA.Q_RES(CHIPS)':
 C_PATH='@s9s_mb_2u_lib.s9s_mb_2u(sch_1):page132_i104@pure_quanta.q_res(chips)',
 P_PATH='@s9s_mb_2u_lib.s9s_mb_2u(sch_1):page164_i104@pure_quanta.q_res(chips)',
 PATH='I104',
 DRAWING='@S9S_MB_2U_LIB.S9S_MB_2U(SCH_1):PAGE132',
 PHYS_PAGE='164',
 XY='(-550,-350)',
 ROT='0',
 VER='1',
 PACK_TYPE='0402LF',
 CDS_LIB='pure_quanta',
 CDS_PART_NAME='Q_RES_0402LF-33.2,1%,1/16W,CHIA',
 WATTAGE='1/16W',
 TOLERANCE='1%',
 MATERIAL='CHIP',
 VALUE='33.2',
 PRIM_FILE='./archive_libs/logical/q_res/chips/chips.prt';

PART_NAME
 R4755 'Q_RES_0402LF-33.2,1%,1/16W,CHIA':;

SECTION_NUMBER 1
 '@S9S_MB_2U_LIB.S9S_MB_2U(SCH_1):PAGE132_I103@PURE_QUANTA.Q_RES(CHIPS)':
 C_PATH='@s9s_mb_2u_lib.s9s_mb_2u(sch_1):page132_i103@pure_quanta.q_res(chips)',
 P_PATH='@s9s_mb_2u_lib.s9s_mb_2u(sch_1):page164_i103@pure_quanta.q_res(chips)',
 PATH='I103',
 DRAWING='@S9S_MB_2U_LIB.S9S_MB_2U(SCH_1):PAGE132',
 PHYS_PAGE='164',
 XY='(-550,-450)',
 ROT='0',
 VER='1',
 PACK_TYPE='0402LF',
 CDS_LIB='pure_quanta',
 CDS_PART_NAME='Q_RES_0402LF-33.2,1%,1/16W,CHIA',
 WATTAGE='1/16W',
 TOLERANCE='1%',
 MATERIAL='CHIP',
 VALUE='33.2',
 PRIM_FILE='./archive_libs/logical/q_res/chips/chips.prt';

PART_NAME
 R4756 'Q_RES_0402LF-10K,1%,1/16W,CHIPA':;

SECTION_NUMBER 1
 '@S9S_MB_2U_LIB.S9S_MB_2U(SCH_1):PAGE132_I105@PURE_QUANTA.Q_RES(CHIPS)':
 C_PATH='@s9s_mb_2u_lib.s9s_mb_2u(sch_1):page132_i105@pure_quanta.q_res(chips)',
 P_PATH='@s9s_mb_2u_lib.s9s_mb_2u(sch_1):page164_i105@pure_quanta.q_res(chips)',
 PATH='I105',
 DRAWING='@S9S_MB_2U_LIB.S9S_MB_2U(SCH_1):PAGE132',
 PHYS_PAGE='164',
 XY='(-275,0)',
 ROT='0',
 VER='2',
 PACK_TYPE='0402LF',
 CDS_LIB='pure_quanta',
 CDS_PART_NAME='Q_RES_0402LF-10K,1%,1/16W,CHIPA',
 WATTAGE='1/16W',
 TOLERANCE='1%',
 MATERIAL='CHIP',
 VALUE='10K',
 PRIM_FILE='./archive_libs/logical/q_res/chips/chips.prt';

PART_NAME
 R4757 'Q_RES_0402LF-0,5%,1/16W,EMPTY,A':;

SECTION_NUMBER 1
 '@S9S_MB_2U_LIB.S9S_MB_2U(SCH_1):PAGE132_I112@PURE_QUANTA.Q_RES(CHIPS)':
 C_PATH='@s9s_mb_2u_lib.s9s_mb_2u(sch_1):page132_i112@pure_quanta.q_res(chips)',
 P_PATH='@s9s_mb_2u_lib.s9s_mb_2u(sch_1):page164_i112@pure_quanta.q_res(chips)',
 PATH='I112',
 DRAWING='@S9S_MB_2U_LIB.S9S_MB_2U(SCH_1):PAGE132',
 PHYS_PAGE='164',
 XY='(1125,250)',
 ROT='0',
 VER='1',
 PACK_TYPE='0402LF',
 CDS_LIB='pure_quanta',
 CDS_PART_NAME='Q_RES_0402LF-0,5%,1/16W,EMPTY,A',
 WATTAGE='1/16W',
 TOLERANCE='5%',
 MATERIAL='EMPTY',
 VALUE='0',
 PRIM_FILE='./archive_libs/logical/q_res/chips/chips.prt';

PART_NAME
 R4758 'Q_RES_0402LF-0,5%,1/16W,EMPTY,A':;

SECTION_NUMBER 1
 '@S9S_MB_2U_LIB.S9S_MB_2U(SCH_1):PAGE132_I107@PURE_QUANTA.Q_RES(CHIPS)':
 C_PATH='@s9s_mb_2u_lib.s9s_mb_2u(sch_1):page132_i107@pure_quanta.q_res(chips)',
 P_PATH='@s9s_mb_2u_lib.s9s_mb_2u(sch_1):page164_i107@pure_quanta.q_res(chips)',
 PATH='I107',
 DRAWING='@S9S_MB_2U_LIB.S9S_MB_2U(SCH_1):PAGE132',
 PHYS_PAGE='164',
 XY='(1175,-825)',
 ROT='0',
 VER='1',
 PACK_TYPE='0402LF',
 CDS_LIB='pure_quanta',
 CDS_PART_NAME='Q_RES_0402LF-0,5%,1/16W,EMPTY,A',
 WATTAGE='1/16W',
 TOLERANCE='5%',
 MATERIAL='EMPTY',
 VALUE='0',
 PRIM_FILE='./archive_libs/logical/q_res/chips/chips.prt';

PART_NAME
 R4759 'Q_RES_0402LF-49.9,1%,1/16W,CHIA':;

SECTION_NUMBER 1
 '@S9S_MB_2U_LIB.S9S_MB_2U(SCH_1):PAGE132_I111@PURE_QUANTA.Q_RES(CHIPS)':
 C_PATH='@s9s_mb_2u_lib.s9s_mb_2u(sch_1):page132_i111@pure_quanta.q_res(chips)',
 P_PATH='@s9s_mb_2u_lib.s9s_mb_2u(sch_1):page164_i111@pure_quanta.q_res(chips)',
 PATH='I111',
 DRAWING='@S9S_MB_2U_LIB.S9S_MB_2U(SCH_1):PAGE132',
 PHYS_PAGE='164',
 XY='(2175,-500)',
 ROT='0',
 VER='1',
 PACK_TYPE='0402LF',
 CDS_LIB='pure_quanta',
 CDS_PART_NAME='Q_RES_0402LF-49.9,1%,1/16W,CHIA',
 WATTAGE='1/16W',
 TOLERANCE='1%',
 MATERIAL='CHIP',
 VALUE='49.9',
 PRIM_FILE='./archive_libs/logical/q_res/chips/chips.prt';

PART_NAME
 R4760 'Q_RES_0402LF-33.2,1%,1/16W,CHIA':;

SECTION_NUMBER 1
 '@S9S_MB_2U_LIB.S9S_MB_2U(SCH_1):PAGE311_I86@PURE_QUANTA.Q_RES(CHIPS)':
 C_PATH='@s9s_mb_2u_lib.s9s_mb_2u(sch_1):page311_i86@pure_quanta.q_res(chips)',
 P_PATH='@s9s_mb_2u_lib.s9s_mb_2u(sch_1):page216_i86@pure_quanta.q_res(chips)',
 PATH='I86',
 DRAWING='@S9S_MB_2U_LIB.S9S_MB_2U(SCH_1):PAGE311',
 PHYS_PAGE='216',
 XY='(-975,-1300)',
 ROT='0',
 VER='1',
 PACK_TYPE='0402LF',
 CDS_LIB='pure_quanta',
 CDS_PART_NAME='Q_RES_0402LF-33.2,1%,1/16W,CHIA',
 WATTAGE='1/16W',
 TOLERANCE='1%',
 MATERIAL='CHIP',
 VALUE='33.2',
 PRIM_FILE='./archive_libs/logical/q_res/chips/chips.prt';

PART_NAME
 R4761 'Q_RES_0402LF-10K,1%,1/16W,CHIPA':;

SECTION_NUMBER 1
 '@S9S_MB_2U_LIB.S9S_MB_2U(SCH_1):PAGE131_I70@PURE_QUANTA.Q_RES(CHIPS)':
 C_PATH='@s9s_mb_2u_lib.s9s_mb_2u(sch_1):page131_i70@pure_quanta.q_res(chips)',
 P_PATH='@s9s_mb_2u_lib.s9s_mb_2u(sch_1):page162_i70@pure_quanta.q_res(chips)',
 PATH='I70',
 DRAWING='@S9S_MB_2U_LIB.S9S_MB_2U(SCH_1):PAGE131',
 PHYS_PAGE='162',
 XY='(2250,-1900)',
 ROT='0',
 VER='2',
 PACK_TYPE='0402LF',
 CDS_LIB='pure_quanta',
 CDS_PART_NAME='Q_RES_0402LF-10K,1%,1/16W,CHIPA',
 WATTAGE='1/16W',
 TOLERANCE='1%',
 MATERIAL='CHIP',
 VALUE='10K',
 PRIM_FILE='./archive_libs/logical/q_res/chips/chips.prt';

PART_NAME
 R4762 'Q_RES_0402LF-10K,1%,1/16W,CHIPA':;

SECTION_NUMBER 1
 '@S9S_MB_2U_LIB.S9S_MB_2U(SCH_1):PAGE153_I76@PURE_QUANTA.Q_RES(CHIPS)':
 C_PATH='@s9s_mb_2u_lib.s9s_mb_2u(sch_1):page153_i76@pure_quanta.q_res(chips)',
 P_PATH='@s9s_mb_2u_lib.s9s_mb_2u(sch_1):page156_i76@pure_quanta.q_res(chips)',
 PATH='I76',
 DRAWING='@S9S_MB_2U_LIB.S9S_MB_2U(SCH_1):PAGE153',
 PHYS_PAGE='156',
 XY='(8600,9300)',
 ROT='0',
 VER='2',
 PACK_TYPE='0402LF',
 CDS_LIB='pure_quanta',
 CDS_PART_NAME='Q_RES_0402LF-10K,1%,1/16W,CHIPA',
 WATTAGE='1/16W',
 TOLERANCE='1%',
 MATERIAL='CHIP',
 VALUE='10K',
 PRIM_FILE='./archive_libs/logical/q_res/chips/chips.prt';

PART_NAME
 R4763 'Q_RES_0402LF-10K,1%,1/16W,CHIPA':;

SECTION_NUMBER 1
 '@S9S_MB_2U_LIB.S9S_MB_2U(SCH_1):PAGE132_I119@PURE_QUANTA.Q_RES(CHIPS)':
 C_PATH='@s9s_mb_2u_lib.s9s_mb_2u(sch_1):page132_i119@pure_quanta.q_res(chips)',
 P_PATH='@s9s_mb_2u_lib.s9s_mb_2u(sch_1):page164_i119@pure_quanta.q_res(chips)',
 PATH='I119',
 DRAWING='@S9S_MB_2U_LIB.S9S_MB_2U(SCH_1):PAGE132',
 PHYS_PAGE='164',
 XY='(-800,3750)',
 ROT='0',
 VER='2',
 PACK_TYPE='0402LF',
 CDS_LIB='pure_quanta',
 CDS_PART_NAME='Q_RES_0402LF-10K,1%,1/16W,CHIPA',
 WATTAGE='1/16W',
 TOLERANCE='1%',
 MATERIAL='CHIP',
 VALUE='10K',
 PRIM_FILE='./archive_libs/logical/q_res/chips/chips.prt';

PART_NAME
 R4764 'Q_RES_0402LF-10K,1%,1/16W,CHIPA':;

SECTION_NUMBER 1
 '@S9S_MB_2U_LIB.S9S_MB_2U(SCH_1):PAGE154_I257@PURE_QUANTA.Q_RES(CHIPS)':
 C_PATH='@s9s_mb_2u_lib.s9s_mb_2u(sch_1):page154_i257@pure_quanta.q_res(chips)',
 P_PATH='@s9s_mb_2u_lib.s9s_mb_2u(sch_1):page158_i257@pure_quanta.q_res(chips)',
 PATH='I257',
 DRAWING='@S9S_MB_2U_LIB.S9S_MB_2U(SCH_1):PAGE154',
 PHYS_PAGE='158',
 XY='(-275,9875)',
 ROT='0',
 VER='2',
 PACK_TYPE='0402LF',
 CDS_LIB='pure_quanta',
 CDS_PART_NAME='Q_RES_0402LF-10K,1%,1/16W,CHIPA',
 WATTAGE='1/16W',
 TOLERANCE='1%',
 MATERIAL='CHIP',
 VALUE='10K',
 PRIM_FILE='./archive_libs/logical/q_res/chips/chips.prt';

PART_NAME
 R4765 'Q_RES_0402LF-33.2,1%,1/16W,CHIA':;

SECTION_NUMBER 1
 '@S9S_MB_2U_LIB.S9S_MB_2U(SCH_1):PAGE311_I90@PURE_QUANTA.Q_RES(CHIPS)':
 C_PATH='@s9s_mb_2u_lib.s9s_mb_2u(sch_1):page311_i90@pure_quanta.q_res(chips)',
 P_PATH='@s9s_mb_2u_lib.s9s_mb_2u(sch_1):page216_i90@pure_quanta.q_res(chips)',
 PATH='I90',
 DRAWING='@S9S_MB_2U_LIB.S9S_MB_2U(SCH_1):PAGE311',
 PHYS_PAGE='216',
 XY='(-975,-1475)',
 ROT='0',
 VER='1',
 PACK_TYPE='0402LF',
 CDS_LIB='pure_quanta',
 CDS_PART_NAME='Q_RES_0402LF-33.2,1%,1/16W,CHIA',
 WATTAGE='1/16W',
 TOLERANCE='1%',
 MATERIAL='CHIP',
 VALUE='33.2',
 PRIM_FILE='./archive_libs/logical/q_res/chips/chips.prt';

PART_NAME
 R4766 'Q_RES_0402LF-49.9,1%,1/16W,CHIA':;

SECTION_NUMBER 1
 '@S9S_MB_2U_LIB.S9S_MB_2U(SCH_1):PAGE175_I314@PURE_QUANTA.Q_RES(CHIPS)':
 C_PATH='@s9s_mb_2u_lib.s9s_mb_2u(sch_1):page175_i314@pure_quanta.q_res(chips)',
 P_PATH='@s9s_mb_2u_lib.s9s_mb_2u(sch_1):page183_i314@pure_quanta.q_res(chips)',
 PATH='I314',
 DRAWING='@S9S_MB_2U_LIB.S9S_MB_2U(SCH_1):PAGE175',
 PHYS_PAGE='183',
 XY='(-2700,3775)',
 ROT='0',
 VER='1',
 PACK_TYPE='0402LF',
 LOCATION='R4766',
 CDS_LIB='pure_quanta',
 CDS_PART_NAME='Q_RES_0402LF-49.9,1%,1/16W,CHIA',
 WATTAGE='1/16W',
 TOLERANCE='1%',
 MATERIAL='CHIP',
 VALUE='49.9',
 PRIM_FILE='./archive_libs/logical/q_res/chips/chips.prt';

PART_NAME
 R4767 'Q_RES_0402LF-49.9,1%,1/16W,CHIA':;

SECTION_NUMBER 1
 '@S9S_MB_2U_LIB.S9S_MB_2U(SCH_1):PAGE297_I331@PURE_QUANTA.Q_RES(CHIPS)':
 C_PATH='@s9s_mb_2u_lib.s9s_mb_2u(sch_1):page297_i331@pure_quanta.q_res(chips)',
 P_PATH='@s9s_mb_2u_lib.s9s_mb_2u(sch_1):page191_i331@pure_quanta.q_res(chips)',
 PATH='I331',
 DRAWING='@S9S_MB_2U_LIB.S9S_MB_2U(SCH_1):PAGE297',
 PHYS_PAGE='191',
 XY='(-1400,1150)',
 ROT='0',
 VER='1',
 PACK_TYPE='0402LF',
 CDS_LIB='pure_quanta',
 CDS_PART_NAME='Q_RES_0402LF-49.9,1%,1/16W,CHIA',
 WATTAGE='1/16W',
 TOLERANCE='1%',
 MATERIAL='CHIP',
 VALUE='49.9',
 PRIM_FILE='./archive_libs/logical/q_res/chips/chips.prt';

PART_NAME
 R4768 'Q_RES_0402LF-10K,1%,1/16W,CHIPA':;

SECTION_NUMBER 1
 '@S9S_MB_2U_LIB.S9S_MB_2U(SCH_1):PAGE175_I315@PURE_QUANTA.Q_RES(CHIPS)':
 C_PATH='@s9s_mb_2u_lib.s9s_mb_2u(sch_1):page175_i315@pure_quanta.q_res(chips)',
 P_PATH='@s9s_mb_2u_lib.s9s_mb_2u(sch_1):page183_i315@pure_quanta.q_res(chips)',
 PATH='I315',
 DRAWING='@S9S_MB_2U_LIB.S9S_MB_2U(SCH_1):PAGE175',
 PHYS_PAGE='183',
 XY='(3475,-1350)',
 ROT='0',
 VER='1',
 PACK_TYPE='0402LF',
 CDS_LIB='pure_quanta',
 CDS_PART_NAME='Q_RES_0402LF-10K,1%,1/16W,CHIPA',
 WATTAGE='1/16W',
 TOLERANCE='1%',
 MATERIAL='CHIP',
 VALUE='10K',
 PRIM_FILE='./archive_libs/logical/q_res/chips/chips.prt';

PART_NAME
 R4769 'Q_RES_0402LF-100K,1%,1/16W,CHIA':;

SECTION_NUMBER 1
 '@S9S_MB_2U_LIB.S9S_MB_2U(SCH_1):PAGE233_I3@PURE_QUANTA.Q_RES(CHIPS)':
 C_PATH='@s9s_mb_2u_lib.s9s_mb_2u(sch_1):page233_i3@pure_quanta.q_res(chips)',
 P_PATH='@s9s_mb_2u_lib.s9s_mb_2u(sch_1):page245_i3@pure_quanta.q_res(chips)',
 PATH='I3',
 DRAWING='@S9S_MB_2U_LIB.S9S_MB_2U(SCH_1):PAGE233',
 PHYS_PAGE='245',
 XY='(-5725,-2250)',
 ROT='0',
 VER='2',
 PACK_TYPE='0402LF',
 CDS_LIB='pure_quanta',
 CDS_PART_NAME='Q_RES_0402LF-100K,1%,1/16W,CHIA',
 WATTAGE='1/16W',
 TOLERANCE='1%',
 MATERIAL='CHIP',
 VALUE='100K',
 PRIM_FILE='./archive_libs/logical/q_res/chips/chips.prt';

PART_NAME
 R4770 'Q_RES_0402LF-0,5%,1/16W,CHIP,CA':
 ROOM='SCM_P12V_BOM2';

SECTION_NUMBER 1
 '@S9S_MB_2U_LIB.S9S_MB_2U(SCH_1):PAGE229_I91@PURE_QUANTA.Q_RES(CHIPS)':
 C_PATH='@s9s_mb_2u_lib.s9s_mb_2u(sch_1):page229_i91@pure_quanta.q_res(chips)',
 P_PATH='@s9s_mb_2u_lib.s9s_mb_2u(sch_1):page242_i91@pure_quanta.q_res(chips)',
 PATH='I91',
 DRAWING='@S9S_MB_2U_LIB.S9S_MB_2U(SCH_1):PAGE229',
 PHYS_PAGE='242',
 XY='(2425,-900)',
 ROT='0',
 VER='1',
 PACK_TYPE='0402LF',
 CDS_LIB='pure_quanta',
 CDS_PART_NAME='Q_RES_0402LF-0,5%,1/16W,CHIP,CA',
 WATTAGE='1/16W',
 TOLERANCE='5%',
 MATERIAL='CHIP',
 ROOM='SCM_P12V_BOM2',
 VALUE='0',
 PRIM_FILE='./archive_libs/logical/q_res/chips/chips.prt';

PART_NAME
 R4771 'Q_RES_0402LF-33.2,1%,1/16W,CHIA':;

SECTION_NUMBER 1
 '@S9S_MB_2U_LIB.S9S_MB_2U(SCH_1):PAGE311_I95@PURE_QUANTA.Q_RES(CHIPS)':
 C_PATH='@s9s_mb_2u_lib.s9s_mb_2u(sch_1):page311_i95@pure_quanta.q_res(chips)',
 P_PATH='@s9s_mb_2u_lib.s9s_mb_2u(sch_1):page216_i95@pure_quanta.q_res(chips)',
 PATH='I95',
 DRAWING='@S9S_MB_2U_LIB.S9S_MB_2U(SCH_1):PAGE311',
 PHYS_PAGE='216',
 XY='(-975,-1625)',
 ROT='0',
 VER='1',
 PACK_TYPE='0402LF',
 CDS_LIB='pure_quanta',
 CDS_PART_NAME='Q_RES_0402LF-33.2,1%,1/16W,CHIA',
 WATTAGE='1/16W',
 TOLERANCE='1%',
 MATERIAL='CHIP',
 VALUE='33.2',
 PRIM_FILE='./archive_libs/logical/q_res/chips/chips.prt';

PART_NAME
 R4772 'Q_RES_0402LF-10K,1%,1/16W,EMPTA':;

SECTION_NUMBER 1
 '@S9S_MB_2U_LIB.S9S_MB_2U(SCH_1):PAGE329_I21@PURE_QUANTA.Q_RES(CHIPS)':
 C_PATH='@s9s_mb_2u_lib.s9s_mb_2u(sch_1):page329_i21@pure_quanta.q_res(chips)',
 P_PATH='@s9s_mb_2u_lib.s9s_mb_2u(sch_1):page307_i21@pure_quanta.q_res(chips)',
 PATH='I21',
 DRAWING='@S9S_MB_2U_LIB.S9S_MB_2U(SCH_1):PAGE329',
 PHYS_PAGE='307',
 XY='(-2100,3450)',
 ROT='0',
 VER='2',
 PACK_TYPE='0402LF',
 CDS_LIB='pure_quanta',
 CDS_PART_NAME='Q_RES_0402LF-10K,1%,1/16W,EMPTA',
 WATTAGE='1/16W',
 TOLERANCE='1%',
 MATERIAL='EMPTY',
 VALUE='10K',
 PRIM_FILE='./archive_libs/logical/q_res/chips/chips.prt';

PART_NAME
 R4773 'Q_RES_0402LF-10K,1%,1/16W,EMPTA':;

SECTION_NUMBER 1
 '@S9S_MB_2U_LIB.S9S_MB_2U(SCH_1):PAGE329_I42@PURE_QUANTA.Q_RES(CHIPS)':
 C_PATH='@s9s_mb_2u_lib.s9s_mb_2u(sch_1):page329_i42@pure_quanta.q_res(chips)',
 P_PATH='@s9s_mb_2u_lib.s9s_mb_2u(sch_1):page307_i42@pure_quanta.q_res(chips)',
 PATH='I42',
 DRAWING='@S9S_MB_2U_LIB.S9S_MB_2U(SCH_1):PAGE329',
 PHYS_PAGE='307',
 XY='(-2075,1325)',
 ROT='0',
 VER='2',
 PACK_TYPE='0402LF',
 CDS_LIB='pure_quanta',
 CDS_PART_NAME='Q_RES_0402LF-10K,1%,1/16W,EMPTA',
 WATTAGE='1/16W',
 TOLERANCE='1%',
 MATERIAL='EMPTY',
 VALUE='10K',
 PRIM_FILE='./archive_libs/logical/q_res/chips/chips.prt';

PART_NAME
 R4774 'Q_RES_0402LF-17.8K,1%,1/16W,EMA':;

SECTION_NUMBER 1
 '@S9S_MB_2U_LIB.S9S_MB_2U(SCH_1):PAGE329_I17@PURE_QUANTA.Q_RES(CHIPS)':
 C_PATH='@s9s_mb_2u_lib.s9s_mb_2u(sch_1):page329_i17@pure_quanta.q_res(chips)',
 P_PATH='@s9s_mb_2u_lib.s9s_mb_2u(sch_1):page307_i17@pure_quanta.q_res(chips)',
 PATH='I17',
 DRAWING='@S9S_MB_2U_LIB.S9S_MB_2U(SCH_1):PAGE329',
 PHYS_PAGE='307',
 XY='(-1100,3500)',
 ROT='0',
 VER='2',
 PACK_TYPE='0402LF',
 CDS_LIB='pure_quanta',
 CDS_PART_NAME='Q_RES_0402LF-17.8K,1%,1/16W,EMA',
 WATTAGE='1/16W',
 TOLERANCE='1%',
 MATERIAL='EMPTY',
 VALUE='17.8K',
 PRIM_FILE='./archive_libs/logical/q_res/chips/chips.prt';

PART_NAME
 R4775 'Q_RES_0402LF-5.11K,1%,1/16W,EMA':;

SECTION_NUMBER 1
 '@S9S_MB_2U_LIB.S9S_MB_2U(SCH_1):PAGE329_I2@PURE_QUANTA.Q_RES(CHIPS)':
 C_PATH='@s9s_mb_2u_lib.s9s_mb_2u(sch_1):page329_i2@pure_quanta.q_res(chips)',
 P_PATH='@s9s_mb_2u_lib.s9s_mb_2u(sch_1):page307_i2@pure_quanta.q_res(chips)',
 PATH='I2',
 DRAWING='@S9S_MB_2U_LIB.S9S_MB_2U(SCH_1):PAGE329',
 PHYS_PAGE='307',
 XY='(-1100,2825)',
 ROT='0',
 VER='2',
 PACK_TYPE='0402LF',
 CDS_LIB='pure_quanta',
 CDS_PART_NAME='Q_RES_0402LF-5.11K,1%,1/16W,EMA',
 WATTAGE='1/16W',
 TOLERANCE='1%',
 MATERIAL='EMPTY',
 VALUE='5.11K',
 PRIM_FILE='./archive_libs/logical/q_res/chips/chips.prt';

PART_NAME
 R4776 'Q_RES_0402LF-17.8K,1%,1/16W,EMA':;

SECTION_NUMBER 1
 '@S9S_MB_2U_LIB.S9S_MB_2U(SCH_1):PAGE329_I38@PURE_QUANTA.Q_RES(CHIPS)':
 C_PATH='@s9s_mb_2u_lib.s9s_mb_2u(sch_1):page329_i38@pure_quanta.q_res(chips)',
 P_PATH='@s9s_mb_2u_lib.s9s_mb_2u(sch_1):page307_i38@pure_quanta.q_res(chips)',
 PATH='I38',
 DRAWING='@S9S_MB_2U_LIB.S9S_MB_2U(SCH_1):PAGE329',
 PHYS_PAGE='307',
 XY='(-1075,1375)',
 ROT='0',
 VER='2',
 PACK_TYPE='0402LF',
 CDS_LIB='pure_quanta',
 CDS_PART_NAME='Q_RES_0402LF-17.8K,1%,1/16W,EMA',
 WATTAGE='1/16W',
 TOLERANCE='1%',
 MATERIAL='EMPTY',
 VALUE='17.8K',
 PRIM_FILE='./archive_libs/logical/q_res/chips/chips.prt';

PART_NAME
 R4777 'Q_RES_0402LF-5.11K,1%,1/16W,EMA':;

SECTION_NUMBER 1
 '@S9S_MB_2U_LIB.S9S_MB_2U(SCH_1):PAGE329_I39@PURE_QUANTA.Q_RES(CHIPS)':
 C_PATH='@s9s_mb_2u_lib.s9s_mb_2u(sch_1):page329_i39@pure_quanta.q_res(chips)',
 P_PATH='@s9s_mb_2u_lib.s9s_mb_2u(sch_1):page307_i39@pure_quanta.q_res(chips)',
 PATH='I39',
 DRAWING='@S9S_MB_2U_LIB.S9S_MB_2U(SCH_1):PAGE329',
 PHYS_PAGE='307',
 XY='(-1075,700)',
 ROT='0',
 VER='2',
 PACK_TYPE='0402LF',
 CDS_LIB='pure_quanta',
 CDS_PART_NAME='Q_RES_0402LF-5.11K,1%,1/16W,EMA',
 WATTAGE='1/16W',
 TOLERANCE='1%',
 MATERIAL='EMPTY',
 VALUE='5.11K',
 PRIM_FILE='./archive_libs/logical/q_res/chips/chips.prt';

PART_NAME
 R4778 'Q_RES_0402LF-1M,1%,1/16W,CHIP,A':;

SECTION_NUMBER 1
 '@S9S_MB_2U_LIB.S9S_MB_2U(SCH_1):PAGE329_I9@PURE_QUANTA.Q_RES(CHIPS)':
 C_PATH='@s9s_mb_2u_lib.s9s_mb_2u(sch_1):page329_i9@pure_quanta.q_res(chips)',
 P_PATH='@s9s_mb_2u_lib.s9s_mb_2u(sch_1):page307_i9@pure_quanta.q_res(chips)',
 PATH='I9',
 DRAWING='@S9S_MB_2U_LIB.S9S_MB_2U(SCH_1):PAGE329',
 PHYS_PAGE='307',
 XY='(525,3550)',
 ROT='0',
 VER='1',
 PACK_TYPE='0402LF',
 CDS_LIB='pure_quanta',
 CDS_PART_NAME='Q_RES_0402LF-1M,1%,1/16W,CHIP,A',
 WATTAGE='1/16W',
 TOLERANCE='1%',
 MATERIAL='CHIP',
 VALUE='1M',
 PRIM_FILE='./archive_libs/logical/q_res/chips/chips.prt';

PART_NAME
 R4779 'Q_RES_0402LF-1M,1%,1/16W,CHIP,A':;

SECTION_NUMBER 1
 '@S9S_MB_2U_LIB.S9S_MB_2U(SCH_1):PAGE329_I31@PURE_QUANTA.Q_RES(CHIPS)':
 C_PATH='@s9s_mb_2u_lib.s9s_mb_2u(sch_1):page329_i31@pure_quanta.q_res(chips)',
 P_PATH='@s9s_mb_2u_lib.s9s_mb_2u(sch_1):page307_i31@pure_quanta.q_res(chips)',
 PATH='I31',
 DRAWING='@S9S_MB_2U_LIB.S9S_MB_2U(SCH_1):PAGE329',
 PHYS_PAGE='307',
 XY='(550,1425)',
 ROT='0',
 VER='1',
 PACK_TYPE='0402LF',
 CDS_LIB='pure_quanta',
 CDS_PART_NAME='Q_RES_0402LF-1M,1%,1/16W,CHIP,A',
 WATTAGE='1/16W',
 TOLERANCE='1%',
 MATERIAL='CHIP',
 VALUE='1M',
 PRIM_FILE='./archive_libs/logical/q_res/chips/chips.prt';

PART_NAME
 R4780 'Q_RES_0402LF-0,5%,1/16W,CHIP,CA':;

SECTION_NUMBER 1
 '@S9S_MB_2U_LIB.S9S_MB_2U(SCH_1):PAGE248_I52@PURE_QUANTA.Q_RES(CHIPS)':
 C_PATH='@s9s_mb_2u_lib.s9s_mb_2u(sch_1):page248_i52@pure_quanta.q_res(chips)',
 P_PATH='@s9s_mb_2u_lib.s9s_mb_2u(sch_1):page262_i52@pure_quanta.q_res(chips)',
 PATH='I52',
 DRAWING='@S9S_MB_2U_LIB.S9S_MB_2U(SCH_1):PAGE248',
 PHYS_PAGE='262',
 XY='(975,275)',
 ROT='0',
 VER='1',
 PACK_TYPE='0402LF',
 LOCATION='R4780',
 CDS_LIB='pure_quanta',
 CDS_PART_NAME='Q_RES_0402LF-0,5%,1/16W,CHIP,CA',
 WATTAGE='1/16W',
 TOLERANCE='5%',
 MATERIAL='CHIP',
 VALUE='0',
 PRIM_FILE='./archive_libs/logical/q_res/chips/chips.prt';

PART_NAME
 R4781 'Q_RES_0402LF-0,5%,1/16W,CHIP,CA':;

SECTION_NUMBER 1
 '@S9S_MB_2U_LIB.S9S_MB_2U(SCH_1):PAGE278_I103@PURE_QUANTA.Q_RES(CHIPS)':
 C_PATH='@s9s_mb_2u_lib.s9s_mb_2u(sch_1):page278_i103@pure_quanta.q_res(chips)',
 P_PATH='@s9s_mb_2u_lib.s9s_mb_2u(sch_1):page292_i103@pure_quanta.q_res(chips)',
 PATH='I103',
 DRAWING='@S9S_MB_2U_LIB.S9S_MB_2U(SCH_1):PAGE278',
 PHYS_PAGE='292',
 XY='(1175,9150)',
 ROT='0',
 VER='1',
 PACK_TYPE='0402LF',
 LOCATION='R4781',
 CDS_LIB='pure_quanta',
 CDS_PART_NAME='Q_RES_0402LF-0,5%,1/16W,CHIP,CA',
 WATTAGE='1/16W',
 TOLERANCE='5%',
 MATERIAL='CHIP',
 VALUE='0',
 PRIM_FILE='./archive_libs/logical/q_res/chips/chips.prt';

PART_NAME
 R4782 'Q_RES_0402LF-33.2,1%,1/16W,EMPA':;

SECTION_NUMBER 1
 '@S9S_MB_2U_LIB.S9S_MB_2U(SCH_1):PAGE329_I7@PURE_QUANTA.Q_RES(CHIPS)':
 C_PATH='@s9s_mb_2u_lib.s9s_mb_2u(sch_1):page329_i7@pure_quanta.q_res(chips)',
 P_PATH='@s9s_mb_2u_lib.s9s_mb_2u(sch_1):page307_i7@pure_quanta.q_res(chips)',
 PATH='I7',
 DRAWING='@S9S_MB_2U_LIB.S9S_MB_2U(SCH_1):PAGE329',
 PHYS_PAGE='307',
 XY='(1450,3225)',
 ROT='0',
 VER='1',
 PACK_TYPE='0402LF',
 CDS_LIB='pure_quanta',
 CDS_PART_NAME='Q_RES_0402LF-33.2,1%,1/16W,EMPA',
 WATTAGE='1/16W',
 TOLERANCE='1%',
 MATERIAL='EMPTY',
 VALUE='33.2',
 PRIM_FILE='./archive_libs/logical/q_res/chips/chips.prt';

PART_NAME
 R4783 'Q_RES_0402LF-33.2,1%,1/16W,EMPA':;

SECTION_NUMBER 1
 '@S9S_MB_2U_LIB.S9S_MB_2U(SCH_1):PAGE329_I27@PURE_QUANTA.Q_RES(CHIPS)':
 C_PATH='@s9s_mb_2u_lib.s9s_mb_2u(sch_1):page329_i27@pure_quanta.q_res(chips)',
 P_PATH='@s9s_mb_2u_lib.s9s_mb_2u(sch_1):page307_i27@pure_quanta.q_res(chips)',
 PATH='I27',
 DRAWING='@S9S_MB_2U_LIB.S9S_MB_2U(SCH_1):PAGE329',
 PHYS_PAGE='307',
 XY='(1475,1100)',
 ROT='0',
 VER='1',
 PACK_TYPE='0402LF',
 CDS_LIB='pure_quanta',
 CDS_PART_NAME='Q_RES_0402LF-33.2,1%,1/16W,EMPA',
 WATTAGE='1/16W',
 TOLERANCE='1%',
 MATERIAL='EMPTY',
 VALUE='33.2',
 PRIM_FILE='./archive_libs/logical/q_res/chips/chips.prt';

PART_NAME
 R4784 'Q_RES_0402LF-10K,1%,1/16W,EMPTA':;

SECTION_NUMBER 1
 '@S9S_MB_2U_LIB.S9S_MB_2U(SCH_1):PAGE329_I6@PURE_QUANTA.Q_RES(CHIPS)':
 C_PATH='@s9s_mb_2u_lib.s9s_mb_2u(sch_1):page329_i6@pure_quanta.q_res(chips)',
 P_PATH='@s9s_mb_2u_lib.s9s_mb_2u(sch_1):page307_i6@pure_quanta.q_res(chips)',
 PATH='I6',
 DRAWING='@S9S_MB_2U_LIB.S9S_MB_2U(SCH_1):PAGE329',
 PHYS_PAGE='307',
 XY='(2425,3500)',
 ROT='0',
 VER='2',
 PACK_TYPE='0402LF',
 CDS_LIB='pure_quanta',
 CDS_PART_NAME='Q_RES_0402LF-10K,1%,1/16W,EMPTA',
 WATTAGE='1/16W',
 TOLERANCE='1%',
 MATERIAL='EMPTY',
 VALUE='10K',
 PRIM_FILE='./archive_libs/logical/q_res/chips/chips.prt';

PART_NAME
 R4785 'Q_RES_0402LF-10K,1%,1/16W,EMPTA':;

SECTION_NUMBER 1
 '@S9S_MB_2U_LIB.S9S_MB_2U(SCH_1):PAGE329_I25@PURE_QUANTA.Q_RES(CHIPS)':
 C_PATH='@s9s_mb_2u_lib.s9s_mb_2u(sch_1):page329_i25@pure_quanta.q_res(chips)',
 P_PATH='@s9s_mb_2u_lib.s9s_mb_2u(sch_1):page307_i25@pure_quanta.q_res(chips)',
 PATH='I25',
 DRAWING='@S9S_MB_2U_LIB.S9S_MB_2U(SCH_1):PAGE329',
 PHYS_PAGE='307',
 XY='(2450,1375)',
 ROT='0',
 VER='2',
 PACK_TYPE='0402LF',
 CDS_LIB='pure_quanta',
 CDS_PART_NAME='Q_RES_0402LF-10K,1%,1/16W,EMPTA',
 WATTAGE='1/16W',
 TOLERANCE='1%',
 MATERIAL='EMPTY',
 VALUE='10K',
 PRIM_FILE='./archive_libs/logical/q_res/chips/chips.prt';

PART_NAME
 R4786 'Q_RES_0402LF-10K,1%,1/16W,EMPTA':;

SECTION_NUMBER 1
 '@S9S_MB_2U_LIB.S9S_MB_2U(SCH_1):PAGE329_I65@PURE_QUANTA.Q_RES(CHIPS)':
 C_PATH='@s9s_mb_2u_lib.s9s_mb_2u(sch_1):page329_i65@pure_quanta.q_res(chips)',
 P_PATH='@s9s_mb_2u_lib.s9s_mb_2u(sch_1):page307_i65@pure_quanta.q_res(chips)',
 PATH='I65',
 DRAWING='@S9S_MB_2U_LIB.S9S_MB_2U(SCH_1):PAGE329',
 PHYS_PAGE='307',
 XY='(-2075,-550)',
 ROT='0',
 VER='2',
 PACK_TYPE='0402LF',
 CDS_LIB='pure_quanta',
 CDS_PART_NAME='Q_RES_0402LF-10K,1%,1/16W,EMPTA',
 WATTAGE='1/16W',
 TOLERANCE='1%',
 MATERIAL='EMPTY',
 VALUE='10K',
 PRIM_FILE='./archive_libs/logical/q_res/chips/chips.prt';

PART_NAME
 R4787 'Q_RES_0402LF-1M,1%,1/16W,EMPTYA':;

SECTION_NUMBER 1
 '@S9S_MB_2U_LIB.S9S_MB_2U(SCH_1):PAGE329_I46@PURE_QUANTA.Q_RES(CHIPS)':
 C_PATH='@s9s_mb_2u_lib.s9s_mb_2u(sch_1):page329_i46@pure_quanta.q_res(chips)',
 P_PATH='@s9s_mb_2u_lib.s9s_mb_2u(sch_1):page307_i46@pure_quanta.q_res(chips)',
 PATH='I46',
 DRAWING='@S9S_MB_2U_LIB.S9S_MB_2U(SCH_1):PAGE329',
 PHYS_PAGE='307',
 XY='(550,-450)',
 ROT='0',
 VER='1',
 PACK_TYPE='0402LF',
 CDS_LIB='pure_quanta',
 CDS_PART_NAME='Q_RES_0402LF-1M,1%,1/16W,EMPTYA',
 WATTAGE='1/16W',
 TOLERANCE='1%',
 MATERIAL='EMPTY',
 VALUE='1M',
 PRIM_FILE='./archive_libs/logical/q_res/chips/chips.prt';

PART_NAME
 R4788 'Q_RES_0402LF-33.2,1%,1/16W,EMPA':;

SECTION_NUMBER 1
 '@S9S_MB_2U_LIB.S9S_MB_2U(SCH_1):PAGE329_I50@PURE_QUANTA.Q_RES(CHIPS)':
 C_PATH='@s9s_mb_2u_lib.s9s_mb_2u(sch_1):page329_i50@pure_quanta.q_res(chips)',
 P_PATH='@s9s_mb_2u_lib.s9s_mb_2u(sch_1):page307_i50@pure_quanta.q_res(chips)',
 PATH='I50',
 DRAWING='@S9S_MB_2U_LIB.S9S_MB_2U(SCH_1):PAGE329',
 PHYS_PAGE='307',
 XY='(1475,-775)',
 ROT='0',
 VER='1',
 PACK_TYPE='0402LF',
 CDS_LIB='pure_quanta',
 CDS_PART_NAME='Q_RES_0402LF-33.2,1%,1/16W,EMPA',
 WATTAGE='1/16W',
 TOLERANCE='1%',
 MATERIAL='EMPTY',
 VALUE='33.2',
 PRIM_FILE='./archive_libs/logical/q_res/chips/chips.prt';

PART_NAME
 R4789 'Q_RES_0402LF-10K,1%,1/16W,EMPTA':;

SECTION_NUMBER 1
 '@S9S_MB_2U_LIB.S9S_MB_2U(SCH_1):PAGE329_I49@PURE_QUANTA.Q_RES(CHIPS)':
 C_PATH='@s9s_mb_2u_lib.s9s_mb_2u(sch_1):page329_i49@pure_quanta.q_res(chips)',
 P_PATH='@s9s_mb_2u_lib.s9s_mb_2u(sch_1):page307_i49@pure_quanta.q_res(chips)',
 PATH='I49',
 DRAWING='@S9S_MB_2U_LIB.S9S_MB_2U(SCH_1):PAGE329',
 PHYS_PAGE='307',
 XY='(2450,-500)',
 ROT='0',
 VER='2',
 PACK_TYPE='0402LF',
 CDS_LIB='pure_quanta',
 CDS_PART_NAME='Q_RES_0402LF-10K,1%,1/16W,EMPTA',
 WATTAGE='1/16W',
 TOLERANCE='1%',
 MATERIAL='EMPTY',
 VALUE='10K',
 PRIM_FILE='./archive_libs/logical/q_res/chips/chips.prt';

PART_NAME
 R4790 'Q_RES_0402LF-4.75K,1%,1/16W,EMA':;

SECTION_NUMBER 1
 '@S9S_MB_2U_LIB.S9S_MB_2U(SCH_1):PAGE329_I67@PURE_QUANTA.Q_RES(CHIPS)':
 C_PATH='@s9s_mb_2u_lib.s9s_mb_2u(sch_1):page329_i67@pure_quanta.q_res(chips)',
 P_PATH='@s9s_mb_2u_lib.s9s_mb_2u(sch_1):page307_i67@pure_quanta.q_res(chips)',
 PATH='I67',
 DRAWING='@S9S_MB_2U_LIB.S9S_MB_2U(SCH_1):PAGE329',
 PHYS_PAGE='307',
 XY='(-1075,-500)',
 ROT='0',
 VER='2',
 PACK_TYPE='0402LF',
 CDS_LIB='pure_quanta',
 CDS_PART_NAME='Q_RES_0402LF-4.75K,1%,1/16W,EMA',
 WATTAGE='1/16W',
 TOLERANCE='1%',
 MATERIAL='EMPTY',
 VALUE='4.75K',
 PRIM_FILE='./archive_libs/logical/q_res/chips/chips.prt';

PART_NAME
 R4791 'Q_RES_0402LF-2K,1%,1/16W,EMPTYA':;

SECTION_NUMBER 1
 '@S9S_MB_2U_LIB.S9S_MB_2U(SCH_1):PAGE329_I68@PURE_QUANTA.Q_RES(CHIPS)':
 C_PATH='@s9s_mb_2u_lib.s9s_mb_2u(sch_1):page329_i68@pure_quanta.q_res(chips)',
 P_PATH='@s9s_mb_2u_lib.s9s_mb_2u(sch_1):page307_i68@pure_quanta.q_res(chips)',
 PATH='I68',
 DRAWING='@S9S_MB_2U_LIB.S9S_MB_2U(SCH_1):PAGE329',
 PHYS_PAGE='307',
 XY='(-1075,-1175)',
 ROT='0',
 VER='2',
 PACK_TYPE='0402LF',
 CDS_LIB='pure_quanta',
 CDS_PART_NAME='Q_RES_0402LF-2K,1%,1/16W,EMPTYA',
 WATTAGE='1/16W',
 TOLERANCE='1%',
 MATERIAL='EMPTY',
 VALUE='2K',
 PRIM_FILE='./archive_libs/logical/q_res/chips/chips.prt';

PART_NAME
 R4792 'Q_RES_0402LF-10K,1%,1/16W,EMPTA':;

SECTION_NUMBER 1
 '@S9S_MB_2U_LIB.S9S_MB_2U(SCH_1):PAGE326_I57@PURE_QUANTA.Q_RES(CHIPS)':
 C_PATH='@s9s_mb_2u_lib.s9s_mb_2u(sch_1):page326_i57@pure_quanta.q_res(chips)',
 P_PATH='@s9s_mb_2u_lib.s9s_mb_2u(sch_1):page306_i57@pure_quanta.q_res(chips)',
 PATH='I57',
 DRAWING='@S9S_MB_2U_LIB.S9S_MB_2U(SCH_1):PAGE326',
 PHYS_PAGE='306',
 XY='(-1275,1975)',
 ROT='0',
 VER='2',
 PACK_TYPE='0402LF',
 CDS_LIB='pure_quanta',
 CDS_PART_NAME='Q_RES_0402LF-10K,1%,1/16W,EMPTA',
 WATTAGE='1/16W',
 TOLERANCE='1%',
 MATERIAL='EMPTY',
 VALUE='10K',
 PRIM_FILE='./archive_libs/logical/q_res/chips/chips.prt';

PART_NAME
 R4793 'Q_RES_0402LF-1M,1%,1/16W,EMPTYA':;

SECTION_NUMBER 1
 '@S9S_MB_2U_LIB.S9S_MB_2U(SCH_1):PAGE326_I68@PURE_QUANTA.Q_RES(CHIPS)':
 C_PATH='@s9s_mb_2u_lib.s9s_mb_2u(sch_1):page326_i68@pure_quanta.q_res(chips)',
 P_PATH='@s9s_mb_2u_lib.s9s_mb_2u(sch_1):page306_i68@pure_quanta.q_res(chips)',
 PATH='I68',
 DRAWING='@S9S_MB_2U_LIB.S9S_MB_2U(SCH_1):PAGE326',
 PHYS_PAGE='306',
 XY='(1350,2075)',
 ROT='0',
 VER='1',
 PACK_TYPE='0402LF',
 CDS_LIB='pure_quanta',
 CDS_PART_NAME='Q_RES_0402LF-1M,1%,1/16W,EMPTYA',
 WATTAGE='1/16W',
 TOLERANCE='1%',
 MATERIAL='EMPTY',
 VALUE='1M',
 PRIM_FILE='./archive_libs/logical/q_res/chips/chips.prt';

PART_NAME
 R4794 'Q_RES_0402LF-33.2,1%,1/16W,EMPA':;

SECTION_NUMBER 1
 '@S9S_MB_2U_LIB.S9S_MB_2U(SCH_1):PAGE326_I72@PURE_QUANTA.Q_RES(CHIPS)':
 C_PATH='@s9s_mb_2u_lib.s9s_mb_2u(sch_1):page326_i72@pure_quanta.q_res(chips)',
 P_PATH='@s9s_mb_2u_lib.s9s_mb_2u(sch_1):page306_i72@pure_quanta.q_res(chips)',
 PATH='I72',
 DRAWING='@S9S_MB_2U_LIB.S9S_MB_2U(SCH_1):PAGE326',
 PHYS_PAGE='306',
 XY='(2275,1750)',
 ROT='0',
 VER='1',
 PACK_TYPE='0402LF',
 CDS_LIB='pure_quanta',
 CDS_PART_NAME='Q_RES_0402LF-33.2,1%,1/16W,EMPA',
 WATTAGE='1/16W',
 TOLERANCE='1%',
 MATERIAL='EMPTY',
 VALUE='33.2',
 PRIM_FILE='./archive_libs/logical/q_res/chips/chips.prt';

PART_NAME
 R4795 'Q_RES_0402LF-160K,1%,1/16W,EMPA':;

SECTION_NUMBER 1
 '@S9S_MB_2U_LIB.S9S_MB_2U(SCH_1):PAGE326_I78@PURE_QUANTA.Q_RES(CHIPS)':
 C_PATH='@s9s_mb_2u_lib.s9s_mb_2u(sch_1):page326_i78@pure_quanta.q_res(chips)',
 P_PATH='@s9s_mb_2u_lib.s9s_mb_2u(sch_1):page306_i78@pure_quanta.q_res(chips)',
 PATH='I78',
 DRAWING='@S9S_MB_2U_LIB.S9S_MB_2U(SCH_1):PAGE326',
 PHYS_PAGE='306',
 XY='(-275,2025)',
 ROT='0',
 VER='2',
 PACK_TYPE='0402LF',
 CDS_LIB='pure_quanta',
 CDS_PART_NAME='Q_RES_0402LF-160K,1%,1/16W,EMPA',
 WATTAGE='1/16W',
 TOLERANCE='1%',
 MATERIAL='EMPTY',
 VALUE='160K',
 PRIM_FILE='./archive_libs/logical/q_res/chips/chips.prt';

PART_NAME
 R4796 'Q_RES_0402LF-10K,1%,1/16W,EMPTA':;

SECTION_NUMBER 1
 '@S9S_MB_2U_LIB.S9S_MB_2U(SCH_1):PAGE326_I77@PURE_QUANTA.Q_RES(CHIPS)':
 C_PATH='@s9s_mb_2u_lib.s9s_mb_2u(sch_1):page326_i77@pure_quanta.q_res(chips)',
 P_PATH='@s9s_mb_2u_lib.s9s_mb_2u(sch_1):page306_i77@pure_quanta.q_res(chips)',
 PATH='I77',
 DRAWING='@S9S_MB_2U_LIB.S9S_MB_2U(SCH_1):PAGE326',
 PHYS_PAGE='306',
 XY='(-275,1350)',
 ROT='0',
 VER='2',
 PACK_TYPE='0402LF',
 CDS_LIB='pure_quanta',
 CDS_PART_NAME='Q_RES_0402LF-10K,1%,1/16W,EMPTA',
 WATTAGE='1/16W',
 TOLERANCE='1%',
 MATERIAL='EMPTY',
 VALUE='10K',
 PRIM_FILE='./archive_libs/logical/q_res/chips/chips.prt';

PART_NAME
 R4797 'Q_RES_0402LF-10K,1%,1/16W,EMPTA':;

SECTION_NUMBER 1
 '@S9S_MB_2U_LIB.S9S_MB_2U(SCH_1):PAGE326_I80@PURE_QUANTA.Q_RES(CHIPS)':
 C_PATH='@s9s_mb_2u_lib.s9s_mb_2u(sch_1):page326_i80@pure_quanta.q_res(chips)',
 P_PATH='@s9s_mb_2u_lib.s9s_mb_2u(sch_1):page306_i80@pure_quanta.q_res(chips)',
 PATH='I80',
 DRAWING='@S9S_MB_2U_LIB.S9S_MB_2U(SCH_1):PAGE326',
 PHYS_PAGE='306',
 XY='(3100,2025)',
 ROT='0',
 VER='2',
 PACK_TYPE='0402LF',
 CDS_LIB='pure_quanta',
 CDS_PART_NAME='Q_RES_0402LF-10K,1%,1/16W,EMPTA',
 WATTAGE='1/16W',
 TOLERANCE='1%',
 MATERIAL='EMPTY',
 VALUE='10K',
 PRIM_FILE='./archive_libs/logical/q_res/chips/chips.prt';

PART_NAME
 R4798 'Q_RES_0402LF-10K,1%,1/16W,CHIPA':;

SECTION_NUMBER 1
 '@S9S_MB_2U_LIB.S9S_MB_2U(SCH_1):PAGE147_I75@PURE_QUANTA.Q_RES(CHIPS)':
 C_PATH='@s9s_mb_2u_lib.s9s_mb_2u(sch_1):page147_i75@pure_quanta.q_res(chips)',
 P_PATH='@s9s_mb_2u_lib.s9s_mb_2u(sch_1):page144_i75@pure_quanta.q_res(chips)',
 PATH='I75',
 DRAWING='@S9S_MB_2U_LIB.S9S_MB_2U(SCH_1):PAGE147',
 PHYS_PAGE='144',
 XY='(-6350,3600)',
 ROT='0',
 VER='2',
 PACK_TYPE='0402LF',
 CDS_LIB='pure_quanta',
 CDS_PART_NAME='Q_RES_0402LF-10K,1%,1/16W,CHIPA',
 WATTAGE='1/16W',
 TOLERANCE='1%',
 MATERIAL='CHIP',
 VALUE='10K',
 PRIM_FILE='./archive_libs/logical/q_res/chips/chips.prt';

PART_NAME
 R4799 'Q_RES_0402LF-100K,1%,1/16W,EMPA':;

SECTION_NUMBER 1
 '@S9S_MB_2U_LIB.S9S_MB_2U(SCH_1):PAGE147_I76@PURE_QUANTA.Q_RES(CHIPS)':
 C_PATH='@s9s_mb_2u_lib.s9s_mb_2u(sch_1):page147_i76@pure_quanta.q_res(chips)',
 P_PATH='@s9s_mb_2u_lib.s9s_mb_2u(sch_1):page144_i76@pure_quanta.q_res(chips)',
 PATH='I76',
 DRAWING='@S9S_MB_2U_LIB.S9S_MB_2U(SCH_1):PAGE147',
 PHYS_PAGE='144',
 XY='(-6325,3125)',
 ROT='0',
 VER='2',
 PACK_TYPE='0402LF',
 CDS_LIB='pure_quanta',
 CDS_PART_NAME='Q_RES_0402LF-100K,1%,1/16W,EMPA',
 WATTAGE='1/16W',
 TOLERANCE='1%',
 MATERIAL='EMPTY',
 VALUE='100K',
 PRIM_FILE='./archive_libs/logical/q_res/chips/chips.prt';

PART_NAME
 R4800 'Q_RES_0402LF-4.7K,5%,1/16W,CHIA':;

SECTION_NUMBER 1
 '@S9S_MB_2U_LIB.S9S_MB_2U(SCH_1):PAGE147_I70@PURE_QUANTA.Q_RES(CHIPS)':
 C_PATH='@s9s_mb_2u_lib.s9s_mb_2u(sch_1):page147_i70@pure_quanta.q_res(chips)',
 P_PATH='@s9s_mb_2u_lib.s9s_mb_2u(sch_1):page144_i70@pure_quanta.q_res(chips)',
 PATH='I70',
 DRAWING='@S9S_MB_2U_LIB.S9S_MB_2U(SCH_1):PAGE147',
 PHYS_PAGE='144',
 XY='(-5175,3975)',
 ROT='0',
 VER='2',
 PACK_TYPE='0402LF',
 CDS_LIB='pure_quanta',
 CDS_PART_NAME='Q_RES_0402LF-4.7K,5%,1/16W,CHIA',
 WATTAGE='1/16W',
 TOLERANCE='5%',
 MATERIAL='CHIP',
 VALUE='4.7K',
 PRIM_FILE='./archive_libs/logical/q_res/chips/chips.prt';

PART_NAME
 R4801 'Q_RES_0402LF-4.7K,5%,1/16W,CHIA':;

SECTION_NUMBER 1
 '@S9S_MB_2U_LIB.S9S_MB_2U(SCH_1):PAGE147_I65@PURE_QUANTA.Q_RES(CHIPS)':
 C_PATH='@s9s_mb_2u_lib.s9s_mb_2u(sch_1):page147_i65@pure_quanta.q_res(chips)',
 P_PATH='@s9s_mb_2u_lib.s9s_mb_2u(sch_1):page144_i65@pure_quanta.q_res(chips)',
 PATH='I65',
 DRAWING='@S9S_MB_2U_LIB.S9S_MB_2U(SCH_1):PAGE147',
 PHYS_PAGE='144',
 XY='(-4025,4100)',
 ROT='0',
 VER='2',
 PACK_TYPE='0402LF',
 CDS_LIB='pure_quanta',
 CDS_PART_NAME='Q_RES_0402LF-4.7K,5%,1/16W,CHIA',
 WATTAGE='1/16W',
 TOLERANCE='5%',
 MATERIAL='CHIP',
 VALUE='4.7K',
 PRIM_FILE='./archive_libs/logical/q_res/chips/chips.prt';

PART_NAME
 R4802 'Q_RES_0402LF-0,5%,1/16W,CHIP,CA':;

SECTION_NUMBER 1
 '@S9S_MB_2U_LIB.S9S_MB_2U(SCH_1):PAGE214_I164@PURE_QUANTA.Q_RES(CHIPS)':
 C_PATH='@s9s_mb_2u_lib.s9s_mb_2u(sch_1):page214_i164@pure_quanta.q_res(chips)',
 P_PATH='@s9s_mb_2u_lib.s9s_mb_2u(sch_1):page227_i164@pure_quanta.q_res(chips)',
 PATH='I164',
 DRAWING='@S9S_MB_2U_LIB.S9S_MB_2U(SCH_1):PAGE214',
 PHYS_PAGE='227',
 XY='(8650,975)',
 ROT='0',
 VER='1',
 PACK_TYPE='0402LF',
 CDS_LIB='pure_quanta',
 CDS_PART_NAME='Q_RES_0402LF-0,5%,1/16W,CHIP,CA',
 WATTAGE='1/16W',
 TOLERANCE='5%',
 MATERIAL='CHIP',
 VALUE='0',
 PRIM_FILE='./archive_libs/logical/q_res/chips/chips.prt';

PART_NAME
 R4803 'Q_RES_0402LF-0,5%,1/16W,CHIP,CA':;

SECTION_NUMBER 1
 '@S9S_MB_2U_LIB.S9S_MB_2U(SCH_1):PAGE181_I165@PURE_QUANTA.Q_RES(CHIPS)':
 C_PATH='@s9s_mb_2u_lib.s9s_mb_2u(sch_1):page181_i165@pure_quanta.q_res(chips)',
 P_PATH='@s9s_mb_2u_lib.s9s_mb_2u(sch_1):page189_i165@pure_quanta.q_res(chips)',
 PATH='I165',
 DRAWING='@S9S_MB_2U_LIB.S9S_MB_2U(SCH_1):PAGE181',
 PHYS_PAGE='189',
 XY='(3150,4125)',
 ROT='0',
 VER='1',
 PACK_TYPE='0402LF',
 CDS_LIB='pure_quanta',
 CDS_PART_NAME='Q_RES_0402LF-0,5%,1/16W,CHIP,CA',
 WATTAGE='1/16W',
 TOLERANCE='5%',
 MATERIAL='CHIP',
 VALUE='0',
 PRIM_FILE='./archive_libs/logical/q_res/chips/chips.prt';

PART_NAME
 R4804 'Q_RES_0402LF-1K,1%,1/16W,EMPTYA':;

SECTION_NUMBER 1
 '@S9S_MB_2U_LIB.S9S_MB_2U(SCH_1):PAGE326_I97@PURE_QUANTA.Q_RES(CHIPS)':
 C_PATH='@s9s_mb_2u_lib.s9s_mb_2u(sch_1):page326_i97@pure_quanta.q_res(chips)',
 P_PATH='@s9s_mb_2u_lib.s9s_mb_2u(sch_1):page306_i97@pure_quanta.q_res(chips)',
 PATH='I97',
 DRAWING='@S9S_MB_2U_LIB.S9S_MB_2U(SCH_1):PAGE326',
 PHYS_PAGE='306',
 XY='(-1300,-675)',
 ROT='0',
 VER='2',
 PACK_TYPE='0402LF',
 LOCATION='R4804',
 CDS_LIB='pure_quanta',
 CDS_PART_NAME='Q_RES_0402LF-1K,1%,1/16W,EMPTYA',
 WATTAGE='1/16W',
 TOLERANCE='1%',
 MATERIAL='EMPTY',
 VALUE='1K',
 PRIM_FILE='./archive_libs/logical/q_res/chips/chips.prt';

PART_NAME
 R4805 'Q_RES_0402LF-1K,1%,1/16W,EMPTYA':;

SECTION_NUMBER 1
 '@S9S_MB_2U_LIB.S9S_MB_2U(SCH_1):PAGE326_I99@PURE_QUANTA.Q_RES(CHIPS)':
 C_PATH='@s9s_mb_2u_lib.s9s_mb_2u(sch_1):page326_i99@pure_quanta.q_res(chips)',
 P_PATH='@s9s_mb_2u_lib.s9s_mb_2u(sch_1):page306_i99@pure_quanta.q_res(chips)',
 PATH='I99',
 DRAWING='@S9S_MB_2U_LIB.S9S_MB_2U(SCH_1):PAGE326',
 PHYS_PAGE='306',
 XY='(650,4450)',
 ROT='0',
 VER='2',
 PACK_TYPE='0402LF',
 LOCATION='R4805',
 CDS_LIB='pure_quanta',
 CDS_PART_NAME='Q_RES_0402LF-1K,1%,1/16W,EMPTYA',
 WATTAGE='1/16W',
 TOLERANCE='1%',
 MATERIAL='EMPTY',
 VALUE='1K',
 PRIM_FILE='./archive_libs/logical/q_res/chips/chips.prt';

PART_NAME
 R4806 'Q_RES_0402LF-1K,1%,1/16W,CHIP,A':;

SECTION_NUMBER 1
 '@S9S_MB_2U_LIB.S9S_MB_2U(SCH_1):PAGE326_I98@PURE_QUANTA.Q_RES(CHIPS)':
 C_PATH='@s9s_mb_2u_lib.s9s_mb_2u(sch_1):page326_i98@pure_quanta.q_res(chips)',
 P_PATH='@s9s_mb_2u_lib.s9s_mb_2u(sch_1):page306_i98@pure_quanta.q_res(chips)',
 PATH='I98',
 DRAWING='@S9S_MB_2U_LIB.S9S_MB_2U(SCH_1):PAGE326',
 PHYS_PAGE='306',
 XY='(1275,675)',
 ROT='0',
 VER='2',
 PACK_TYPE='0402LF',
 LOCATION='R4806',
 CDS_LIB='pure_quanta',
 CDS_PART_NAME='Q_RES_0402LF-1K,1%,1/16W,CHIP,A',
 WATTAGE='1/16W',
 TOLERANCE='1%',
 MATERIAL='CHIP',
 VALUE='1K',
 PRIM_FILE='./archive_libs/logical/q_res/chips/chips.prt';

PART_NAME
 R4807 'Q_RES_0402LF-0,5%,1/16W,EMPTY,A':;

SECTION_NUMBER 1
 '@S9S_MB_2U_LIB.S9S_MB_2U(SCH_1):PAGE232_I13@PURE_QUANTA.Q_RES(CHIPS)':
 C_PATH='@s9s_mb_2u_lib.s9s_mb_2u(sch_1):page232_i13@pure_quanta.q_res(chips)',
 P_PATH='@s9s_mb_2u_lib.s9s_mb_2u(sch_1):page244_i13@pure_quanta.q_res(chips)',
 PATH='I13',
 DRAWING='@S9S_MB_2U_LIB.S9S_MB_2U(SCH_1):PAGE232',
 PHYS_PAGE='244',
 XY='(-875,-1500)',
 ROT='0',
 VER='1',
 PACK_TYPE='0402LF',
 CDS_LIB='pure_quanta',
 CDS_PART_NAME='Q_RES_0402LF-0,5%,1/16W,EMPTY,A',
 WATTAGE='1/16W',
 TOLERANCE='5%',
 MATERIAL='EMPTY',
 VALUE='0',
 PRIM_FILE='./archive_libs/logical/q_res/chips/chips.prt';

PART_NAME
 R4808 'Q_RES_0402LF-100K,1%,1/16W,EMPA':;

SECTION_NUMBER 1
 '@S9S_MB_2U_LIB.S9S_MB_2U(SCH_1):PAGE232_I31@PURE_QUANTA.Q_RES(CHIPS)':
 C_PATH='@s9s_mb_2u_lib.s9s_mb_2u(sch_1):page232_i31@pure_quanta.q_res(chips)',
 P_PATH='@s9s_mb_2u_lib.s9s_mb_2u(sch_1):page244_i31@pure_quanta.q_res(chips)',
 PATH='I31',
 DRAWING='@S9S_MB_2U_LIB.S9S_MB_2U(SCH_1):PAGE232',
 PHYS_PAGE='244',
 XY='(675,-2600)',
 ROT='0',
 VER='2',
 PACK_TYPE='0402LF',
 CDS_LIB='pure_quanta',
 CDS_PART_NAME='Q_RES_0402LF-100K,1%,1/16W,EMPA',
 WATTAGE='1/16W',
 TOLERANCE='1%',
 MATERIAL='EMPTY',
 VALUE='100K',
 PRIM_FILE='./archive_libs/logical/q_res/chips/chips.prt';

PART_NAME
 R4809 'Q_RES_0402LF-0,5%,1/16W,CHIP,CA':;

SECTION_NUMBER 1
 '@S9S_MB_2U_LIB.S9S_MB_2U(SCH_1):PAGE227_I2@PURE_QUANTA.Q_RES(CHIPS)':
 C_PATH='@s9s_mb_2u_lib.s9s_mb_2u(sch_1):page227_i2@pure_quanta.q_res(chips)',
 P_PATH='@s9s_mb_2u_lib.s9s_mb_2u(sch_1):page240_i2@pure_quanta.q_res(chips)',
 PATH='I2',
 DRAWING='@S9S_MB_2U_LIB.S9S_MB_2U(SCH_1):PAGE227',
 PHYS_PAGE='240',
 XY='(-14825,-2425)',
 ROT='0',
 VER='2',
 PACK_TYPE='0402LF',
 CDS_LIB='pure_quanta',
 CDS_PART_NAME='Q_RES_0402LF-0,5%,1/16W,CHIP,CA',
 WATTAGE='1/16W',
 TOLERANCE='5%',
 MATERIAL='CHIP',
 VALUE='0',
 PRIM_FILE='./archive_libs/logical/q_res/chips/chips.prt';

PART_NAME
 R4892 'Q_RES_0402LF-49.9,1%,1/16W,EMPA':
 ROOM='HSC1_BOM2';

SECTION_NUMBER 1
 '@S9S_MB_2U_LIB.S9S_MB_2U(SCH_1):PAGE327_I5@PURE_QUANTA.Q_RES(CHIPS)':
 C_PATH='@s9s_mb_2u_lib.s9s_mb_2u(sch_1):page327_i5@pure_quanta.q_res(chips)',
 P_PATH='@s9s_mb_2u_lib.s9s_mb_2u(sch_1):page305_i5@pure_quanta.q_res(chips)',
 PATH='I5',
 DRAWING='@S9S_MB_2U_LIB.S9S_MB_2U(SCH_1):PAGE327',
 PHYS_PAGE='305',
 XY='(1750,300)',
 ROT='0',
 VER='1',
 PACK_TYPE='0402LF',
 LOCATION='R4892',
 CDS_LIB='pure_quanta',
 CDS_PART_NAME='Q_RES_0402LF-49.9,1%,1/16W,EMPA',
 WATTAGE='1/16W',
 TOLERANCE='1%',
 MATERIAL='EMPTY',
 ROOM='HSC1_BOM2',
 VALUE='49.9',
 PRIM_FILE='./archive_libs/logical/q_res/chips/chips.prt';

PART_NAME
 R4893 'Q_RES_0402LF-49.9,1%,1/16W,EMPA':
 ROOM='HSC1_BOM2';

SECTION_NUMBER 1
 '@S9S_MB_2U_LIB.S9S_MB_2U(SCH_1):PAGE327_I4@PURE_QUANTA.Q_RES(CHIPS)':
 C_PATH='@s9s_mb_2u_lib.s9s_mb_2u(sch_1):page327_i4@pure_quanta.q_res(chips)',
 P_PATH='@s9s_mb_2u_lib.s9s_mb_2u(sch_1):page305_i4@pure_quanta.q_res(chips)',
 PATH='I4',
 DRAWING='@S9S_MB_2U_LIB.S9S_MB_2U(SCH_1):PAGE327',
 PHYS_PAGE='305',
 XY='(1725,-50)',
 ROT='0',
 VER='1',
 PACK_TYPE='0402LF',
 LOCATION='R4893',
 CDS_LIB='pure_quanta',
 CDS_PART_NAME='Q_RES_0402LF-49.9,1%,1/16W,EMPA',
 WATTAGE='1/16W',
 TOLERANCE='1%',
 MATERIAL='EMPTY',
 ROOM='HSC1_BOM2',
 VALUE='49.9',
 PRIM_FILE='./archive_libs/logical/q_res/chips/chips.prt';

PART_NAME
 R4894 'Q_RES_0402LF-0,5%,1/16W,EMPTY,A':
 ROOM='HSC1_BOM2';

SECTION_NUMBER 1
 '@S9S_MB_2U_LIB.S9S_MB_2U(SCH_1):PAGE327_I15@PURE_QUANTA.Q_RES(CHIPS)':
 C_PATH='@s9s_mb_2u_lib.s9s_mb_2u(sch_1):page327_i15@pure_quanta.q_res(chips)',
 P_PATH='@s9s_mb_2u_lib.s9s_mb_2u(sch_1):page305_i15@pure_quanta.q_res(chips)',
 PATH='I15',
 DRAWING='@S9S_MB_2U_LIB.S9S_MB_2U(SCH_1):PAGE327',
 PHYS_PAGE='305',
 XY='(4475,400)',
 ROT='0',
 VER='1',
 PACK_TYPE='0402LF',
 LOCATION='R4894',
 CDS_LIB='pure_quanta',
 CDS_PART_NAME='Q_RES_0402LF-0,5%,1/16W,EMPTY,A',
 WATTAGE='1/16W',
 TOLERANCE='5%',
 MATERIAL='EMPTY',
 ROOM='HSC1_BOM2',
 VALUE='0',
 PRIM_FILE='./archive_libs/logical/q_res/chips/chips.prt';

PART_NAME
 R4895 'Q_RES_0402LF-0,5%,1/16W,EMPTY,A':
 ROOM='HSC1_BOM2';

SECTION_NUMBER 1
 '@S9S_MB_2U_LIB.S9S_MB_2U(SCH_1):PAGE327_I16@PURE_QUANTA.Q_RES(CHIPS)':
 C_PATH='@s9s_mb_2u_lib.s9s_mb_2u(sch_1):page327_i16@pure_quanta.q_res(chips)',
 P_PATH='@s9s_mb_2u_lib.s9s_mb_2u(sch_1):page305_i16@pure_quanta.q_res(chips)',
 PATH='I16',
 DRAWING='@S9S_MB_2U_LIB.S9S_MB_2U(SCH_1):PAGE327',
 PHYS_PAGE='305',
 XY='(4475,300)',
 ROT='0',
 VER='1',
 PACK_TYPE='0402LF',
 LOCATION='R4895',
 CDS_LIB='pure_quanta',
 CDS_PART_NAME='Q_RES_0402LF-0,5%,1/16W,EMPTY,A',
 WATTAGE='1/16W',
 TOLERANCE='5%',
 MATERIAL='EMPTY',
 ROOM='HSC1_BOM2',
 VALUE='0',
 PRIM_FILE='./archive_libs/logical/q_res/chips/chips.prt';

PART_NAME
 R4896 'Q_RES_0402LF-0,5%,1/16W,EMPTY,A':
 ROOM='HSC1_BOM2';

SECTION_NUMBER 1
 '@S9S_MB_2U_LIB.S9S_MB_2U(SCH_1):PAGE327_I11@PURE_QUANTA.Q_RES(CHIPS)':
 C_PATH='@s9s_mb_2u_lib.s9s_mb_2u(sch_1):page327_i11@pure_quanta.q_res(chips)',
 P_PATH='@s9s_mb_2u_lib.s9s_mb_2u(sch_1):page305_i11@pure_quanta.q_res(chips)',
 PATH='I11',
 DRAWING='@S9S_MB_2U_LIB.S9S_MB_2U(SCH_1):PAGE327',
 PHYS_PAGE='305',
 XY='(3425,-325)',
 ROT='0',
 VER='1',
 PACK_TYPE='0402LF',
 LOCATION='R4896',
 CDS_LIB='pure_quanta',
 CDS_PART_NAME='Q_RES_0402LF-0,5%,1/16W,EMPTY,A',
 WATTAGE='1/16W',
 TOLERANCE='5%',
 MATERIAL='EMPTY',
 ROOM='HSC1_BOM2',
 VALUE='0',
 PRIM_FILE='./archive_libs/logical/q_res/chips/chips.prt';

PART_NAME
 R4901 'Q_RES_0402LF-82K,1%,1/16W,CHIPA':;

SECTION_NUMBER 1
 '@S9S_MB_2U_LIB.S9S_MB_2U(SCH_1):PAGE303_I26@PURE_QUANTA.Q_RES(CHIPS)':
 C_PATH='@s9s_mb_2u_lib.s9s_mb_2u(sch_1):page303_i26@pure_quanta.q_res(chips)',
 P_PATH='@s9s_mb_2u_lib.s9s_mb_2u(sch_1):page301_i26@pure_quanta.q_res(chips)',
 PATH='I26',
 DRAWING='@S9S_MB_2U_LIB.S9S_MB_2U(SCH_1):PAGE303',
 PHYS_PAGE='301',
 XY='(-15400,1350)',
 ROT='0',
 VER='1',
 PACK_TYPE='0402LF',
 LOCATION='R4901',
 CDS_LIB='pure_quanta',
 CDS_PART_NAME='Q_RES_0402LF-82K,1%,1/16W,CHIPA',
 WATTAGE='1/16W',
 TOLERANCE='1%',
 MATERIAL='CHIP',
 VALUE='82K',
 PRIM_FILE='./archive_libs/logical/q_res/chips/chips.prt';

PART_NAME
 R5234 'Q_RES_0402LF-0,5%,1/16W,CHIP,CA':;

SECTION_NUMBER 1
 '@S9S_MB_2U_LIB.S9S_MB_2U(SCH_1):PAGE155_I91@PURE_QUANTA.Q_RES(CHIPS)':
 C_PATH='@s9s_mb_2u_lib.s9s_mb_2u(sch_1):page155_i91@pure_quanta.q_res(chips)',
 P_PATH='@s9s_mb_2u_lib.s9s_mb_2u(sch_1):page152_i91@pure_quanta.q_res(chips)',
 PATH='I91',
 DRAWING='@S9S_MB_2U_LIB.S9S_MB_2U(SCH_1):PAGE155',
 PHYS_PAGE='152',
 XY='(1375,225)',
 ROT='0',
 VER='1',
 PACK_TYPE='0402LF',
 CDS_LIB='pure_quanta',
 CDS_PART_NAME='Q_RES_0402LF-0,5%,1/16W,CHIP,CA',
 WATTAGE='1/16W',
 TOLERANCE='5%',
 MATERIAL='CHIP',
 VALUE='0',
 PRIM_FILE='./archive_libs/logical/q_res/chips/chips.prt';

PART_NAME
 R5236 'Q_RES_0402LF-0,5%,1/16W,CHIP,CA':;

SECTION_NUMBER 1
 '@S9S_MB_2U_LIB.S9S_MB_2U(SCH_1):PAGE155_I90@PURE_QUANTA.Q_RES(CHIPS)':
 C_PATH='@s9s_mb_2u_lib.s9s_mb_2u(sch_1):page155_i90@pure_quanta.q_res(chips)',
 P_PATH='@s9s_mb_2u_lib.s9s_mb_2u(sch_1):page152_i90@pure_quanta.q_res(chips)',
 PATH='I90',
 DRAWING='@S9S_MB_2U_LIB.S9S_MB_2U(SCH_1):PAGE155',
 PHYS_PAGE='152',
 XY='(1375,175)',
 ROT='0',
 VER='1',
 PACK_TYPE='0402LF',
 CDS_LIB='pure_quanta',
 CDS_PART_NAME='Q_RES_0402LF-0,5%,1/16W,CHIP,CA',
 WATTAGE='1/16W',
 TOLERANCE='5%',
 MATERIAL='CHIP',
 VALUE='0',
 PRIM_FILE='./archive_libs/logical/q_res/chips/chips.prt';

PART_NAME
 R5238 'Q_RES_0402LF-3.9K,5%,1/16W,EMPA':
 ROOM='USB1_BOM2';

SECTION_NUMBER 1
 '@S9S_MB_2U_LIB.S9S_MB_2U(SCH_1):PAGE155_I83@PURE_QUANTA.Q_RES(CHIPS)':
 C_PATH='@s9s_mb_2u_lib.s9s_mb_2u(sch_1):page155_i83@pure_quanta.q_res(chips)',
 P_PATH='@s9s_mb_2u_lib.s9s_mb_2u(sch_1):page152_i83@pure_quanta.q_res(chips)',
 PATH='I83',
 DRAWING='@S9S_MB_2U_LIB.S9S_MB_2U(SCH_1):PAGE155',
 PHYS_PAGE='152',
 XY='(-675,-250)',
 ROT='0',
 VER='2',
 PACK_TYPE='0402LF',
 CDS_LIB='pure_quanta',
 CDS_PART_NAME='Q_RES_0402LF-3.9K,5%,1/16W,EMPA',
 WATTAGE='1/16W',
 TOLERANCE='5%',
 MATERIAL='EMPTY',
 ROOM='USB1_BOM2',
 VALUE='3.9K',
 PRIM_FILE='./archive_libs/logical/q_res/chips/chips.prt';

PART_NAME
 R5377 'Q_RES_0402LF-0,5%,1/16W,CHIP,CA':;

SECTION_NUMBER 1
 '@S9S_MB_2U_LIB.S9S_MB_2U(SCH_1):PAGE182_I312@PURE_QUANTA.Q_RES(CHIPS)':
 C_PATH='@s9s_mb_2u_lib.s9s_mb_2u(sch_1):page182_i312@pure_quanta.q_res(chips)',
 P_PATH='@s9s_mb_2u_lib.s9s_mb_2u(sch_1):page190_i312@pure_quanta.q_res(chips)',
 PATH='I312',
 DRAWING='@S9S_MB_2U_LIB.S9S_MB_2U(SCH_1):PAGE182',
 PHYS_PAGE='190',
 XY='(11000,250)',
 ROT='0',
 VER='1',
 PACK_TYPE='0402LF',
 CDS_LIB='pure_quanta',
 CDS_PART_NAME='Q_RES_0402LF-0,5%,1/16W,CHIP,CA',
 WATTAGE='1/16W',
 TOLERANCE='5%',
 MATERIAL='CHIP',
 VALUE='0',
 PRIM_FILE='./archive_libs/logical/q_res/chips/chips.prt';

PART_NAME
 R5487 'Q_RES_0402LF-0,5%,1/16W,CHIP,CA':;

SECTION_NUMBER 1
 '@S9S_MB_2U_LIB.S9S_MB_2U(SCH_1):PAGE153_I19@PURE_QUANTA.Q_RES(CHIPS)':
 C_PATH='@s9s_mb_2u_lib.s9s_mb_2u(sch_1):page153_i19@pure_quanta.q_res(chips)',
 P_PATH='@s9s_mb_2u_lib.s9s_mb_2u(sch_1):page156_i19@pure_quanta.q_res(chips)',
 PATH='I19',
 DRAWING='@S9S_MB_2U_LIB.S9S_MB_2U(SCH_1):PAGE153',
 PHYS_PAGE='156',
 XY='(3175,11850)',
 ROT='0',
 VER='1',
 PACK_TYPE='0402LF',
 CDS_LIB='pure_quanta',
 CDS_PART_NAME='Q_RES_0402LF-0,5%,1/16W,CHIP,CA',
 WATTAGE='1/16W',
 TOLERANCE='5%',
 MATERIAL='CHIP',
 VALUE='0',
 PRIM_FILE='./archive_libs/logical/q_res/chips/chips.prt';

PART_NAME
 SW5 'SW_PUSHBUTTON4P_24-SW4S_DTSM-6A':;

SECTION_NUMBER 1
 '@S9S_MB_2U_LIB.S9S_MB_2U(SCH_1):PAGE189_I122@PURE_QUANTA.SW_PUSHBUTTON4P_24(CHIPS)':
 C_PATH='@s9s_mb_2u_lib.s9s_mb_2u(sch_1):page189_i122@pure_quanta.sw_pushbutton4~
p_24(chips)',
 P_PATH='@s9s_mb_2u_lib.s9s_mb_2u(sch_1):page201_i122@pure_quanta.sw_pushbutton4~
p_24(chips)',
 PATH='I122',
 DRAWING='@S9S_MB_2U_LIB.S9S_MB_2U(SCH_1):PAGE189',
 PHYS_PAGE='201',
 XY='(1150,1550)',
 ROT='0',
 VER='1',
 CDS_LIB='pure_quanta',
 CDS_PART_NAME='SW_PUSHBUTTON4P_24-SW4S_DTSM-6A',
 PART_TYPE='SMLF',
 MATERIAL='MECH',
 VALUE='SW4S_DTSM-61N-S-Q-T/R',
 PRIM_FILE='./archive_libs/logical/sw_pushbutton4p_24/chips/chips.prt';

PART_NAME
 U1 'SOCKET4677_AZIF0045P001C01CS-SA':;

SECTION_NUMBER 1
 '@S9S_MB_2U_LIB.S9S_MB_2U(SCH_1):PAGE44_I51@PURE_QUANTA.SOCKET4677_AZIF0045P001C01CS(CHIPS)':
 C_PATH='@s9s_mb_2u_lib.s9s_mb_2u(sch_1):page44_i51@pure_quanta.socket4677_azif0~
045p001c01cs(chips)',
 P_PATH='@s9s_mb_2u_lib.s9s_mb_2u(sch_1):page44_i51@pure_quanta.socket4677_azif0~
045p001c01cs(chips)',
 PATH='I51',
 DRAWING='@S9S_MB_2U_LIB.S9S_MB_2U(SCH_1):PAGE44',
 PHYS_PAGE='44',
 XY='(-4500,7100)',
 ROT='0',
 VER='1',
 CDS_LIB='pure_quanta',
 CDS_PART_NAME='SOCKET4677_AZIF0045P001C01CS-SA',
 PART_TYPE='SMLF',
 MATERIAL='IO',
 VALUE='SOCKET4677_AZIF0045-P001C01CS',
 PRIM_FILE='./archive_libs/logical/socket4677_azif0045p001c01cs/chips/chips.prt';

SECTION_NUMBER 2
 '@S9S_MB_2U_LIB.S9S_MB_2U(SCH_1):PAGE45_I29@PURE_QUANTA.SOCKET4677_AZIF0045P001C01CS(CHIPS)':
 C_PATH='@s9s_mb_2u_lib.s9s_mb_2u(sch_1):page45_i29@pure_quanta.socket4677_azif0~
045p001c01cs(chips)',
 P_PATH='@s9s_mb_2u_lib.s9s_mb_2u(sch_1):page45_i29@pure_quanta.socket4677_azif0~
045p001c01cs(chips)',
 PATH='I29',
 DRAWING='@S9S_MB_2U_LIB.S9S_MB_2U(SCH_1):PAGE45',
 PHYS_PAGE='45',
 XY='(-5750,-1925)',
 ROT='0',
 VER='2',
 CDS_LIB='pure_quanta',
 CDS_PART_NAME='SOCKET4677_AZIF0045P001C01CS-SA',
 PART_TYPE='SMLF',
 MATERIAL='IO',
 VALUE='SOCKET4677_AZIF0045-P001C01CS',
 PRIM_FILE='./archive_libs/logical/socket4677_azif0045p001c01cs/chips/chips.prt';

SECTION_NUMBER 3
 '@S9S_MB_2U_LIB.S9S_MB_2U(SCH_1):PAGE46_I5@PURE_QUANTA.SOCKET4677_AZIF0045P001C01CS(CHIPS)':
 C_PATH='@s9s_mb_2u_lib.s9s_mb_2u(sch_1):page46_i5@pure_quanta.socket4677_azif00~
45p001c01cs(chips)',
 P_PATH='@s9s_mb_2u_lib.s9s_mb_2u(sch_1):page46_i5@pure_quanta.socket4677_azif00~
45p001c01cs(chips)',
 PATH='I5',
 DRAWING='@S9S_MB_2U_LIB.S9S_MB_2U(SCH_1):PAGE46',
 PHYS_PAGE='46',
 XY='(-3400,9125)',
 ROT='0',
 VER='3',
 CDS_LIB='pure_quanta',
 CDS_PART_NAME='SOCKET4677_AZIF0045P001C01CS-SA',
 PART_TYPE='SMLF',
 MATERIAL='IO',
 VALUE='SOCKET4677_AZIF0045-P001C01CS',
 PRIM_FILE='./archive_libs/logical/socket4677_azif0045p001c01cs/chips/chips.prt';

SECTION_NUMBER 4
 '@S9S_MB_2U_LIB.S9S_MB_2U(SCH_1):PAGE47_I16@PURE_QUANTA.SOCKET4677_AZIF0045P001C01CS(CHIPS)':
 C_PATH='@s9s_mb_2u_lib.s9s_mb_2u(sch_1):page47_i16@pure_quanta.socket4677_azif0~
045p001c01cs(chips)',
 P_PATH='@s9s_mb_2u_lib.s9s_mb_2u(sch_1):page47_i16@pure_quanta.socket4677_azif0~
045p001c01cs(chips)',
 PATH='I16',
 DRAWING='@S9S_MB_2U_LIB.S9S_MB_2U(SCH_1):PAGE47',
 PHYS_PAGE='47',
 XY='(-450,4875)',
 ROT='0',
 VER='4',
 CDS_LIB='pure_quanta',
 CDS_PART_NAME='SOCKET4677_AZIF0045P001C01CS-SA',
 PART_TYPE='SMLF',
 MATERIAL='IO',
 VALUE='SOCKET4677_AZIF0045-P001C01CS',
 PRIM_FILE='./archive_libs/logical/socket4677_azif0045p001c01cs/chips/chips.prt';

SECTION_NUMBER 5
 '@S9S_MB_2U_LIB.S9S_MB_2U(SCH_1):PAGE48_I1@PURE_QUANTA.SOCKET4677_AZIF0045P001C01CS(CHIPS)':
 C_PATH='@s9s_mb_2u_lib.s9s_mb_2u(sch_1):page48_i1@pure_quanta.socket4677_azif00~
45p001c01cs(chips)',
 P_PATH='@s9s_mb_2u_lib.s9s_mb_2u(sch_1):page48_i1@pure_quanta.socket4677_azif00~
45p001c01cs(chips)',
 PATH='I1',
 DRAWING='@S9S_MB_2U_LIB.S9S_MB_2U(SCH_1):PAGE48',
 PHYS_PAGE='48',
 XY='(550,3125)',
 ROT='0',
 VER='5',
 CDS_LIB='pure_quanta',
 CDS_PART_NAME='SOCKET4677_AZIF0045P001C01CS-SA',
 PART_TYPE='SMLF',
 MATERIAL='IO',
 VALUE='SOCKET4677_AZIF0045-P001C01CS',
 PRIM_FILE='./archive_libs/logical/socket4677_azif0045p001c01cs/chips/chips.prt';

SECTION_NUMBER 6
 '@S9S_MB_2U_LIB.S9S_MB_2U(SCH_1):PAGE49_I2@PURE_QUANTA.SOCKET4677_AZIF0045P001C01CS(CHIPS)':
 C_PATH='@s9s_mb_2u_lib.s9s_mb_2u(sch_1):page49_i2@pure_quanta.socket4677_azif00~
45p001c01cs(chips)',
 P_PATH='@s9s_mb_2u_lib.s9s_mb_2u(sch_1):page49_i2@pure_quanta.socket4677_azif00~
45p001c01cs(chips)',
 PATH='I2',
 DRAWING='@S9S_MB_2U_LIB.S9S_MB_2U(SCH_1):PAGE49',
 PHYS_PAGE='49',
 XY='(925,2500)',
 ROT='0',
 VER='6',
 CDS_LIB='pure_quanta',
 CDS_PART_NAME='SOCKET4677_AZIF0045P001C01CS-SA',
 PART_TYPE='SMLF',
 MATERIAL='IO',
 VALUE='SOCKET4677_AZIF0045-P001C01CS',
 PRIM_FILE='./archive_libs/logical/socket4677_azif0045p001c01cs/chips/chips.prt';

SECTION_NUMBER 7
 '@S9S_MB_2U_LIB.S9S_MB_2U(SCH_1):PAGE50_I23@PURE_QUANTA.SOCKET4677_AZIF0045P001C01CS(CHIPS)':
 C_PATH='@s9s_mb_2u_lib.s9s_mb_2u(sch_1):page50_i23@pure_quanta.socket4677_azif0~
045p001c01cs(chips)',
 P_PATH='@s9s_mb_2u_lib.s9s_mb_2u(sch_1):page50_i23@pure_quanta.socket4677_azif0~
045p001c01cs(chips)',
 PATH='I23',
 DRAWING='@S9S_MB_2U_LIB.S9S_MB_2U(SCH_1):PAGE50',
 PHYS_PAGE='50',
 XY='(1900,2175)',
 ROT='0',
 VER='7',
 CDS_LIB='pure_quanta',
 CDS_PART_NAME='SOCKET4677_AZIF0045P001C01CS-SA',
 PART_TYPE='SMLF',
 MATERIAL='IO',
 VALUE='SOCKET4677_AZIF0045-P001C01CS',
 PRIM_FILE='./archive_libs/logical/socket4677_azif0045p001c01cs/chips/chips.prt';

SECTION_NUMBER 8
 '@S9S_MB_2U_LIB.S9S_MB_2U(SCH_1):PAGE51_I2@PURE_QUANTA.SOCKET4677_AZIF0045P001C01CS(CHIPS)':
 C_PATH='@s9s_mb_2u_lib.s9s_mb_2u(sch_1):page51_i2@pure_quanta.socket4677_azif00~
45p001c01cs(chips)',
 P_PATH='@s9s_mb_2u_lib.s9s_mb_2u(sch_1):page51_i2@pure_quanta.socket4677_azif00~
45p001c01cs(chips)',
 PATH='I2',
 DRAWING='@S9S_MB_2U_LIB.S9S_MB_2U(SCH_1):PAGE51',
 PHYS_PAGE='51',
 XY='(625,2150)',
 ROT='0',
 VER='8',
 CDS_LIB='pure_quanta',
 CDS_PART_NAME='SOCKET4677_AZIF0045P001C01CS-SA',
 PART_TYPE='SMLF',
 MATERIAL='IO',
 VALUE='SOCKET4677_AZIF0045-P001C01CS',
 PRIM_FILE='./archive_libs/logical/socket4677_azif0045p001c01cs/chips/chips.prt';

SECTION_NUMBER 9
 '@S9S_MB_2U_LIB.S9S_MB_2U(SCH_1):PAGE52_I91@PURE_QUANTA.SOCKET4677_AZIF0045P001C01CS(CHIPS)':
 C_PATH='@s9s_mb_2u_lib.s9s_mb_2u(sch_1):page52_i91@pure_quanta.socket4677_azif0~
045p001c01cs(chips)',
 P_PATH='@s9s_mb_2u_lib.s9s_mb_2u(sch_1):page52_i91@pure_quanta.socket4677_azif0~
045p001c01cs(chips)',
 PATH='I91',
 DRAWING='@S9S_MB_2U_LIB.S9S_MB_2U(SCH_1):PAGE52',
 PHYS_PAGE='52',
 XY='(775,1800)',
 ROT='0',
 VER='9',
 CDS_LIB='pure_quanta',
 CDS_PART_NAME='SOCKET4677_AZIF0045P001C01CS-SA',
 PART_TYPE='SMLF',
 MATERIAL='IO',
 VALUE='SOCKET4677_AZIF0045-P001C01CS',
 PRIM_FILE='./archive_libs/logical/socket4677_azif0045p001c01cs/chips/chips.prt';

SECTION_NUMBER 10
 '@S9S_MB_2U_LIB.S9S_MB_2U(SCH_1):PAGE53_I91@PURE_QUANTA.SOCKET4677_AZIF0045P001C01CS(CHIPS)':
 C_PATH='@s9s_mb_2u_lib.s9s_mb_2u(sch_1):page53_i91@pure_quanta.socket4677_azif0~
045p001c01cs(chips)',
 P_PATH='@s9s_mb_2u_lib.s9s_mb_2u(sch_1):page53_i91@pure_quanta.socket4677_azif0~
045p001c01cs(chips)',
 PATH='I91',
 DRAWING='@S9S_MB_2U_LIB.S9S_MB_2U(SCH_1):PAGE53',
 PHYS_PAGE='53',
 XY='(1050,1850)',
 ROT='0',
 VER='10',
 CDS_LIB='pure_quanta',
 CDS_PART_NAME='SOCKET4677_AZIF0045P001C01CS-SA',
 PART_TYPE='SMLF',
 MATERIAL='IO',
 VALUE='SOCKET4677_AZIF0045-P001C01CS',
 PRIM_FILE='./archive_libs/logical/socket4677_azif0045p001c01cs/chips/chips.prt';

SECTION_NUMBER 11
 '@S9S_MB_2U_LIB.S9S_MB_2U(SCH_1):PAGE54_I91@PURE_QUANTA.SOCKET4677_AZIF0045P001C01CS(CHIPS)':
 C_PATH='@s9s_mb_2u_lib.s9s_mb_2u(sch_1):page54_i91@pure_quanta.socket4677_azif0~
045p001c01cs(chips)',
 P_PATH='@s9s_mb_2u_lib.s9s_mb_2u(sch_1):page54_i91@pure_quanta.socket4677_azif0~
045p001c01cs(chips)',
 PATH='I91',
 DRAWING='@S9S_MB_2U_LIB.S9S_MB_2U(SCH_1):PAGE54',
 PHYS_PAGE='54',
 XY='(900,1500)',
 ROT='0',
 VER='11',
 CDS_LIB='pure_quanta',
 CDS_PART_NAME='SOCKET4677_AZIF0045P001C01CS-SA',
 PART_TYPE='SMLF',
 MATERIAL='IO',
 VALUE='SOCKET4677_AZIF0045-P001C01CS',
 PRIM_FILE='./archive_libs/logical/socket4677_azif0045p001c01cs/chips/chips.prt';

SECTION_NUMBER 12
 '@S9S_MB_2U_LIB.S9S_MB_2U(SCH_1):PAGE55_I7@PURE_QUANTA.SOCKET4677_AZIF0045P001C01CS(CHIPS)':
 C_PATH='@s9s_mb_2u_lib.s9s_mb_2u(sch_1):page55_i7@pure_quanta.socket4677_azif00~
45p001c01cs(chips)',
 P_PATH='@s9s_mb_2u_lib.s9s_mb_2u(sch_1):page55_i7@pure_quanta.socket4677_azif00~
45p001c01cs(chips)',
 PATH='I7',
 DRAWING='@S9S_MB_2U_LIB.S9S_MB_2U(SCH_1):PAGE55',
 PHYS_PAGE='55',
 XY='(650,1875)',
 ROT='0',
 VER='12',
 CDS_LIB='pure_quanta',
 CDS_PART_NAME='SOCKET4677_AZIF0045P001C01CS-SA',
 PART_TYPE='SMLF',
 MATERIAL='IO',
 VALUE='SOCKET4677_AZIF0045-P001C01CS',
 PRIM_FILE='./archive_libs/logical/socket4677_azif0045p001c01cs/chips/chips.prt';

SECTION_NUMBER 13
 '@S9S_MB_2U_LIB.S9S_MB_2U(SCH_1):PAGE56_I168@PURE_QUANTA.SOCKET4677_AZIF0045P001C01CS(CHIPS)':
 C_PATH='@s9s_mb_2u_lib.s9s_mb_2u(sch_1):page56_i168@pure_quanta.socket4677_azif~
0045p001c01cs(chips)',
 P_PATH='@s9s_mb_2u_lib.s9s_mb_2u(sch_1):page56_i168@pure_quanta.socket4677_azif~
0045p001c01cs(chips)',
 PATH='I168',
 DRAWING='@S9S_MB_2U_LIB.S9S_MB_2U(SCH_1):PAGE56',
 PHYS_PAGE='56',
 XY='(750,1925)',
 ROT='0',
 VER='13',
 CDS_LIB='pure_quanta',
 CDS_PART_NAME='SOCKET4677_AZIF0045P001C01CS-SA',
 PART_TYPE='SMLF',
 MATERIAL='IO',
 VALUE='SOCKET4677_AZIF0045-P001C01CS',
 PRIM_FILE='./archive_libs/logical/socket4677_azif0045p001c01cs/chips/chips.prt';

SECTION_NUMBER 14
 '@S9S_MB_2U_LIB.S9S_MB_2U(SCH_1):PAGE57_I168@PURE_QUANTA.SOCKET4677_AZIF0045P001C01CS(CHIPS)':
 C_PATH='@s9s_mb_2u_lib.s9s_mb_2u(sch_1):page57_i168@pure_quanta.socket4677_azif~
0045p001c01cs(chips)',
 P_PATH='@s9s_mb_2u_lib.s9s_mb_2u(sch_1):page57_i168@pure_quanta.socket4677_azif~
0045p001c01cs(chips)',
 PATH='I168',
 DRAWING='@S9S_MB_2U_LIB.S9S_MB_2U(SCH_1):PAGE57',
 PHYS_PAGE='57',
 XY='(525,1950)',
 ROT='0',
 VER='14',
 CDS_LIB='pure_quanta',
 CDS_PART_NAME='SOCKET4677_AZIF0045P001C01CS-SA',
 PART_TYPE='SMLF',
 MATERIAL='IO',
 VALUE='SOCKET4677_AZIF0045-P001C01CS',
 PRIM_FILE='./archive_libs/logical/socket4677_azif0045p001c01cs/chips/chips.prt';

SECTION_NUMBER 15
 '@S9S_MB_2U_LIB.S9S_MB_2U(SCH_1):PAGE58_I20@PURE_QUANTA.SOCKET4677_AZIF0045P001C01CS(CHIPS)':
 C_PATH='@s9s_mb_2u_lib.s9s_mb_2u(sch_1):page58_i20@pure_quanta.socket4677_azif0~
045p001c01cs(chips)',
 P_PATH='@s9s_mb_2u_lib.s9s_mb_2u(sch_1):page58_i20@pure_quanta.socket4677_azif0~
045p001c01cs(chips)',
 PATH='I20',
 DRAWING='@S9S_MB_2U_LIB.S9S_MB_2U(SCH_1):PAGE58',
 PHYS_PAGE='58',
 XY='(1075,1725)',
 ROT='0',
 VER='15',
 CDS_LIB='pure_quanta',
 CDS_PART_NAME='SOCKET4677_AZIF0045P001C01CS-SA',
 PART_TYPE='SMLF',
 MATERIAL='IO',
 VALUE='SOCKET4677_AZIF0045-P001C01CS',
 PRIM_FILE='./archive_libs/logical/socket4677_azif0045p001c01cs/chips/chips.prt';

SECTION_NUMBER 16
 '@S9S_MB_2U_LIB.S9S_MB_2U(SCH_1):PAGE59_I20@PURE_QUANTA.SOCKET4677_AZIF0045P001C01CS(CHIPS)':
 C_PATH='@s9s_mb_2u_lib.s9s_mb_2u(sch_1):page59_i20@pure_quanta.socket4677_azif0~
045p001c01cs(chips)',
 P_PATH='@s9s_mb_2u_lib.s9s_mb_2u(sch_1):page59_i20@pure_quanta.socket4677_azif0~
045p001c01cs(chips)',
 PATH='I20',
 DRAWING='@S9S_MB_2U_LIB.S9S_MB_2U(SCH_1):PAGE59',
 PHYS_PAGE='59',
 XY='(975,3425)',
 ROT='0',
 VER='16',
 CDS_LIB='pure_quanta',
 CDS_PART_NAME='SOCKET4677_AZIF0045P001C01CS-SA',
 PART_TYPE='SMLF',
 MATERIAL='IO',
 VALUE='SOCKET4677_AZIF0045-P001C01CS',
 PRIM_FILE='./archive_libs/logical/socket4677_azif0045p001c01cs/chips/chips.prt';

SECTION_NUMBER 17
 '@S9S_MB_2U_LIB.S9S_MB_2U(SCH_1):PAGE60_I80@PURE_QUANTA.SOCKET4677_AZIF0045P001C01CS(CHIPS)':
 C_PATH='@s9s_mb_2u_lib.s9s_mb_2u(sch_1):page60_i80@pure_quanta.socket4677_azif0~
045p001c01cs(chips)',
 P_PATH='@s9s_mb_2u_lib.s9s_mb_2u(sch_1):page60_i80@pure_quanta.socket4677_azif0~
045p001c01cs(chips)',
 PATH='I80',
 DRAWING='@S9S_MB_2U_LIB.S9S_MB_2U(SCH_1):PAGE60',
 PHYS_PAGE='60',
 XY='(1675,3250)',
 ROT='0',
 VER='17',
 CDS_LIB='pure_quanta',
 CDS_PART_NAME='SOCKET4677_AZIF0045P001C01CS-SA',
 PART_TYPE='SMLF',
 MATERIAL='IO',
 VALUE='SOCKET4677_AZIF0045-P001C01CS',
 PRIM_FILE='./archive_libs/logical/socket4677_azif0045p001c01cs/chips/chips.prt';

SECTION_NUMBER 18
 '@S9S_MB_2U_LIB.S9S_MB_2U(SCH_1):PAGE60_I69@PURE_QUANTA.SOCKET4677_AZIF0045P001C01CS(CHIPS)':
 C_PATH='@s9s_mb_2u_lib.s9s_mb_2u(sch_1):page60_i69@pure_quanta.socket4677_azif0~
045p001c01cs(chips)',
 P_PATH='@s9s_mb_2u_lib.s9s_mb_2u(sch_1):page60_i69@pure_quanta.socket4677_azif0~
045p001c01cs(chips)',
 PATH='I69',
 DRAWING='@S9S_MB_2U_LIB.S9S_MB_2U(SCH_1):PAGE60',
 PHYS_PAGE='60',
 XY='(1675,475)',
 ROT='0',
 VER='18',
 CDS_LIB='pure_quanta',
 CDS_PART_NAME='SOCKET4677_AZIF0045P001C01CS-SA',
 PART_TYPE='SMLF',
 MATERIAL='IO',
 VALUE='SOCKET4677_AZIF0045-P001C01CS',
 PRIM_FILE='./archive_libs/logical/socket4677_azif0045p001c01cs/chips/chips.prt';

SECTION_NUMBER 19
 '@S9S_MB_2U_LIB.S9S_MB_2U(SCH_1):PAGE61_I54@PURE_QUANTA.SOCKET4677_AZIF0045P001C01CS(CHIPS)':
 C_PATH='@s9s_mb_2u_lib.s9s_mb_2u(sch_1):page61_i54@pure_quanta.socket4677_azif0~
045p001c01cs(chips)',
 P_PATH='@s9s_mb_2u_lib.s9s_mb_2u(sch_1):page61_i54@pure_quanta.socket4677_azif0~
045p001c01cs(chips)',
 PATH='I54',
 DRAWING='@S9S_MB_2U_LIB.S9S_MB_2U(SCH_1):PAGE61',
 PHYS_PAGE='61',
 XY='(1500,3050)',
 ROT='0',
 VER='19',
 CDS_LIB='pure_quanta',
 CDS_PART_NAME='SOCKET4677_AZIF0045P001C01CS-SA',
 PART_TYPE='SMLF',
 MATERIAL='IO',
 VALUE='SOCKET4677_AZIF0045-P001C01CS',
 PRIM_FILE='./archive_libs/logical/socket4677_azif0045p001c01cs/chips/chips.prt';

SECTION_NUMBER 20
 '@S9S_MB_2U_LIB.S9S_MB_2U(SCH_1):PAGE61_I12@PURE_QUANTA.SOCKET4677_AZIF0045P001C01CS(CHIPS)':
 C_PATH='@s9s_mb_2u_lib.s9s_mb_2u(sch_1):page61_i12@pure_quanta.socket4677_azif0~
045p001c01cs(chips)',
 P_PATH='@s9s_mb_2u_lib.s9s_mb_2u(sch_1):page61_i12@pure_quanta.socket4677_azif0~
045p001c01cs(chips)',
 PATH='I12',
 DRAWING='@S9S_MB_2U_LIB.S9S_MB_2U(SCH_1):PAGE61',
 PHYS_PAGE='61',
 XY='(1500,275)',
 ROT='0',
 VER='20',
 CDS_LIB='pure_quanta',
 CDS_PART_NAME='SOCKET4677_AZIF0045P001C01CS-SA',
 PART_TYPE='SMLF',
 MATERIAL='IO',
 VALUE='SOCKET4677_AZIF0045-P001C01CS',
 PRIM_FILE='./archive_libs/logical/socket4677_azif0045p001c01cs/chips/chips.prt';

SECTION_NUMBER 21
 '@S9S_MB_2U_LIB.S9S_MB_2U(SCH_1):PAGE62_I18@PURE_QUANTA.SOCKET4677_AZIF0045P001C01CS(CHIPS)':
 C_PATH='@s9s_mb_2u_lib.s9s_mb_2u(sch_1):page62_i18@pure_quanta.socket4677_azif0~
045p001c01cs(chips)',
 P_PATH='@s9s_mb_2u_lib.s9s_mb_2u(sch_1):page62_i18@pure_quanta.socket4677_azif0~
045p001c01cs(chips)',
 PATH='I18',
 DRAWING='@S9S_MB_2U_LIB.S9S_MB_2U(SCH_1):PAGE62',
 PHYS_PAGE='62',
 XY='(125,3850)',
 ROT='0',
 VER='21',
 CDS_LIB='pure_quanta',
 CDS_PART_NAME='SOCKET4677_AZIF0045P001C01CS-SA',
 PART_TYPE='SMLF',
 MATERIAL='IO',
 VALUE='SOCKET4677_AZIF0045-P001C01CS',
 PRIM_FILE='./archive_libs/logical/socket4677_azif0045p001c01cs/chips/chips.prt';

SECTION_NUMBER 22
 '@S9S_MB_2U_LIB.S9S_MB_2U(SCH_1):PAGE63_I51@PURE_QUANTA.SOCKET4677_AZIF0045P001C01CS(CHIPS)':
 C_PATH='@s9s_mb_2u_lib.s9s_mb_2u(sch_1):page63_i51@pure_quanta.socket4677_azif0~
045p001c01cs(chips)',
 P_PATH='@s9s_mb_2u_lib.s9s_mb_2u(sch_1):page63_i51@pure_quanta.socket4677_azif0~
045p001c01cs(chips)',
 PATH='I51',
 DRAWING='@S9S_MB_2U_LIB.S9S_MB_2U(SCH_1):PAGE63',
 PHYS_PAGE='63',
 XY='(1100,2925)',
 ROT='0',
 VER='22',
 CDS_LIB='pure_quanta',
 CDS_PART_NAME='SOCKET4677_AZIF0045P001C01CS-SA',
 PART_TYPE='SMLF',
 MATERIAL='IO',
 VALUE='SOCKET4677_AZIF0045-P001C01CS',
 PRIM_FILE='./archive_libs/logical/socket4677_azif0045p001c01cs/chips/chips.prt';

SECTION_NUMBER 23
 '@S9S_MB_2U_LIB.S9S_MB_2U(SCH_1):PAGE64_I21@PURE_QUANTA.SOCKET4677_AZIF0045P001C01CS(CHIPS)':
 C_PATH='@s9s_mb_2u_lib.s9s_mb_2u(sch_1):page64_i21@pure_quanta.socket4677_azif0~
045p001c01cs(chips)',
 P_PATH='@s9s_mb_2u_lib.s9s_mb_2u(sch_1):page64_i21@pure_quanta.socket4677_azif0~
045p001c01cs(chips)',
 PATH='I21',
 DRAWING='@S9S_MB_2U_LIB.S9S_MB_2U(SCH_1):PAGE64',
 PHYS_PAGE='64',
 XY='(1600,2725)',
 ROT='0',
 VER='23',
 CDS_LIB='pure_quanta',
 CDS_PART_NAME='SOCKET4677_AZIF0045P001C01CS-SA',
 PART_TYPE='SMLF',
 MATERIAL='IO',
 VALUE='SOCKET4677_AZIF0045-P001C01CS',
 PRIM_FILE='./archive_libs/logical/socket4677_azif0045p001c01cs/chips/chips.prt';

SECTION_NUMBER 24
 '@S9S_MB_2U_LIB.S9S_MB_2U(SCH_1):PAGE65_I16@PURE_QUANTA.SOCKET4677_AZIF0045P001C01CS(CHIPS)':
 C_PATH='@s9s_mb_2u_lib.s9s_mb_2u(sch_1):page65_i16@pure_quanta.socket4677_azif0~
045p001c01cs(chips)',
 P_PATH='@s9s_mb_2u_lib.s9s_mb_2u(sch_1):page65_i16@pure_quanta.socket4677_azif0~
045p001c01cs(chips)',
 PATH='I16',
 DRAWING='@S9S_MB_2U_LIB.S9S_MB_2U(SCH_1):PAGE65',
 PHYS_PAGE='65',
 XY='(1625,2775)',
 ROT='0',
 VER='24',
 CDS_LIB='pure_quanta',
 CDS_PART_NAME='SOCKET4677_AZIF0045P001C01CS-SA',
 PART_TYPE='SMLF',
 MATERIAL='IO',
 VALUE='SOCKET4677_AZIF0045-P001C01CS',
 PRIM_FILE='./archive_libs/logical/socket4677_azif0045p001c01cs/chips/chips.prt';

SECTION_NUMBER 25
 '@S9S_MB_2U_LIB.S9S_MB_2U(SCH_1):PAGE66_I16@PURE_QUANTA.SOCKET4677_AZIF0045P001C01CS(CHIPS)':
 C_PATH='@s9s_mb_2u_lib.s9s_mb_2u(sch_1):page66_i16@pure_quanta.socket4677_azif0~
045p001c01cs(chips)',
 P_PATH='@s9s_mb_2u_lib.s9s_mb_2u(sch_1):page66_i16@pure_quanta.socket4677_azif0~
045p001c01cs(chips)',
 PATH='I16',
 DRAWING='@S9S_MB_2U_LIB.S9S_MB_2U(SCH_1):PAGE66',
 PHYS_PAGE='66',
 XY='(600,2750)',
 ROT='0',
 VER='25',
 CDS_LIB='pure_quanta',
 CDS_PART_NAME='SOCKET4677_AZIF0045P001C01CS-SA',
 PART_TYPE='SMLF',
 MATERIAL='IO',
 VALUE='SOCKET4677_AZIF0045-P001C01CS',
 PRIM_FILE='./archive_libs/logical/socket4677_azif0045p001c01cs/chips/chips.prt';

SECTION_NUMBER 26
 '@S9S_MB_2U_LIB.S9S_MB_2U(SCH_1):PAGE67_I1@PURE_QUANTA.SOCKET4677_AZIF0045P001C01CS(CHIPS)':
 C_PATH='@s9s_mb_2u_lib.s9s_mb_2u(sch_1):page67_i1@pure_quanta.socket4677_azif00~
45p001c01cs(chips)',
 P_PATH='@s9s_mb_2u_lib.s9s_mb_2u(sch_1):page67_i1@pure_quanta.socket4677_azif00~
45p001c01cs(chips)',
 PATH='I1',
 DRAWING='@S9S_MB_2U_LIB.S9S_MB_2U(SCH_1):PAGE67',
 PHYS_PAGE='67',
 XY='(-650,1900)',
 ROT='0',
 VER='26',
 CDS_LIB='pure_quanta',
 CDS_PART_NAME='SOCKET4677_AZIF0045P001C01CS-SA',
 PART_TYPE='SMLF',
 MATERIAL='IO',
 VALUE='SOCKET4677_AZIF0045-P001C01CS',
 PRIM_FILE='./archive_libs/logical/socket4677_azif0045p001c01cs/chips/chips.prt';

SECTION_NUMBER 27
 '@S9S_MB_2U_LIB.S9S_MB_2U(SCH_1):PAGE67_I3@PURE_QUANTA.SOCKET4677_AZIF0045P001C01CS(CHIPS)':
 C_PATH='@s9s_mb_2u_lib.s9s_mb_2u(sch_1):page67_i3@pure_quanta.socket4677_azif00~
45p001c01cs(chips)',
 P_PATH='@s9s_mb_2u_lib.s9s_mb_2u(sch_1):page67_i3@pure_quanta.socket4677_azif00~
45p001c01cs(chips)',
 PATH='I3',
 DRAWING='@S9S_MB_2U_LIB.S9S_MB_2U(SCH_1):PAGE67',
 PHYS_PAGE='67',
 XY='(3725,1900)',
 ROT='0',
 VER='27',
 CDS_LIB='pure_quanta',
 CDS_PART_NAME='SOCKET4677_AZIF0045P001C01CS-SA',
 PART_TYPE='SMLF',
 MATERIAL='IO',
 VALUE='SOCKET4677_AZIF0045-P001C01CS',
 PRIM_FILE='./archive_libs/logical/socket4677_azif0045p001c01cs/chips/chips.prt';

SECTION_NUMBER 28
 '@S9S_MB_2U_LIB.S9S_MB_2U(SCH_1):PAGE68_I1@PURE_QUANTA.SOCKET4677_AZIF0045P001C01CS(CHIPS)':
 C_PATH='@s9s_mb_2u_lib.s9s_mb_2u(sch_1):page68_i1@pure_quanta.socket4677_azif00~
45p001c01cs(chips)',
 P_PATH='@s9s_mb_2u_lib.s9s_mb_2u(sch_1):page68_i1@pure_quanta.socket4677_azif00~
45p001c01cs(chips)',
 PATH='I1',
 DRAWING='@S9S_MB_2U_LIB.S9S_MB_2U(SCH_1):PAGE68',
 PHYS_PAGE='68',
 XY='(-875,2325)',
 ROT='0',
 VER='28',
 CDS_LIB='pure_quanta',
 CDS_PART_NAME='SOCKET4677_AZIF0045P001C01CS-SA',
 PART_TYPE='SMLF',
 MATERIAL='IO',
 VALUE='SOCKET4677_AZIF0045-P001C01CS',
 PRIM_FILE='./archive_libs/logical/socket4677_azif0045p001c01cs/chips/chips.prt';

SECTION_NUMBER 29
 '@S9S_MB_2U_LIB.S9S_MB_2U(SCH_1):PAGE68_I8@PURE_QUANTA.SOCKET4677_AZIF0045P001C01CS(CHIPS)':
 C_PATH='@s9s_mb_2u_lib.s9s_mb_2u(sch_1):page68_i8@pure_quanta.socket4677_azif00~
45p001c01cs(chips)',
 P_PATH='@s9s_mb_2u_lib.s9s_mb_2u(sch_1):page68_i8@pure_quanta.socket4677_azif00~
45p001c01cs(chips)',
 PATH='I8',
 DRAWING='@S9S_MB_2U_LIB.S9S_MB_2U(SCH_1):PAGE68',
 PHYS_PAGE='68',
 XY='(3500,1925)',
 ROT='0',
 VER='29',
 CDS_LIB='pure_quanta',
 CDS_PART_NAME='SOCKET4677_AZIF0045P001C01CS-SA',
 PART_TYPE='SMLF',
 MATERIAL='IO',
 VALUE='SOCKET4677_AZIF0045-P001C01CS',
 PRIM_FILE='./archive_libs/logical/socket4677_azif0045p001c01cs/chips/chips.prt';

SECTION_NUMBER 30
 '@S9S_MB_2U_LIB.S9S_MB_2U(SCH_1):PAGE69_I1@PURE_QUANTA.SOCKET4677_AZIF0045P001C01CS(CHIPS)':
 C_PATH='@s9s_mb_2u_lib.s9s_mb_2u(sch_1):page69_i1@pure_quanta.socket4677_azif00~
45p001c01cs(chips)',
 P_PATH='@s9s_mb_2u_lib.s9s_mb_2u(sch_1):page69_i1@pure_quanta.socket4677_azif00~
45p001c01cs(chips)',
 PATH='I1',
 DRAWING='@S9S_MB_2U_LIB.S9S_MB_2U(SCH_1):PAGE69',
 PHYS_PAGE='69',
 XY='(1300,2075)',
 ROT='0',
 VER='30',
 CDS_LIB='pure_quanta',
 CDS_PART_NAME='SOCKET4677_AZIF0045P001C01CS-SA',
 PART_TYPE='SMLF',
 MATERIAL='IO',
 VALUE='SOCKET4677_AZIF0045-P001C01CS',
 PRIM_FILE='./archive_libs/logical/socket4677_azif0045p001c01cs/chips/chips.prt';

SECTION_NUMBER 31
 '@S9S_MB_2U_LIB.S9S_MB_2U(SCH_1):PAGE70_I2@PURE_QUANTA.SOCKET4677_AZIF0045P001C01CS(CHIPS)':
 C_PATH='@s9s_mb_2u_lib.s9s_mb_2u(sch_1):page70_i2@pure_quanta.socket4677_azif00~
45p001c01cs(chips)',
 P_PATH='@s9s_mb_2u_lib.s9s_mb_2u(sch_1):page70_i2@pure_quanta.socket4677_azif00~
45p001c01cs(chips)',
 PATH='I2',
 DRAWING='@S9S_MB_2U_LIB.S9S_MB_2U(SCH_1):PAGE70',
 PHYS_PAGE='70',
 XY='(-2075,1800)',
 ROT='0',
 VER='31',
 CDS_LIB='pure_quanta',
 CDS_PART_NAME='SOCKET4677_AZIF0045P001C01CS-SA',
 PART_TYPE='SMLF',
 MATERIAL='IO',
 VALUE='SOCKET4677_AZIF0045-P001C01CS',
 PRIM_FILE='./archive_libs/logical/socket4677_azif0045p001c01cs/chips/chips.prt';

SECTION_NUMBER 32
 '@S9S_MB_2U_LIB.S9S_MB_2U(SCH_1):PAGE70_I5@PURE_QUANTA.SOCKET4677_AZIF0045P001C01CS(CHIPS)':
 C_PATH='@s9s_mb_2u_lib.s9s_mb_2u(sch_1):page70_i5@pure_quanta.socket4677_azif00~
45p001c01cs(chips)',
 P_PATH='@s9s_mb_2u_lib.s9s_mb_2u(sch_1):page70_i5@pure_quanta.socket4677_azif00~
45p001c01cs(chips)',
 PATH='I5',
 DRAWING='@S9S_MB_2U_LIB.S9S_MB_2U(SCH_1):PAGE70',
 PHYS_PAGE='70',
 XY='(975,1800)',
 ROT='0',
 VER='32',
 CDS_LIB='pure_quanta',
 CDS_PART_NAME='SOCKET4677_AZIF0045P001C01CS-SA',
 PART_TYPE='SMLF',
 MATERIAL='IO',
 VALUE='SOCKET4677_AZIF0045-P001C01CS',
 PRIM_FILE='./archive_libs/logical/socket4677_azif0045p001c01cs/chips/chips.prt';

SECTION_NUMBER 33
 '@S9S_MB_2U_LIB.S9S_MB_2U(SCH_1):PAGE70_I8@PURE_QUANTA.SOCKET4677_AZIF0045P001C01CS(CHIPS)':
 C_PATH='@s9s_mb_2u_lib.s9s_mb_2u(sch_1):page70_i8@pure_quanta.socket4677_azif00~
45p001c01cs(chips)',
 P_PATH='@s9s_mb_2u_lib.s9s_mb_2u(sch_1):page70_i8@pure_quanta.socket4677_azif00~
45p001c01cs(chips)',
 PATH='I8',
 DRAWING='@S9S_MB_2U_LIB.S9S_MB_2U(SCH_1):PAGE70',
 PHYS_PAGE='70',
 XY='(4000,1800)',
 ROT='0',
 VER='33',
 CDS_LIB='pure_quanta',
 CDS_PART_NAME='SOCKET4677_AZIF0045P001C01CS-SA',
 PART_TYPE='SMLF',
 MATERIAL='IO',
 VALUE='SOCKET4677_AZIF0045-P001C01CS',
 PRIM_FILE='./archive_libs/logical/socket4677_azif0045p001c01cs/chips/chips.prt';

SECTION_NUMBER 34
 '@S9S_MB_2U_LIB.S9S_MB_2U(SCH_1):PAGE71_I2@PURE_QUANTA.SOCKET4677_AZIF0045P001C01CS(CHIPS)':
 C_PATH='@s9s_mb_2u_lib.s9s_mb_2u(sch_1):page71_i2@pure_quanta.socket4677_azif00~
45p001c01cs(chips)',
 P_PATH='@s9s_mb_2u_lib.s9s_mb_2u(sch_1):page71_i2@pure_quanta.socket4677_azif00~
45p001c01cs(chips)',
 PATH='I2',
 DRAWING='@S9S_MB_2U_LIB.S9S_MB_2U(SCH_1):PAGE71',
 PHYS_PAGE='71',
 XY='(-2375,1750)',
 ROT='0',
 VER='34',
 CDS_LIB='pure_quanta',
 CDS_PART_NAME='SOCKET4677_AZIF0045P001C01CS-SA',
 PART_TYPE='SMLF',
 MATERIAL='IO',
 VALUE='SOCKET4677_AZIF0045-P001C01CS',
 PRIM_FILE='./archive_libs/logical/socket4677_azif0045p001c01cs/chips/chips.prt';

SECTION_NUMBER 35
 '@S9S_MB_2U_LIB.S9S_MB_2U(SCH_1):PAGE71_I5@PURE_QUANTA.SOCKET4677_AZIF0045P001C01CS(CHIPS)':
 C_PATH='@s9s_mb_2u_lib.s9s_mb_2u(sch_1):page71_i5@pure_quanta.socket4677_azif00~
45p001c01cs(chips)',
 P_PATH='@s9s_mb_2u_lib.s9s_mb_2u(sch_1):page71_i5@pure_quanta.socket4677_azif00~
45p001c01cs(chips)',
 PATH='I5',
 DRAWING='@S9S_MB_2U_LIB.S9S_MB_2U(SCH_1):PAGE71',
 PHYS_PAGE='71',
 XY='(675,1750)',
 ROT='0',
 VER='35',
 CDS_LIB='pure_quanta',
 CDS_PART_NAME='SOCKET4677_AZIF0045P001C01CS-SA',
 PART_TYPE='SMLF',
 MATERIAL='IO',
 VALUE='SOCKET4677_AZIF0045-P001C01CS',
 PRIM_FILE='./archive_libs/logical/socket4677_azif0045p001c01cs/chips/chips.prt';

SECTION_NUMBER 36
 '@S9S_MB_2U_LIB.S9S_MB_2U(SCH_1):PAGE71_I8@PURE_QUANTA.SOCKET4677_AZIF0045P001C01CS(CHIPS)':
 C_PATH='@s9s_mb_2u_lib.s9s_mb_2u(sch_1):page71_i8@pure_quanta.socket4677_azif00~
45p001c01cs(chips)',
 P_PATH='@s9s_mb_2u_lib.s9s_mb_2u(sch_1):page71_i8@pure_quanta.socket4677_azif00~
45p001c01cs(chips)',
 PATH='I8',
 DRAWING='@S9S_MB_2U_LIB.S9S_MB_2U(SCH_1):PAGE71',
 PHYS_PAGE='71',
 XY='(3700,1750)',
 ROT='0',
 VER='36',
 CDS_LIB='pure_quanta',
 CDS_PART_NAME='SOCKET4677_AZIF0045P001C01CS-SA',
 PART_TYPE='SMLF',
 MATERIAL='IO',
 VALUE='SOCKET4677_AZIF0045-P001C01CS',
 PRIM_FILE='./archive_libs/logical/socket4677_azif0045p001c01cs/chips/chips.prt';

SECTION_NUMBER 37
 '@S9S_MB_2U_LIB.S9S_MB_2U(SCH_1):PAGE72_I2@PURE_QUANTA.SOCKET4677_AZIF0045P001C01CS(CHIPS)':
 C_PATH='@s9s_mb_2u_lib.s9s_mb_2u(sch_1):page72_i2@pure_quanta.socket4677_azif00~
45p001c01cs(chips)',
 P_PATH='@s9s_mb_2u_lib.s9s_mb_2u(sch_1):page72_i2@pure_quanta.socket4677_azif00~
45p001c01cs(chips)',
 PATH='I2',
 DRAWING='@S9S_MB_2U_LIB.S9S_MB_2U(SCH_1):PAGE72',
 PHYS_PAGE='72',
 XY='(-1350,1775)',
 ROT='0',
 VER='37',
 CDS_LIB='pure_quanta',
 CDS_PART_NAME='SOCKET4677_AZIF0045P001C01CS-SA',
 PART_TYPE='SMLF',
 MATERIAL='IO',
 VALUE='SOCKET4677_AZIF0045-P001C01CS',
 PRIM_FILE='./archive_libs/logical/socket4677_azif0045p001c01cs/chips/chips.prt';

SECTION_NUMBER 38
 '@S9S_MB_2U_LIB.S9S_MB_2U(SCH_1):PAGE72_I5@PURE_QUANTA.SOCKET4677_AZIF0045P001C01CS(CHIPS)':
 C_PATH='@s9s_mb_2u_lib.s9s_mb_2u(sch_1):page72_i5@pure_quanta.socket4677_azif00~
45p001c01cs(chips)',
 P_PATH='@s9s_mb_2u_lib.s9s_mb_2u(sch_1):page72_i5@pure_quanta.socket4677_azif00~
45p001c01cs(chips)',
 PATH='I5',
 DRAWING='@S9S_MB_2U_LIB.S9S_MB_2U(SCH_1):PAGE72',
 PHYS_PAGE='72',
 XY='(1700,1775)',
 ROT='0',
 VER='38',
 CDS_LIB='pure_quanta',
 CDS_PART_NAME='SOCKET4677_AZIF0045P001C01CS-SA',
 PART_TYPE='SMLF',
 MATERIAL='IO',
 VALUE='SOCKET4677_AZIF0045-P001C01CS',
 PRIM_FILE='./archive_libs/logical/socket4677_azif0045p001c01cs/chips/chips.prt';

SECTION_NUMBER 39
 '@S9S_MB_2U_LIB.S9S_MB_2U(SCH_1):PAGE72_I8@PURE_QUANTA.SOCKET4677_AZIF0045P001C01CS(CHIPS)':
 C_PATH='@s9s_mb_2u_lib.s9s_mb_2u(sch_1):page72_i8@pure_quanta.socket4677_azif00~
45p001c01cs(chips)',
 P_PATH='@s9s_mb_2u_lib.s9s_mb_2u(sch_1):page72_i8@pure_quanta.socket4677_azif00~
45p001c01cs(chips)',
 PATH='I8',
 DRAWING='@S9S_MB_2U_LIB.S9S_MB_2U(SCH_1):PAGE72',
 PHYS_PAGE='72',
 XY='(4725,1775)',
 ROT='0',
 VER='39',
 CDS_LIB='pure_quanta',
 CDS_PART_NAME='SOCKET4677_AZIF0045P001C01CS-SA',
 PART_TYPE='SMLF',
 MATERIAL='IO',
 VALUE='SOCKET4677_AZIF0045-P001C01CS',
 PRIM_FILE='./archive_libs/logical/socket4677_azif0045p001c01cs/chips/chips.prt';

SECTION_NUMBER 40
 '@S9S_MB_2U_LIB.S9S_MB_2U(SCH_1):PAGE73_I2@PURE_QUANTA.SOCKET4677_AZIF0045P001C01CS(CHIPS)':
 C_PATH='@s9s_mb_2u_lib.s9s_mb_2u(sch_1):page73_i2@pure_quanta.socket4677_azif00~
45p001c01cs(chips)',
 P_PATH='@s9s_mb_2u_lib.s9s_mb_2u(sch_1):page73_i2@pure_quanta.socket4677_azif00~
45p001c01cs(chips)',
 PATH='I2',
 DRAWING='@S9S_MB_2U_LIB.S9S_MB_2U(SCH_1):PAGE73',
 PHYS_PAGE='73',
 XY='(-1600,1850)',
 ROT='0',
 VER='40',
 CDS_LIB='pure_quanta',
 CDS_PART_NAME='SOCKET4677_AZIF0045P001C01CS-SA',
 PART_TYPE='SMLF',
 MATERIAL='IO',
 VALUE='SOCKET4677_AZIF0045-P001C01CS',
 PRIM_FILE='./archive_libs/logical/socket4677_azif0045p001c01cs/chips/chips.prt';

SECTION_NUMBER 41
 '@S9S_MB_2U_LIB.S9S_MB_2U(SCH_1):PAGE73_I5@PURE_QUANTA.SOCKET4677_AZIF0045P001C01CS(CHIPS)':
 C_PATH='@s9s_mb_2u_lib.s9s_mb_2u(sch_1):page73_i5@pure_quanta.socket4677_azif00~
45p001c01cs(chips)',
 P_PATH='@s9s_mb_2u_lib.s9s_mb_2u(sch_1):page73_i5@pure_quanta.socket4677_azif00~
45p001c01cs(chips)',
 PATH='I5',
 DRAWING='@S9S_MB_2U_LIB.S9S_MB_2U(SCH_1):PAGE73',
 PHYS_PAGE='73',
 XY='(1450,1850)',
 ROT='0',
 VER='41',
 CDS_LIB='pure_quanta',
 CDS_PART_NAME='SOCKET4677_AZIF0045P001C01CS-SA',
 PART_TYPE='SMLF',
 MATERIAL='IO',
 VALUE='SOCKET4677_AZIF0045-P001C01CS',
 PRIM_FILE='./archive_libs/logical/socket4677_azif0045p001c01cs/chips/chips.prt';

SECTION_NUMBER 42
 '@S9S_MB_2U_LIB.S9S_MB_2U(SCH_1):PAGE73_I8@PURE_QUANTA.SOCKET4677_AZIF0045P001C01CS(CHIPS)':
 C_PATH='@s9s_mb_2u_lib.s9s_mb_2u(sch_1):page73_i8@pure_quanta.socket4677_azif00~
45p001c01cs(chips)',
 P_PATH='@s9s_mb_2u_lib.s9s_mb_2u(sch_1):page73_i8@pure_quanta.socket4677_azif00~
45p001c01cs(chips)',
 PATH='I8',
 DRAWING='@S9S_MB_2U_LIB.S9S_MB_2U(SCH_1):PAGE73',
 PHYS_PAGE='73',
 XY='(4475,1900)',
 ROT='0',
 VER='42',
 CDS_LIB='pure_quanta',
 CDS_PART_NAME='SOCKET4677_AZIF0045P001C01CS-SA',
 PART_TYPE='SMLF',
 MATERIAL='IO',
 VALUE='SOCKET4677_AZIF0045-P001C01CS',
 PRIM_FILE='./archive_libs/logical/socket4677_azif0045p001c01cs/chips/chips.prt';

PART_NAME
 U1_BL 'TP_TP_BOM ONLY-NA,TP12_BOM':;

SECTION_NUMBER 1
 '@S9S_MB_2U_LIB.S9S_MB_2U(SCH_1):PAGE290_I40@PURE_QUANTA.TP(CHIPS)':
 C_PATH='@s9s_mb_2u_lib.s9s_mb_2u(sch_1):page290_i40@pure_quanta.tp(chips)',
 P_PATH='@s9s_mb_2u_lib.s9s_mb_2u(sch_1):page312_i40@pure_quanta.tp(chips)',
 PATH='I40',
 DRAWING='@S9S_MB_2U_LIB.S9S_MB_2U(SCH_1):PAGE290',
 QPN='DGRA^000178',
 PHYS_PAGE='312',
 XY='(-500,800)',
 ROT='0',
 VER='1',
 PACK_TYPE='TP_BOM ONLY',
 LOCATION='U1_BL',
 CDS_LIB='pure_quanta',
 CDS_PART_NAME='TP_TP_BOM ONLY-NA,TP12_BOM',
 MATERIAL='NA',
 PRIM_FILE='./archive_libs/logical/tp/chips/chips.prt';

PART_NAME
 U1_BP 'TP_TP_BOM ONLY-NA,TP12_BOM':;

SECTION_NUMBER 1
 '@S9S_MB_2U_LIB.S9S_MB_2U(SCH_1):PAGE290_I43@PURE_QUANTA.TP(CHIPS)':
 C_PATH='@s9s_mb_2u_lib.s9s_mb_2u(sch_1):page290_i43@pure_quanta.tp(chips)',
 P_PATH='@s9s_mb_2u_lib.s9s_mb_2u(sch_1):page312_i43@pure_quanta.tp(chips)',
 PATH='I43',
 DRAWING='@S9S_MB_2U_LIB.S9S_MB_2U(SCH_1):PAGE290',
 QPN='DGRA^000128',
 PHYS_PAGE='312',
 XY='(-500,250)',
 ROT='0',
 VER='1',
 PACK_TYPE='TP_BOM ONLY',
 LOCATION='U1_BP',
 CDS_LIB='pure_quanta',
 CDS_PART_NAME='TP_TP_BOM ONLY-NA,TP12_BOM',
 MATERIAL='NA',
 PRIM_FILE='./archive_libs/logical/tp/chips/chips.prt';

PART_NAME
 U1_DC 'TP_TP_BOM ONLY-NA,TP12_BOM':;

SECTION_NUMBER 1
 '@S9S_MB_2U_LIB.S9S_MB_2U(SCH_1):PAGE290_I47@PURE_QUANTA.TP(CHIPS)':
 C_PATH='@s9s_mb_2u_lib.s9s_mb_2u(sch_1):page290_i47@pure_quanta.tp(chips)',
 P_PATH='@s9s_mb_2u_lib.s9s_mb_2u(sch_1):page312_i47@pure_quanta.tp(chips)',
 PATH='I47',
 DRAWING='@S9S_MB_2U_LIB.S9S_MB_2U(SCH_1):PAGE290',
 QPN='DGRA^000180',
 PHYS_PAGE='312',
 XY='(825,250)',
 ROT='0',
 VER='1',
 PACK_TYPE='TP_BOM ONLY',
 LOCATION='U1_DC',
 CDS_LIB='pure_quanta',
 CDS_PART_NAME='TP_TP_BOM ONLY-NA,TP12_BOM',
 MATERIAL='NA',
 PRIM_FILE='./archive_libs/logical/tp/chips/chips.prt';

PART_NAME
 U2 'SOCKET4677_AZIF0045P001C01CS-SA':;

SECTION_NUMBER 1
 '@S9S_MB_2U_LIB.S9S_MB_2U(SCH_1):PAGE13_I57@PURE_QUANTA.SOCKET4677_AZIF0045P001C01CS(CHIPS)':
 C_PATH='@s9s_mb_2u_lib.s9s_mb_2u(sch_1):page13_i57@pure_quanta.socket4677_azif0~
045p001c01cs(chips)',
 P_PATH='@s9s_mb_2u_lib.s9s_mb_2u(sch_1):page13_i57@pure_quanta.socket4677_azif0~
045p001c01cs(chips)',
 PATH='I57',
 DRAWING='@S9S_MB_2U_LIB.S9S_MB_2U(SCH_1):PAGE13',
 PHYS_PAGE='13',
 XY='(700,2650)',
 ROT='0',
 VER='1',
 CDS_LIB='pure_quanta',
 CDS_PART_NAME='SOCKET4677_AZIF0045P001C01CS-SA',
 PART_TYPE='SMLF',
 MATERIAL='IO',
 VALUE='SOCKET4677_AZIF0045-P001C01CS',
 PRIM_FILE='./archive_libs/logical/socket4677_azif0045p001c01cs/chips/chips.prt';

SECTION_NUMBER 2
 '@S9S_MB_2U_LIB.S9S_MB_2U(SCH_1):PAGE14_I1@PURE_QUANTA.SOCKET4677_AZIF0045P001C01CS(CHIPS)':
 C_PATH='@s9s_mb_2u_lib.s9s_mb_2u(sch_1):page14_i1@pure_quanta.socket4677_azif00~
45p001c01cs(chips)',
 P_PATH='@s9s_mb_2u_lib.s9s_mb_2u(sch_1):page14_i1@pure_quanta.socket4677_azif00~
45p001c01cs(chips)',
 PATH='I1',
 DRAWING='@S9S_MB_2U_LIB.S9S_MB_2U(SCH_1):PAGE14',
 PHYS_PAGE='14',
 XY='(-350,3250)',
 ROT='0',
 VER='2',
 CDS_LIB='pure_quanta',
 CDS_PART_NAME='SOCKET4677_AZIF0045P001C01CS-SA',
 PART_TYPE='SMLF',
 MATERIAL='IO',
 VALUE='SOCKET4677_AZIF0045-P001C01CS',
 PRIM_FILE='./archive_libs/logical/socket4677_azif0045p001c01cs/chips/chips.prt';

SECTION_NUMBER 3
 '@S9S_MB_2U_LIB.S9S_MB_2U(SCH_1):PAGE15_I1@PURE_QUANTA.SOCKET4677_AZIF0045P001C01CS(CHIPS)':
 C_PATH='@s9s_mb_2u_lib.s9s_mb_2u(sch_1):page15_i1@pure_quanta.socket4677_azif00~
45p001c01cs(chips)',
 P_PATH='@s9s_mb_2u_lib.s9s_mb_2u(sch_1):page15_i1@pure_quanta.socket4677_azif00~
45p001c01cs(chips)',
 PATH='I1',
 DRAWING='@S9S_MB_2U_LIB.S9S_MB_2U(SCH_1):PAGE15',
 PHYS_PAGE='15',
 XY='(200,2475)',
 ROT='0',
 VER='3',
 CDS_LIB='pure_quanta',
 CDS_PART_NAME='SOCKET4677_AZIF0045P001C01CS-SA',
 PART_TYPE='SMLF',
 MATERIAL='IO',
 VALUE='SOCKET4677_AZIF0045-P001C01CS',
 PRIM_FILE='./archive_libs/logical/socket4677_azif0045p001c01cs/chips/chips.prt';

SECTION_NUMBER 4
 '@S9S_MB_2U_LIB.S9S_MB_2U(SCH_1):PAGE16_I1@PURE_QUANTA.SOCKET4677_AZIF0045P001C01CS(CHIPS)':
 C_PATH='@s9s_mb_2u_lib.s9s_mb_2u(sch_1):page16_i1@pure_quanta.socket4677_azif00~
45p001c01cs(chips)',
 P_PATH='@s9s_mb_2u_lib.s9s_mb_2u(sch_1):page16_i1@pure_quanta.socket4677_azif00~
45p001c01cs(chips)',
 PATH='I1',
 DRAWING='@S9S_MB_2U_LIB.S9S_MB_2U(SCH_1):PAGE16',
 PHYS_PAGE='16',
 XY='(1025,2875)',
 ROT='0',
 VER='4',
 CDS_LIB='pure_quanta',
 CDS_PART_NAME='SOCKET4677_AZIF0045P001C01CS-SA',
 PART_TYPE='SMLF',
 MATERIAL='IO',
 VALUE='SOCKET4677_AZIF0045-P001C01CS',
 PRIM_FILE='./archive_libs/logical/socket4677_azif0045p001c01cs/chips/chips.prt';

SECTION_NUMBER 5
 '@S9S_MB_2U_LIB.S9S_MB_2U(SCH_1):PAGE17_I1@PURE_QUANTA.SOCKET4677_AZIF0045P001C01CS(CHIPS)':
 C_PATH='@s9s_mb_2u_lib.s9s_mb_2u(sch_1):page17_i1@pure_quanta.socket4677_azif00~
45p001c01cs(chips)',
 P_PATH='@s9s_mb_2u_lib.s9s_mb_2u(sch_1):page17_i1@pure_quanta.socket4677_azif00~
45p001c01cs(chips)',
 PATH='I1',
 DRAWING='@S9S_MB_2U_LIB.S9S_MB_2U(SCH_1):PAGE17',
 PHYS_PAGE='17',
 XY='(475,2925)',
 ROT='0',
 VER='5',
 CDS_LIB='pure_quanta',
 CDS_PART_NAME='SOCKET4677_AZIF0045P001C01CS-SA',
 PART_TYPE='SMLF',
 MATERIAL='IO',
 VALUE='SOCKET4677_AZIF0045-P001C01CS',
 PRIM_FILE='./archive_libs/logical/socket4677_azif0045p001c01cs/chips/chips.prt';

SECTION_NUMBER 6
 '@S9S_MB_2U_LIB.S9S_MB_2U(SCH_1):PAGE18_I1@PURE_QUANTA.SOCKET4677_AZIF0045P001C01CS(CHIPS)':
 C_PATH='@s9s_mb_2u_lib.s9s_mb_2u(sch_1):page18_i1@pure_quanta.socket4677_azif00~
45p001c01cs(chips)',
 P_PATH='@s9s_mb_2u_lib.s9s_mb_2u(sch_1):page18_i1@pure_quanta.socket4677_azif00~
45p001c01cs(chips)',
 PATH='I1',
 DRAWING='@S9S_MB_2U_LIB.S9S_MB_2U(SCH_1):PAGE18',
 PHYS_PAGE='18',
 XY='(1750,2600)',
 ROT='0',
 VER='6',
 CDS_LIB='pure_quanta',
 CDS_PART_NAME='SOCKET4677_AZIF0045P001C01CS-SA',
 PART_TYPE='SMLF',
 MATERIAL='IO',
 VALUE='SOCKET4677_AZIF0045-P001C01CS',
 PRIM_FILE='./archive_libs/logical/socket4677_azif0045p001c01cs/chips/chips.prt';

SECTION_NUMBER 7
 '@S9S_MB_2U_LIB.S9S_MB_2U(SCH_1):PAGE19_I1@PURE_QUANTA.SOCKET4677_AZIF0045P001C01CS(CHIPS)':
 C_PATH='@s9s_mb_2u_lib.s9s_mb_2u(sch_1):page19_i1@pure_quanta.socket4677_azif00~
45p001c01cs(chips)',
 P_PATH='@s9s_mb_2u_lib.s9s_mb_2u(sch_1):page19_i1@pure_quanta.socket4677_azif00~
45p001c01cs(chips)',
 PATH='I1',
 DRAWING='@S9S_MB_2U_LIB.S9S_MB_2U(SCH_1):PAGE19',
 PHYS_PAGE='19',
 XY='(1500,2625)',
 ROT='0',
 VER='7',
 CDS_LIB='pure_quanta',
 CDS_PART_NAME='SOCKET4677_AZIF0045P001C01CS-SA',
 PART_TYPE='SMLF',
 MATERIAL='IO',
 VALUE='SOCKET4677_AZIF0045-P001C01CS',
 PRIM_FILE='./archive_libs/logical/socket4677_azif0045p001c01cs/chips/chips.prt';

SECTION_NUMBER 8
 '@S9S_MB_2U_LIB.S9S_MB_2U(SCH_1):PAGE20_I1@PURE_QUANTA.SOCKET4677_AZIF0045P001C01CS(CHIPS)':
 C_PATH='@s9s_mb_2u_lib.s9s_mb_2u(sch_1):page20_i1@pure_quanta.socket4677_azif00~
45p001c01cs(chips)',
 P_PATH='@s9s_mb_2u_lib.s9s_mb_2u(sch_1):page20_i1@pure_quanta.socket4677_azif00~
45p001c01cs(chips)',
 PATH='I1',
 DRAWING='@S9S_MB_2U_LIB.S9S_MB_2U(SCH_1):PAGE20',
 PHYS_PAGE='20',
 XY='(1100,2100)',
 ROT='0',
 VER='8',
 CDS_LIB='pure_quanta',
 CDS_PART_NAME='SOCKET4677_AZIF0045P001C01CS-SA',
 PART_TYPE='SMLF',
 MATERIAL='IO',
 VALUE='SOCKET4677_AZIF0045-P001C01CS',
 PRIM_FILE='./archive_libs/logical/socket4677_azif0045p001c01cs/chips/chips.prt';

SECTION_NUMBER 9
 '@S9S_MB_2U_LIB.S9S_MB_2U(SCH_1):PAGE21_I169@PURE_QUANTA.SOCKET4677_AZIF0045P001C01CS(CHIPS)':
 C_PATH='@s9s_mb_2u_lib.s9s_mb_2u(sch_1):page21_i169@pure_quanta.socket4677_azif~
0045p001c01cs(chips)',
 P_PATH='@s9s_mb_2u_lib.s9s_mb_2u(sch_1):page21_i169@pure_quanta.socket4677_azif~
0045p001c01cs(chips)',
 PATH='I169',
 DRAWING='@S9S_MB_2U_LIB.S9S_MB_2U(SCH_1):PAGE21',
 PHYS_PAGE='21',
 XY='(1550,1875)',
 ROT='0',
 VER='9',
 CDS_LIB='pure_quanta',
 CDS_PART_NAME='SOCKET4677_AZIF0045P001C01CS-SA',
 PART_TYPE='SMLF',
 MATERIAL='IO',
 VALUE='SOCKET4677_AZIF0045-P001C01CS',
 PRIM_FILE='./archive_libs/logical/socket4677_azif0045p001c01cs/chips/chips.prt';

SECTION_NUMBER 10
 '@S9S_MB_2U_LIB.S9S_MB_2U(SCH_1):PAGE22_I169@PURE_QUANTA.SOCKET4677_AZIF0045P001C01CS(CHIPS)':
 C_PATH='@s9s_mb_2u_lib.s9s_mb_2u(sch_1):page22_i169@pure_quanta.socket4677_azif~
0045p001c01cs(chips)',
 P_PATH='@s9s_mb_2u_lib.s9s_mb_2u(sch_1):page22_i169@pure_quanta.socket4677_azif~
0045p001c01cs(chips)',
 PATH='I169',
 DRAWING='@S9S_MB_2U_LIB.S9S_MB_2U(SCH_1):PAGE22',
 PHYS_PAGE='22',
 XY='(1725,1525)',
 ROT='0',
 VER='10',
 CDS_LIB='pure_quanta',
 CDS_PART_NAME='SOCKET4677_AZIF0045P001C01CS-SA',
 PART_TYPE='SMLF',
 MATERIAL='IO',
 VALUE='SOCKET4677_AZIF0045-P001C01CS',
 PRIM_FILE='./archive_libs/logical/socket4677_azif0045p001c01cs/chips/chips.prt';

SECTION_NUMBER 11
 '@S9S_MB_2U_LIB.S9S_MB_2U(SCH_1):PAGE23_I169@PURE_QUANTA.SOCKET4677_AZIF0045P001C01CS(CHIPS)':
 C_PATH='@s9s_mb_2u_lib.s9s_mb_2u(sch_1):page23_i169@pure_quanta.socket4677_azif~
0045p001c01cs(chips)',
 P_PATH='@s9s_mb_2u_lib.s9s_mb_2u(sch_1):page23_i169@pure_quanta.socket4677_azif~
0045p001c01cs(chips)',
 PATH='I169',
 DRAWING='@S9S_MB_2U_LIB.S9S_MB_2U(SCH_1):PAGE23',
 PHYS_PAGE='23',
 XY='(1700,1800)',
 ROT='0',
 VER='11',
 CDS_LIB='pure_quanta',
 CDS_PART_NAME='SOCKET4677_AZIF0045P001C01CS-SA',
 PART_TYPE='SMLF',
 MATERIAL='IO',
 VALUE='SOCKET4677_AZIF0045-P001C01CS',
 PRIM_FILE='./archive_libs/logical/socket4677_azif0045p001c01cs/chips/chips.prt';

SECTION_NUMBER 12
 '@S9S_MB_2U_LIB.S9S_MB_2U(SCH_1):PAGE24_I169@PURE_QUANTA.SOCKET4677_AZIF0045P001C01CS(CHIPS)':
 C_PATH='@s9s_mb_2u_lib.s9s_mb_2u(sch_1):page24_i169@pure_quanta.socket4677_azif~
0045p001c01cs(chips)',
 P_PATH='@s9s_mb_2u_lib.s9s_mb_2u(sch_1):page24_i169@pure_quanta.socket4677_azif~
0045p001c01cs(chips)',
 PATH='I169',
 DRAWING='@S9S_MB_2U_LIB.S9S_MB_2U(SCH_1):PAGE24',
 PHYS_PAGE='24',
 XY='(1025,1900)',
 ROT='0',
 VER='12',
 CDS_LIB='pure_quanta',
 CDS_PART_NAME='SOCKET4677_AZIF0045P001C01CS-SA',
 PART_TYPE='SMLF',
 MATERIAL='IO',
 VALUE='SOCKET4677_AZIF0045-P001C01CS',
 PRIM_FILE='./archive_libs/logical/socket4677_azif0045p001c01cs/chips/chips.prt';

SECTION_NUMBER 13
 '@S9S_MB_2U_LIB.S9S_MB_2U(SCH_1):PAGE25_I169@PURE_QUANTA.SOCKET4677_AZIF0045P001C01CS(CHIPS)':
 C_PATH='@s9s_mb_2u_lib.s9s_mb_2u(sch_1):page25_i169@pure_quanta.socket4677_azif~
0045p001c01cs(chips)',
 P_PATH='@s9s_mb_2u_lib.s9s_mb_2u(sch_1):page25_i169@pure_quanta.socket4677_azif~
0045p001c01cs(chips)',
 PATH='I169',
 DRAWING='@S9S_MB_2U_LIB.S9S_MB_2U(SCH_1):PAGE25',
 PHYS_PAGE='25',
 XY='(1500,1750)',
 ROT='0',
 VER='13',
 CDS_LIB='pure_quanta',
 CDS_PART_NAME='SOCKET4677_AZIF0045P001C01CS-SA',
 PART_TYPE='SMLF',
 MATERIAL='IO',
 VALUE='SOCKET4677_AZIF0045-P001C01CS',
 PRIM_FILE='./archive_libs/logical/socket4677_azif0045p001c01cs/chips/chips.prt';

SECTION_NUMBER 14
 '@S9S_MB_2U_LIB.S9S_MB_2U(SCH_1):PAGE26_I169@PURE_QUANTA.SOCKET4677_AZIF0045P001C01CS(CHIPS)':
 C_PATH='@s9s_mb_2u_lib.s9s_mb_2u(sch_1):page26_i169@pure_quanta.socket4677_azif~
0045p001c01cs(chips)',
 P_PATH='@s9s_mb_2u_lib.s9s_mb_2u(sch_1):page26_i169@pure_quanta.socket4677_azif~
0045p001c01cs(chips)',
 PATH='I169',
 DRAWING='@S9S_MB_2U_LIB.S9S_MB_2U(SCH_1):PAGE26',
 PHYS_PAGE='26',
 XY='(1525,1950)',
 ROT='0',
 VER='14',
 CDS_LIB='pure_quanta',
 CDS_PART_NAME='SOCKET4677_AZIF0045P001C01CS-SA',
 PART_TYPE='SMLF',
 MATERIAL='IO',
 VALUE='SOCKET4677_AZIF0045-P001C01CS',
 PRIM_FILE='./archive_libs/logical/socket4677_azif0045p001c01cs/chips/chips.prt';

SECTION_NUMBER 15
 '@S9S_MB_2U_LIB.S9S_MB_2U(SCH_1):PAGE27_I169@PURE_QUANTA.SOCKET4677_AZIF0045P001C01CS(CHIPS)':
 C_PATH='@s9s_mb_2u_lib.s9s_mb_2u(sch_1):page27_i169@pure_quanta.socket4677_azif~
0045p001c01cs(chips)',
 P_PATH='@s9s_mb_2u_lib.s9s_mb_2u(sch_1):page27_i169@pure_quanta.socket4677_azif~
0045p001c01cs(chips)',
 PATH='I169',
 DRAWING='@S9S_MB_2U_LIB.S9S_MB_2U(SCH_1):PAGE27',
 PHYS_PAGE='27',
 XY='(775,2400)',
 ROT='0',
 VER='15',
 CDS_LIB='pure_quanta',
 CDS_PART_NAME='SOCKET4677_AZIF0045P001C01CS-SA',
 PART_TYPE='SMLF',
 MATERIAL='IO',
 VALUE='SOCKET4677_AZIF0045-P001C01CS',
 PRIM_FILE='./archive_libs/logical/socket4677_azif0045p001c01cs/chips/chips.prt';

SECTION_NUMBER 16
 '@S9S_MB_2U_LIB.S9S_MB_2U(SCH_1):PAGE28_I169@PURE_QUANTA.SOCKET4677_AZIF0045P001C01CS(CHIPS)':
 C_PATH='@s9s_mb_2u_lib.s9s_mb_2u(sch_1):page28_i169@pure_quanta.socket4677_azif~
0045p001c01cs(chips)',
 P_PATH='@s9s_mb_2u_lib.s9s_mb_2u(sch_1):page28_i169@pure_quanta.socket4677_azif~
0045p001c01cs(chips)',
 PATH='I169',
 DRAWING='@S9S_MB_2U_LIB.S9S_MB_2U(SCH_1):PAGE28',
 PHYS_PAGE='28',
 XY='(1475,3600)',
 ROT='0',
 VER='16',
 CDS_LIB='pure_quanta',
 CDS_PART_NAME='SOCKET4677_AZIF0045P001C01CS-SA',
 PART_TYPE='SMLF',
 MATERIAL='IO',
 VALUE='SOCKET4677_AZIF0045-P001C01CS',
 PRIM_FILE='./archive_libs/logical/socket4677_azif0045p001c01cs/chips/chips.prt';

SECTION_NUMBER 17
 '@S9S_MB_2U_LIB.S9S_MB_2U(SCH_1):PAGE29_I37@PURE_QUANTA.SOCKET4677_AZIF0045P001C01CS(CHIPS)':
 C_PATH='@s9s_mb_2u_lib.s9s_mb_2u(sch_1):page29_i37@pure_quanta.socket4677_azif0~
045p001c01cs(chips)',
 P_PATH='@s9s_mb_2u_lib.s9s_mb_2u(sch_1):page29_i37@pure_quanta.socket4677_azif0~
045p001c01cs(chips)',
 PATH='I37',
 DRAWING='@S9S_MB_2U_LIB.S9S_MB_2U(SCH_1):PAGE29',
 PHYS_PAGE='29',
 XY='(1400,3075)',
 ROT='0',
 VER='17',
 CDS_LIB='pure_quanta',
 CDS_PART_NAME='SOCKET4677_AZIF0045P001C01CS-SA',
 PART_TYPE='SMLF',
 MATERIAL='IO',
 VALUE='SOCKET4677_AZIF0045-P001C01CS',
 PRIM_FILE='./archive_libs/logical/socket4677_azif0045p001c01cs/chips/chips.prt';

SECTION_NUMBER 18
 '@S9S_MB_2U_LIB.S9S_MB_2U(SCH_1):PAGE29_I176@PURE_QUANTA.SOCKET4677_AZIF0045P001C01CS(CHIPS)':
 C_PATH='@s9s_mb_2u_lib.s9s_mb_2u(sch_1):page29_i176@pure_quanta.socket4677_azif~
0045p001c01cs(chips)',
 P_PATH='@s9s_mb_2u_lib.s9s_mb_2u(sch_1):page29_i176@pure_quanta.socket4677_azif~
0045p001c01cs(chips)',
 PATH='I176',
 DRAWING='@S9S_MB_2U_LIB.S9S_MB_2U(SCH_1):PAGE29',
 PHYS_PAGE='29',
 XY='(1400,325)',
 ROT='0',
 VER='18',
 CDS_LIB='pure_quanta',
 CDS_PART_NAME='SOCKET4677_AZIF0045P001C01CS-SA',
 PART_TYPE='SMLF',
 MATERIAL='IO',
 VALUE='SOCKET4677_AZIF0045-P001C01CS',
 PRIM_FILE='./archive_libs/logical/socket4677_azif0045p001c01cs/chips/chips.prt';

SECTION_NUMBER 19
 '@S9S_MB_2U_LIB.S9S_MB_2U(SCH_1):PAGE30_I139@PURE_QUANTA.SOCKET4677_AZIF0045P001C01CS(CHIPS)':
 C_PATH='@s9s_mb_2u_lib.s9s_mb_2u(sch_1):page30_i139@pure_quanta.socket4677_azif~
0045p001c01cs(chips)',
 P_PATH='@s9s_mb_2u_lib.s9s_mb_2u(sch_1):page30_i139@pure_quanta.socket4677_azif~
0045p001c01cs(chips)',
 PATH='I139',
 DRAWING='@S9S_MB_2U_LIB.S9S_MB_2U(SCH_1):PAGE30',
 PHYS_PAGE='30',
 XY='(1100,3025)',
 ROT='0',
 VER='19',
 CDS_LIB='pure_quanta',
 CDS_PART_NAME='SOCKET4677_AZIF0045P001C01CS-SA',
 PART_TYPE='SMLF',
 MATERIAL='IO',
 VALUE='SOCKET4677_AZIF0045-P001C01CS',
 PRIM_FILE='./archive_libs/logical/socket4677_azif0045p001c01cs/chips/chips.prt';

SECTION_NUMBER 20
 '@S9S_MB_2U_LIB.S9S_MB_2U(SCH_1):PAGE30_I140@PURE_QUANTA.SOCKET4677_AZIF0045P001C01CS(CHIPS)':
 C_PATH='@s9s_mb_2u_lib.s9s_mb_2u(sch_1):page30_i140@pure_quanta.socket4677_azif~
0045p001c01cs(chips)',
 P_PATH='@s9s_mb_2u_lib.s9s_mb_2u(sch_1):page30_i140@pure_quanta.socket4677_azif~
0045p001c01cs(chips)',
 PATH='I140',
 DRAWING='@S9S_MB_2U_LIB.S9S_MB_2U(SCH_1):PAGE30',
 PHYS_PAGE='30',
 XY='(1100,250)',
 ROT='0',
 VER='20',
 CDS_LIB='pure_quanta',
 CDS_PART_NAME='SOCKET4677_AZIF0045P001C01CS-SA',
 PART_TYPE='SMLF',
 MATERIAL='IO',
 VALUE='SOCKET4677_AZIF0045-P001C01CS',
 PRIM_FILE='./archive_libs/logical/socket4677_azif0045p001c01cs/chips/chips.prt';

SECTION_NUMBER 21
 '@S9S_MB_2U_LIB.S9S_MB_2U(SCH_1):PAGE31_I139@PURE_QUANTA.SOCKET4677_AZIF0045P001C01CS(CHIPS)':
 C_PATH='@s9s_mb_2u_lib.s9s_mb_2u(sch_1):page31_i139@pure_quanta.socket4677_azif~
0045p001c01cs(chips)',
 P_PATH='@s9s_mb_2u_lib.s9s_mb_2u(sch_1):page31_i139@pure_quanta.socket4677_azif~
0045p001c01cs(chips)',
 PATH='I139',
 DRAWING='@S9S_MB_2U_LIB.S9S_MB_2U(SCH_1):PAGE31',
 PHYS_PAGE='31',
 XY='(2100,3125)',
 ROT='0',
 VER='21',
 CDS_LIB='pure_quanta',
 CDS_PART_NAME='SOCKET4677_AZIF0045P001C01CS-SA',
 PART_TYPE='SMLF',
 MATERIAL='IO',
 VALUE='SOCKET4677_AZIF0045-P001C01CS',
 PRIM_FILE='./archive_libs/logical/socket4677_azif0045p001c01cs/chips/chips.prt';

SECTION_NUMBER 22
 '@S9S_MB_2U_LIB.S9S_MB_2U(SCH_1):PAGE32_I70@PURE_QUANTA.SOCKET4677_AZIF0045P001C01CS(CHIPS)':
 C_PATH='@s9s_mb_2u_lib.s9s_mb_2u(sch_1):page32_i70@pure_quanta.socket4677_azif0~
045p001c01cs(chips)',
 P_PATH='@s9s_mb_2u_lib.s9s_mb_2u(sch_1):page32_i70@pure_quanta.socket4677_azif0~
045p001c01cs(chips)',
 PATH='I70',
 DRAWING='@S9S_MB_2U_LIB.S9S_MB_2U(SCH_1):PAGE32',
 PHYS_PAGE='32',
 XY='(1300,2475)',
 ROT='0',
 VER='22',
 CDS_LIB='pure_quanta',
 CDS_PART_NAME='SOCKET4677_AZIF0045P001C01CS-SA',
 PART_TYPE='SMLF',
 MATERIAL='IO',
 VALUE='SOCKET4677_AZIF0045-P001C01CS',
 PRIM_FILE='./archive_libs/logical/socket4677_azif0045p001c01cs/chips/chips.prt';

SECTION_NUMBER 23
 '@S9S_MB_2U_LIB.S9S_MB_2U(SCH_1):PAGE33_I102@PURE_QUANTA.SOCKET4677_AZIF0045P001C01CS(CHIPS)':
 C_PATH='@s9s_mb_2u_lib.s9s_mb_2u(sch_1):page33_i102@pure_quanta.socket4677_azif~
0045p001c01cs(chips)',
 P_PATH='@s9s_mb_2u_lib.s9s_mb_2u(sch_1):page33_i102@pure_quanta.socket4677_azif~
0045p001c01cs(chips)',
 PATH='I102',
 DRAWING='@S9S_MB_2U_LIB.S9S_MB_2U(SCH_1):PAGE33',
 PHYS_PAGE='33',
 XY='(1050,2375)',
 ROT='0',
 VER='23',
 CDS_LIB='pure_quanta',
 CDS_PART_NAME='SOCKET4677_AZIF0045P001C01CS-SA',
 PART_TYPE='SMLF',
 MATERIAL='IO',
 VALUE='SOCKET4677_AZIF0045-P001C01CS',
 PRIM_FILE='./archive_libs/logical/socket4677_azif0045p001c01cs/chips/chips.prt';

SECTION_NUMBER 24
 '@S9S_MB_2U_LIB.S9S_MB_2U(SCH_1):PAGE34_I102@PURE_QUANTA.SOCKET4677_AZIF0045P001C01CS(CHIPS)':
 C_PATH='@s9s_mb_2u_lib.s9s_mb_2u(sch_1):page34_i102@pure_quanta.socket4677_azif~
0045p001c01cs(chips)',
 P_PATH='@s9s_mb_2u_lib.s9s_mb_2u(sch_1):page34_i102@pure_quanta.socket4677_azif~
0045p001c01cs(chips)',
 PATH='I102',
 DRAWING='@S9S_MB_2U_LIB.S9S_MB_2U(SCH_1):PAGE34',
 PHYS_PAGE='34',
 XY='(900,2600)',
 ROT='0',
 VER='24',
 CDS_LIB='pure_quanta',
 CDS_PART_NAME='SOCKET4677_AZIF0045P001C01CS-SA',
 PART_TYPE='SMLF',
 MATERIAL='IO',
 VALUE='SOCKET4677_AZIF0045-P001C01CS',
 PRIM_FILE='./archive_libs/logical/socket4677_azif0045p001c01cs/chips/chips.prt';

SECTION_NUMBER 25
 '@S9S_MB_2U_LIB.S9S_MB_2U(SCH_1):PAGE35_I102@PURE_QUANTA.SOCKET4677_AZIF0045P001C01CS(CHIPS)':
 C_PATH='@s9s_mb_2u_lib.s9s_mb_2u(sch_1):page35_i102@pure_quanta.socket4677_azif~
0045p001c01cs(chips)',
 P_PATH='@s9s_mb_2u_lib.s9s_mb_2u(sch_1):page35_i102@pure_quanta.socket4677_azif~
0045p001c01cs(chips)',
 PATH='I102',
 DRAWING='@S9S_MB_2U_LIB.S9S_MB_2U(SCH_1):PAGE35',
 PHYS_PAGE='35',
 XY='(650,2600)',
 ROT='0',
 VER='25',
 CDS_LIB='pure_quanta',
 CDS_PART_NAME='SOCKET4677_AZIF0045P001C01CS-SA',
 PART_TYPE='SMLF',
 MATERIAL='IO',
 VALUE='SOCKET4677_AZIF0045-P001C01CS',
 PRIM_FILE='./archive_libs/logical/socket4677_azif0045p001c01cs/chips/chips.prt';

SECTION_NUMBER 26
 '@S9S_MB_2U_LIB.S9S_MB_2U(SCH_1):PAGE36_I1@PURE_QUANTA.SOCKET4677_AZIF0045P001C01CS(CHIPS)':
 C_PATH='@s9s_mb_2u_lib.s9s_mb_2u(sch_1):page36_i1@pure_quanta.socket4677_azif00~
45p001c01cs(chips)',
 P_PATH='@s9s_mb_2u_lib.s9s_mb_2u(sch_1):page36_i1@pure_quanta.socket4677_azif00~
45p001c01cs(chips)',
 PATH='I1',
 DRAWING='@S9S_MB_2U_LIB.S9S_MB_2U(SCH_1):PAGE36',
 PHYS_PAGE='36',
 XY='(-1000,1375)',
 ROT='0',
 VER='26',
 CDS_LIB='pure_quanta',
 CDS_PART_NAME='SOCKET4677_AZIF0045P001C01CS-SA',
 PART_TYPE='SMLF',
 MATERIAL='IO',
 VALUE='SOCKET4677_AZIF0045-P001C01CS',
 PRIM_FILE='./archive_libs/logical/socket4677_azif0045p001c01cs/chips/chips.prt';

SECTION_NUMBER 27
 '@S9S_MB_2U_LIB.S9S_MB_2U(SCH_1):PAGE36_I7@PURE_QUANTA.SOCKET4677_AZIF0045P001C01CS(CHIPS)':
 C_PATH='@s9s_mb_2u_lib.s9s_mb_2u(sch_1):page36_i7@pure_quanta.socket4677_azif00~
45p001c01cs(chips)',
 P_PATH='@s9s_mb_2u_lib.s9s_mb_2u(sch_1):page36_i7@pure_quanta.socket4677_azif00~
45p001c01cs(chips)',
 PATH='I7',
 DRAWING='@S9S_MB_2U_LIB.S9S_MB_2U(SCH_1):PAGE36',
 PHYS_PAGE='36',
 XY='(3375,1375)',
 ROT='0',
 VER='27',
 CDS_LIB='pure_quanta',
 CDS_PART_NAME='SOCKET4677_AZIF0045P001C01CS-SA',
 PART_TYPE='SMLF',
 MATERIAL='IO',
 VALUE='SOCKET4677_AZIF0045-P001C01CS',
 PRIM_FILE='./archive_libs/logical/socket4677_azif0045p001c01cs/chips/chips.prt';

SECTION_NUMBER 28
 '@S9S_MB_2U_LIB.S9S_MB_2U(SCH_1):PAGE37_I7@PURE_QUANTA.SOCKET4677_AZIF0045P001C01CS(CHIPS)':
 C_PATH='@s9s_mb_2u_lib.s9s_mb_2u(sch_1):page37_i7@pure_quanta.socket4677_azif00~
45p001c01cs(chips)',
 P_PATH='@s9s_mb_2u_lib.s9s_mb_2u(sch_1):page37_i7@pure_quanta.socket4677_azif00~
45p001c01cs(chips)',
 PATH='I7',
 DRAWING='@S9S_MB_2U_LIB.S9S_MB_2U(SCH_1):PAGE37',
 PHYS_PAGE='37',
 XY='(-1600,2850)',
 ROT='0',
 VER='28',
 CDS_LIB='pure_quanta',
 CDS_PART_NAME='SOCKET4677_AZIF0045P001C01CS-SA',
 PART_TYPE='SMLF',
 MATERIAL='IO',
 VALUE='SOCKET4677_AZIF0045-P001C01CS',
 PRIM_FILE='./archive_libs/logical/socket4677_azif0045p001c01cs/chips/chips.prt';

SECTION_NUMBER 29
 '@S9S_MB_2U_LIB.S9S_MB_2U(SCH_1):PAGE37_I8@PURE_QUANTA.SOCKET4677_AZIF0045P001C01CS(CHIPS)':
 C_PATH='@s9s_mb_2u_lib.s9s_mb_2u(sch_1):page37_i8@pure_quanta.socket4677_azif00~
45p001c01cs(chips)',
 P_PATH='@s9s_mb_2u_lib.s9s_mb_2u(sch_1):page37_i8@pure_quanta.socket4677_azif00~
45p001c01cs(chips)',
 PATH='I8',
 DRAWING='@S9S_MB_2U_LIB.S9S_MB_2U(SCH_1):PAGE37',
 PHYS_PAGE='37',
 XY='(2775,2450)',
 ROT='0',
 VER='29',
 CDS_LIB='pure_quanta',
 CDS_PART_NAME='SOCKET4677_AZIF0045P001C01CS-SA',
 PART_TYPE='SMLF',
 MATERIAL='IO',
 VALUE='SOCKET4677_AZIF0045-P001C01CS',
 PRIM_FILE='./archive_libs/logical/socket4677_azif0045p001c01cs/chips/chips.prt';

SECTION_NUMBER 30
 '@S9S_MB_2U_LIB.S9S_MB_2U(SCH_1):PAGE38_I4@PURE_QUANTA.SOCKET4677_AZIF0045P001C01CS(CHIPS)':
 C_PATH='@s9s_mb_2u_lib.s9s_mb_2u(sch_1):page38_i4@pure_quanta.socket4677_azif00~
45p001c01cs(chips)',
 P_PATH='@s9s_mb_2u_lib.s9s_mb_2u(sch_1):page38_i4@pure_quanta.socket4677_azif00~
45p001c01cs(chips)',
 PATH='I4',
 DRAWING='@S9S_MB_2U_LIB.S9S_MB_2U(SCH_1):PAGE38',
 PHYS_PAGE='38',
 XY='(-925,2050)',
 ROT='0',
 VER='30',
 CDS_LIB='pure_quanta',
 CDS_PART_NAME='SOCKET4677_AZIF0045P001C01CS-SA',
 PART_TYPE='SMLF',
 MATERIAL='IO',
 VALUE='SOCKET4677_AZIF0045-P001C01CS',
 PRIM_FILE='./archive_libs/logical/socket4677_azif0045p001c01cs/chips/chips.prt';

SECTION_NUMBER 31
 '@S9S_MB_2U_LIB.S9S_MB_2U(SCH_1):PAGE39_I1@PURE_QUANTA.SOCKET4677_AZIF0045P001C01CS(CHIPS)':
 C_PATH='@s9s_mb_2u_lib.s9s_mb_2u(sch_1):page39_i1@pure_quanta.socket4677_azif00~
45p001c01cs(chips)',
 P_PATH='@s9s_mb_2u_lib.s9s_mb_2u(sch_1):page39_i1@pure_quanta.socket4677_azif00~
45p001c01cs(chips)',
 PATH='I1',
 DRAWING='@S9S_MB_2U_LIB.S9S_MB_2U(SCH_1):PAGE39',
 PHYS_PAGE='39',
 XY='(-1500,1675)',
 ROT='0',
 VER='31',
 CDS_LIB='pure_quanta',
 CDS_PART_NAME='SOCKET4677_AZIF0045P001C01CS-SA',
 PART_TYPE='SMLF',
 MATERIAL='IO',
 VALUE='SOCKET4677_AZIF0045-P001C01CS',
 PRIM_FILE='./archive_libs/logical/socket4677_azif0045p001c01cs/chips/chips.prt';

SECTION_NUMBER 32
 '@S9S_MB_2U_LIB.S9S_MB_2U(SCH_1):PAGE39_I9@PURE_QUANTA.SOCKET4677_AZIF0045P001C01CS(CHIPS)':
 C_PATH='@s9s_mb_2u_lib.s9s_mb_2u(sch_1):page39_i9@pure_quanta.socket4677_azif00~
45p001c01cs(chips)',
 P_PATH='@s9s_mb_2u_lib.s9s_mb_2u(sch_1):page39_i9@pure_quanta.socket4677_azif00~
45p001c01cs(chips)',
 PATH='I9',
 DRAWING='@S9S_MB_2U_LIB.S9S_MB_2U(SCH_1):PAGE39',
 PHYS_PAGE='39',
 XY='(1550,1675)',
 ROT='0',
 VER='32',
 CDS_LIB='pure_quanta',
 CDS_PART_NAME='SOCKET4677_AZIF0045P001C01CS-SA',
 PART_TYPE='SMLF',
 MATERIAL='IO',
 VALUE='SOCKET4677_AZIF0045-P001C01CS',
 PRIM_FILE='./archive_libs/logical/socket4677_azif0045p001c01cs/chips/chips.prt';

SECTION_NUMBER 33
 '@S9S_MB_2U_LIB.S9S_MB_2U(SCH_1):PAGE39_I10@PURE_QUANTA.SOCKET4677_AZIF0045P001C01CS(CHIPS)':
 C_PATH='@s9s_mb_2u_lib.s9s_mb_2u(sch_1):page39_i10@pure_quanta.socket4677_azif0~
045p001c01cs(chips)',
 P_PATH='@s9s_mb_2u_lib.s9s_mb_2u(sch_1):page39_i10@pure_quanta.socket4677_azif0~
045p001c01cs(chips)',
 PATH='I10',
 DRAWING='@S9S_MB_2U_LIB.S9S_MB_2U(SCH_1):PAGE39',
 PHYS_PAGE='39',
 XY='(4575,1675)',
 ROT='0',
 VER='33',
 CDS_LIB='pure_quanta',
 CDS_PART_NAME='SOCKET4677_AZIF0045P001C01CS-SA',
 PART_TYPE='SMLF',
 MATERIAL='IO',
 VALUE='SOCKET4677_AZIF0045-P001C01CS',
 PRIM_FILE='./archive_libs/logical/socket4677_azif0045p001c01cs/chips/chips.prt';

SECTION_NUMBER 34
 '@S9S_MB_2U_LIB.S9S_MB_2U(SCH_1):PAGE40_I10@PURE_QUANTA.SOCKET4677_AZIF0045P001C01CS(CHIPS)':
 C_PATH='@s9s_mb_2u_lib.s9s_mb_2u(sch_1):page40_i10@pure_quanta.socket4677_azif0~
045p001c01cs(chips)',
 P_PATH='@s9s_mb_2u_lib.s9s_mb_2u(sch_1):page40_i10@pure_quanta.socket4677_azif0~
045p001c01cs(chips)',
 PATH='I10',
 DRAWING='@S9S_MB_2U_LIB.S9S_MB_2U(SCH_1):PAGE40',
 PHYS_PAGE='40',
 XY='(-2225,1800)',
 ROT='0',
 VER='34',
 CDS_LIB='pure_quanta',
 CDS_PART_NAME='SOCKET4677_AZIF0045P001C01CS-SA',
 PART_TYPE='SMLF',
 MATERIAL='IO',
 VALUE='SOCKET4677_AZIF0045-P001C01CS',
 PRIM_FILE='./archive_libs/logical/socket4677_azif0045p001c01cs/chips/chips.prt';

SECTION_NUMBER 35
 '@S9S_MB_2U_LIB.S9S_MB_2U(SCH_1):PAGE40_I11@PURE_QUANTA.SOCKET4677_AZIF0045P001C01CS(CHIPS)':
 C_PATH='@s9s_mb_2u_lib.s9s_mb_2u(sch_1):page40_i11@pure_quanta.socket4677_azif0~
045p001c01cs(chips)',
 P_PATH='@s9s_mb_2u_lib.s9s_mb_2u(sch_1):page40_i11@pure_quanta.socket4677_azif0~
045p001c01cs(chips)',
 PATH='I11',
 DRAWING='@S9S_MB_2U_LIB.S9S_MB_2U(SCH_1):PAGE40',
 PHYS_PAGE='40',
 XY='(825,1800)',
 ROT='0',
 VER='35',
 CDS_LIB='pure_quanta',
 CDS_PART_NAME='SOCKET4677_AZIF0045P001C01CS-SA',
 PART_TYPE='SMLF',
 MATERIAL='IO',
 VALUE='SOCKET4677_AZIF0045-P001C01CS',
 PRIM_FILE='./archive_libs/logical/socket4677_azif0045p001c01cs/chips/chips.prt';

SECTION_NUMBER 36
 '@S9S_MB_2U_LIB.S9S_MB_2U(SCH_1):PAGE40_I12@PURE_QUANTA.SOCKET4677_AZIF0045P001C01CS(CHIPS)':
 C_PATH='@s9s_mb_2u_lib.s9s_mb_2u(sch_1):page40_i12@pure_quanta.socket4677_azif0~
045p001c01cs(chips)',
 P_PATH='@s9s_mb_2u_lib.s9s_mb_2u(sch_1):page40_i12@pure_quanta.socket4677_azif0~
045p001c01cs(chips)',
 PATH='I12',
 DRAWING='@S9S_MB_2U_LIB.S9S_MB_2U(SCH_1):PAGE40',
 PHYS_PAGE='40',
 XY='(3850,1800)',
 ROT='0',
 VER='36',
 CDS_LIB='pure_quanta',
 CDS_PART_NAME='SOCKET4677_AZIF0045P001C01CS-SA',
 PART_TYPE='SMLF',
 MATERIAL='IO',
 VALUE='SOCKET4677_AZIF0045-P001C01CS',
 PRIM_FILE='./archive_libs/logical/socket4677_azif0045p001c01cs/chips/chips.prt';

SECTION_NUMBER 37
 '@S9S_MB_2U_LIB.S9S_MB_2U(SCH_1):PAGE41_I9@PURE_QUANTA.SOCKET4677_AZIF0045P001C01CS(CHIPS)':
 C_PATH='@s9s_mb_2u_lib.s9s_mb_2u(sch_1):page41_i9@pure_quanta.socket4677_azif00~
45p001c01cs(chips)',
 P_PATH='@s9s_mb_2u_lib.s9s_mb_2u(sch_1):page41_i9@pure_quanta.socket4677_azif00~
45p001c01cs(chips)',
 PATH='I9',
 DRAWING='@S9S_MB_2U_LIB.S9S_MB_2U(SCH_1):PAGE41',
 PHYS_PAGE='41',
 XY='(-1775,1950)',
 ROT='0',
 VER='37',
 CDS_LIB='pure_quanta',
 CDS_PART_NAME='SOCKET4677_AZIF0045P001C01CS-SA',
 PART_TYPE='SMLF',
 MATERIAL='IO',
 VALUE='SOCKET4677_AZIF0045-P001C01CS',
 PRIM_FILE='./archive_libs/logical/socket4677_azif0045p001c01cs/chips/chips.prt';

SECTION_NUMBER 38
 '@S9S_MB_2U_LIB.S9S_MB_2U(SCH_1):PAGE41_I10@PURE_QUANTA.SOCKET4677_AZIF0045P001C01CS(CHIPS)':
 C_PATH='@s9s_mb_2u_lib.s9s_mb_2u(sch_1):page41_i10@pure_quanta.socket4677_azif0~
045p001c01cs(chips)',
 P_PATH='@s9s_mb_2u_lib.s9s_mb_2u(sch_1):page41_i10@pure_quanta.socket4677_azif0~
045p001c01cs(chips)',
 PATH='I10',
 DRAWING='@S9S_MB_2U_LIB.S9S_MB_2U(SCH_1):PAGE41',
 PHYS_PAGE='41',
 XY='(1275,1950)',
 ROT='0',
 VER='38',
 CDS_LIB='pure_quanta',
 CDS_PART_NAME='SOCKET4677_AZIF0045P001C01CS-SA',
 PART_TYPE='SMLF',
 MATERIAL='IO',
 VALUE='SOCKET4677_AZIF0045-P001C01CS',
 PRIM_FILE='./archive_libs/logical/socket4677_azif0045p001c01cs/chips/chips.prt';

SECTION_NUMBER 39
 '@S9S_MB_2U_LIB.S9S_MB_2U(SCH_1):PAGE41_I11@PURE_QUANTA.SOCKET4677_AZIF0045P001C01CS(CHIPS)':
 C_PATH='@s9s_mb_2u_lib.s9s_mb_2u(sch_1):page41_i11@pure_quanta.socket4677_azif0~
045p001c01cs(chips)',
 P_PATH='@s9s_mb_2u_lib.s9s_mb_2u(sch_1):page41_i11@pure_quanta.socket4677_azif0~
045p001c01cs(chips)',
 PATH='I11',
 DRAWING='@S9S_MB_2U_LIB.S9S_MB_2U(SCH_1):PAGE41',
 PHYS_PAGE='41',
 XY='(4300,1950)',
 ROT='0',
 VER='39',
 CDS_LIB='pure_quanta',
 CDS_PART_NAME='SOCKET4677_AZIF0045P001C01CS-SA',
 PART_TYPE='SMLF',
 MATERIAL='IO',
 VALUE='SOCKET4677_AZIF0045-P001C01CS',
 PRIM_FILE='./archive_libs/logical/socket4677_azif0045p001c01cs/chips/chips.prt';

SECTION_NUMBER 40
 '@S9S_MB_2U_LIB.S9S_MB_2U(SCH_1):PAGE42_I10@PURE_QUANTA.SOCKET4677_AZIF0045P001C01CS(CHIPS)':
 C_PATH='@s9s_mb_2u_lib.s9s_mb_2u(sch_1):page42_i10@pure_quanta.socket4677_azif0~
045p001c01cs(chips)',
 P_PATH='@s9s_mb_2u_lib.s9s_mb_2u(sch_1):page42_i10@pure_quanta.socket4677_azif0~
045p001c01cs(chips)',
 PATH='I10',
 DRAWING='@S9S_MB_2U_LIB.S9S_MB_2U(SCH_1):PAGE42',
 PHYS_PAGE='42',
 XY='(-1825,1675)',
 ROT='0',
 VER='40',
 CDS_LIB='pure_quanta',
 CDS_PART_NAME='SOCKET4677_AZIF0045P001C01CS-SA',
 PART_TYPE='SMLF',
 MATERIAL='IO',
 VALUE='SOCKET4677_AZIF0045-P001C01CS',
 PRIM_FILE='./archive_libs/logical/socket4677_azif0045p001c01cs/chips/chips.prt';

SECTION_NUMBER 41
 '@S9S_MB_2U_LIB.S9S_MB_2U(SCH_1):PAGE42_I11@PURE_QUANTA.SOCKET4677_AZIF0045P001C01CS(CHIPS)':
 C_PATH='@s9s_mb_2u_lib.s9s_mb_2u(sch_1):page42_i11@pure_quanta.socket4677_azif0~
045p001c01cs(chips)',
 P_PATH='@s9s_mb_2u_lib.s9s_mb_2u(sch_1):page42_i11@pure_quanta.socket4677_azif0~
045p001c01cs(chips)',
 PATH='I11',
 DRAWING='@S9S_MB_2U_LIB.S9S_MB_2U(SCH_1):PAGE42',
 PHYS_PAGE='42',
 XY='(1225,1675)',
 ROT='0',
 VER='41',
 CDS_LIB='pure_quanta',
 CDS_PART_NAME='SOCKET4677_AZIF0045P001C01CS-SA',
 PART_TYPE='SMLF',
 MATERIAL='IO',
 VALUE='SOCKET4677_AZIF0045-P001C01CS',
 PRIM_FILE='./archive_libs/logical/socket4677_azif0045p001c01cs/chips/chips.prt';

SECTION_NUMBER 42
 '@S9S_MB_2U_LIB.S9S_MB_2U(SCH_1):PAGE42_I12@PURE_QUANTA.SOCKET4677_AZIF0045P001C01CS(CHIPS)':
 C_PATH='@s9s_mb_2u_lib.s9s_mb_2u(sch_1):page42_i12@pure_quanta.socket4677_azif0~
045p001c01cs(chips)',
 P_PATH='@s9s_mb_2u_lib.s9s_mb_2u(sch_1):page42_i12@pure_quanta.socket4677_azif0~
045p001c01cs(chips)',
 PATH='I12',
 DRAWING='@S9S_MB_2U_LIB.S9S_MB_2U(SCH_1):PAGE42',
 PHYS_PAGE='42',
 XY='(4250,1725)',
 ROT='0',
 VER='42',
 CDS_LIB='pure_quanta',
 CDS_PART_NAME='SOCKET4677_AZIF0045P001C01CS-SA',
 PART_TYPE='SMLF',
 MATERIAL='IO',
 VALUE='SOCKET4677_AZIF0045-P001C01CS',
 PRIM_FILE='./archive_libs/logical/socket4677_azif0045p001c01cs/chips/chips.prt';

PART_NAME
 U2_BL 'TP_TP_BOM ONLY-NA,TP12_BOM':;

SECTION_NUMBER 1
 '@S9S_MB_2U_LIB.S9S_MB_2U(SCH_1):PAGE290_I41@PURE_QUANTA.TP(CHIPS)':
 C_PATH='@s9s_mb_2u_lib.s9s_mb_2u(sch_1):page290_i41@pure_quanta.tp(chips)',
 P_PATH='@s9s_mb_2u_lib.s9s_mb_2u(sch_1):page312_i41@pure_quanta.tp(chips)',
 PATH='I41',
 DRAWING='@S9S_MB_2U_LIB.S9S_MB_2U(SCH_1):PAGE290',
 QPN='DGRA^000178',
 PHYS_PAGE='312',
 XY='(50,800)',
 ROT='0',
 VER='1',
 PACK_TYPE='TP_BOM ONLY',
 LOCATION='U2_BL',
 CDS_LIB='pure_quanta',
 CDS_PART_NAME='TP_TP_BOM ONLY-NA,TP12_BOM',
 MATERIAL='NA',
 PRIM_FILE='./archive_libs/logical/tp/chips/chips.prt';

PART_NAME
 U2_BP 'TP_TP_BOM ONLY-NA,TP12_BOM':;

SECTION_NUMBER 1
 '@S9S_MB_2U_LIB.S9S_MB_2U(SCH_1):PAGE290_I42@PURE_QUANTA.TP(CHIPS)':
 C_PATH='@s9s_mb_2u_lib.s9s_mb_2u(sch_1):page290_i42@pure_quanta.tp(chips)',
 P_PATH='@s9s_mb_2u_lib.s9s_mb_2u(sch_1):page312_i42@pure_quanta.tp(chips)',
 PATH='I42',
 DRAWING='@S9S_MB_2U_LIB.S9S_MB_2U(SCH_1):PAGE290',
 QPN='DGRA^000128',
 PHYS_PAGE='312',
 XY='(50,250)',
 ROT='0',
 VER='1',
 PACK_TYPE='TP_BOM ONLY',
 LOCATION='U2_BP',
 CDS_LIB='pure_quanta',
 CDS_PART_NAME='TP_TP_BOM ONLY-NA,TP12_BOM',
 MATERIAL='NA',
 PRIM_FILE='./archive_libs/logical/tp/chips/chips.prt';

PART_NAME
 U2_DC 'TP_TP_BOM ONLY-NA,TP12_BOM':;

SECTION_NUMBER 1
 '@S9S_MB_2U_LIB.S9S_MB_2U(SCH_1):PAGE290_I45@PURE_QUANTA.TP(CHIPS)':
 C_PATH='@s9s_mb_2u_lib.s9s_mb_2u(sch_1):page290_i45@pure_quanta.tp(chips)',
 P_PATH='@s9s_mb_2u_lib.s9s_mb_2u(sch_1):page312_i45@pure_quanta.tp(chips)',
 PATH='I45',
 DRAWING='@S9S_MB_2U_LIB.S9S_MB_2U(SCH_1):PAGE290',
 QPN='DGRA^000180',
 PHYS_PAGE='312',
 XY='(1375,250)',
 ROT='0',
 VER='1',
 PACK_TYPE='TP_BOM ONLY',
 LOCATION='U2_DC',
 CDS_LIB='pure_quanta',
 CDS_PART_NAME='TP_TP_BOM ONLY-NA,TP12_BOM',
 MATERIAL='NA',
 PRIM_FILE='./archive_libs/logical/tp/chips/chips.prt';

PART_NAME
 U4 'EMMITSBURG_REV0P9-GFNOCPU04302A':;

SECTION_NUMBER 1
 '@S9S_MB_2U_LIB.S9S_MB_2U(SCH_1):PAGE171_I78@PURE_QUANTA.EMMITSBURG_REV0P9(CHIPS)':
 C_PATH='@s9s_mb_2u_lib.s9s_mb_2u(sch_1):page171_i78@pure_quanta.emmitsburg_rev0~
p9(chips)',
 P_PATH='@s9s_mb_2u_lib.s9s_mb_2u(sch_1):page179_i78@pure_quanta.emmitsburg_rev0~
p9(chips)',
 PATH='I78',
 DRAWING='@S9S_MB_2U_LIB.S9S_MB_2U(SCH_1):PAGE171',
 PHYS_PAGE='179',
 XY='(1525,3175)',
 ROT='0',
 VER='1',
 CDS_LIB='pure_quanta',
 CDS_PART_NAME='EMMITSBURG_REV0P9-GFNOCPU04302A',
 PART_TYPE='SMLF',
 MATERIAL='IC',
 VALUE='GFNOCPU04302300-QV2N-MM#99A1WT',
 PRIM_FILE='./archive_libs/logical/emmitsburg_rev0p9/chips/chips.prt';

SECTION_NUMBER 2
 '@S9S_MB_2U_LIB.S9S_MB_2U(SCH_1):PAGE172_I11@PURE_QUANTA.EMMITSBURG_REV0P9(CHIPS)':
 C_PATH='@s9s_mb_2u_lib.s9s_mb_2u(sch_1):page172_i11@pure_quanta.emmitsburg_rev0~
p9(chips)',
 P_PATH='@s9s_mb_2u_lib.s9s_mb_2u(sch_1):page180_i11@pure_quanta.emmitsburg_rev0~
p9(chips)',
 PATH='I11',
 DRAWING='@S9S_MB_2U_LIB.S9S_MB_2U(SCH_1):PAGE172',
 PHYS_PAGE='180',
 XY='(-4125,3500)',
 ROT='0',
 VER='2',
 CDS_LIB='pure_quanta',
 CDS_PART_NAME='EMMITSBURG_REV0P9-GFNOCPU04302A',
 PART_TYPE='SMLF',
 MATERIAL='IC',
 VALUE='GFNOCPU04302300-QV2N-MM#99A1WT',
 PRIM_FILE='./archive_libs/logical/emmitsburg_rev0p9/chips/chips.prt';

SECTION_NUMBER 3
 '@S9S_MB_2U_LIB.S9S_MB_2U(SCH_1):PAGE173_I110@PURE_QUANTA.EMMITSBURG_REV0P9(CHIPS)':
 C_PATH='@s9s_mb_2u_lib.s9s_mb_2u(sch_1):page173_i110@pure_quanta.emmitsburg_rev~
0p9(chips)',
 P_PATH='@s9s_mb_2u_lib.s9s_mb_2u(sch_1):page181_i110@pure_quanta.emmitsburg_rev~
0p9(chips)',
 PATH='I110',
 DRAWING='@S9S_MB_2U_LIB.S9S_MB_2U(SCH_1):PAGE173',
 PHYS_PAGE='181',
 XY='(425,2000)',
 ROT='0',
 VER='3',
 CDS_LIB='pure_quanta',
 CDS_PART_NAME='EMMITSBURG_REV0P9-GFNOCPU04302A',
 PART_TYPE='SMLF',
 MATERIAL='IC',
 VALUE='GFNOCPU04302300-QV2N-MM#99A1WT',
 PRIM_FILE='./archive_libs/logical/emmitsburg_rev0p9/chips/chips.prt';

SECTION_NUMBER 4
 '@S9S_MB_2U_LIB.S9S_MB_2U(SCH_1):PAGE174_I36@PURE_QUANTA.EMMITSBURG_REV0P9(CHIPS)':
 C_PATH='@s9s_mb_2u_lib.s9s_mb_2u(sch_1):page174_i36@pure_quanta.emmitsburg_rev0~
p9(chips)',
 P_PATH='@s9s_mb_2u_lib.s9s_mb_2u(sch_1):page182_i36@pure_quanta.emmitsburg_rev0~
p9(chips)',
 PATH='I36',
 DRAWING='@S9S_MB_2U_LIB.S9S_MB_2U(SCH_1):PAGE174',
 PHYS_PAGE='182',
 XY='(2000,2475)',
 ROT='0',
 VER='4',
 CDS_LIB='pure_quanta',
 CDS_PART_NAME='EMMITSBURG_REV0P9-GFNOCPU04302A',
 PART_TYPE='SMLF',
 MATERIAL='IC',
 VALUE='GFNOCPU04302300-QV2N-MM#99A1WT',
 PRIM_FILE='./archive_libs/logical/emmitsburg_rev0p9/chips/chips.prt';

SECTION_NUMBER 5
 '@S9S_MB_2U_LIB.S9S_MB_2U(SCH_1):PAGE175_I93@PURE_QUANTA.EMMITSBURG_REV0P9(CHIPS)':
 C_PATH='@s9s_mb_2u_lib.s9s_mb_2u(sch_1):page175_i93@pure_quanta.emmitsburg_rev0~
p9(chips)',
 P_PATH='@s9s_mb_2u_lib.s9s_mb_2u(sch_1):page183_i93@pure_quanta.emmitsburg_rev0~
p9(chips)',
 PATH='I93',
 DRAWING='@S9S_MB_2U_LIB.S9S_MB_2U(SCH_1):PAGE175',
 PHYS_PAGE='183',
 XY='(1325,3200)',
 ROT='0',
 VER='5',
 CDS_LIB='pure_quanta',
 CDS_PART_NAME='EMMITSBURG_REV0P9-GFNOCPU04302A',
 PART_TYPE='SMLF',
 MATERIAL='IC',
 VALUE='GFNOCPU04302300-QV2N-MM#99A1WT',
 PRIM_FILE='./archive_libs/logical/emmitsburg_rev0p9/chips/chips.prt';

SECTION_NUMBER 6
 '@S9S_MB_2U_LIB.S9S_MB_2U(SCH_1):PAGE176_I22@PURE_QUANTA.EMMITSBURG_REV0P9(CHIPS)':
 C_PATH='@s9s_mb_2u_lib.s9s_mb_2u(sch_1):page176_i22@pure_quanta.emmitsburg_rev0~
p9(chips)',
 P_PATH='@s9s_mb_2u_lib.s9s_mb_2u(sch_1):page184_i22@pure_quanta.emmitsburg_rev0~
p9(chips)',
 PATH='I22',
 DRAWING='@S9S_MB_2U_LIB.S9S_MB_2U(SCH_1):PAGE176',
 PHYS_PAGE='184',
 XY='(1600,2400)',
 ROT='0',
 VER='6',
 CDS_LIB='pure_quanta',
 CDS_PART_NAME='EMMITSBURG_REV0P9-GFNOCPU04302A',
 PART_TYPE='SMLF',
 MATERIAL='IC',
 VALUE='GFNOCPU04302300-QV2N-MM#99A1WT',
 PRIM_FILE='./archive_libs/logical/emmitsburg_rev0p9/chips/chips.prt';

SECTION_NUMBER 7
 '@S9S_MB_2U_LIB.S9S_MB_2U(SCH_1):PAGE177_I27@PURE_QUANTA.EMMITSBURG_REV0P9(CHIPS)':
 C_PATH='@s9s_mb_2u_lib.s9s_mb_2u(sch_1):page177_i27@pure_quanta.emmitsburg_rev0~
p9(chips)',
 P_PATH='@s9s_mb_2u_lib.s9s_mb_2u(sch_1):page185_i27@pure_quanta.emmitsburg_rev0~
p9(chips)',
 PATH='I27',
 DRAWING='@S9S_MB_2U_LIB.S9S_MB_2U(SCH_1):PAGE177',
 PHYS_PAGE='185',
 XY='(1125,2675)',
 ROT='0',
 VER='7',
 CDS_LIB='pure_quanta',
 CDS_PART_NAME='EMMITSBURG_REV0P9-GFNOCPU04302A',
 PART_TYPE='SMLF',
 MATERIAL='IC',
 VALUE='GFNOCPU04302300-QV2N-MM#99A1WT',
 PRIM_FILE='./archive_libs/logical/emmitsburg_rev0p9/chips/chips.prt';

SECTION_NUMBER 8
 '@S9S_MB_2U_LIB.S9S_MB_2U(SCH_1):PAGE178_I11@PURE_QUANTA.EMMITSBURG_REV0P9(CHIPS)':
 C_PATH='@s9s_mb_2u_lib.s9s_mb_2u(sch_1):page178_i11@pure_quanta.emmitsburg_rev0~
p9(chips)',
 P_PATH='@s9s_mb_2u_lib.s9s_mb_2u(sch_1):page186_i11@pure_quanta.emmitsburg_rev0~
p9(chips)',
 PATH='I11',
 DRAWING='@S9S_MB_2U_LIB.S9S_MB_2U(SCH_1):PAGE178',
 PHYS_PAGE='186',
 XY='(1875,2250)',
 ROT='0',
 VER='8',
 CDS_LIB='pure_quanta',
 CDS_PART_NAME='EMMITSBURG_REV0P9-GFNOCPU04302A',
 PART_TYPE='SMLF',
 MATERIAL='IC',
 VALUE='GFNOCPU04302300-QV2N-MM#99A1WT',
 PRIM_FILE='./archive_libs/logical/emmitsburg_rev0p9/chips/chips.prt';

SECTION_NUMBER 9
 '@S9S_MB_2U_LIB.S9S_MB_2U(SCH_1):PAGE179_I4@PURE_QUANTA.EMMITSBURG_REV0P9(CHIPS)':
 C_PATH='@s9s_mb_2u_lib.s9s_mb_2u(sch_1):page179_i4@pure_quanta.emmitsburg_rev0p~
9(chips)',
 P_PATH='@s9s_mb_2u_lib.s9s_mb_2u(sch_1):page187_i4@pure_quanta.emmitsburg_rev0p~
9(chips)',
 PATH='I4',
 DRAWING='@S9S_MB_2U_LIB.S9S_MB_2U(SCH_1):PAGE179',
 PHYS_PAGE='187',
 XY='(1350,3175)',
 ROT='0',
 VER='9',
 CDS_LIB='pure_quanta',
 CDS_PART_NAME='EMMITSBURG_REV0P9-GFNOCPU04302A',
 PART_TYPE='SMLF',
 MATERIAL='IC',
 VALUE='GFNOCPU04302300-QV2N-MM#99A1WT',
 PRIM_FILE='./archive_libs/logical/emmitsburg_rev0p9/chips/chips.prt';

SECTION_NUMBER 10
 '@S9S_MB_2U_LIB.S9S_MB_2U(SCH_1):PAGE180_I7@PURE_QUANTA.EMMITSBURG_REV0P9(CHIPS)':
 C_PATH='@s9s_mb_2u_lib.s9s_mb_2u(sch_1):page180_i7@pure_quanta.emmitsburg_rev0p~
9(chips)',
 P_PATH='@s9s_mb_2u_lib.s9s_mb_2u(sch_1):page188_i7@pure_quanta.emmitsburg_rev0p~
9(chips)',
 PATH='I7',
 DRAWING='@S9S_MB_2U_LIB.S9S_MB_2U(SCH_1):PAGE180',
 PHYS_PAGE='188',
 XY='(-300,1450)',
 ROT='0',
 VER='10',
 CDS_LIB='pure_quanta',
 CDS_PART_NAME='EMMITSBURG_REV0P9-GFNOCPU04302A',
 PART_TYPE='SMLF',
 MATERIAL='IC',
 VALUE='GFNOCPU04302300-QV2N-MM#99A1WT',
 PRIM_FILE='./archive_libs/logical/emmitsburg_rev0p9/chips/chips.prt';

SECTION_NUMBER 11
 '@S9S_MB_2U_LIB.S9S_MB_2U(SCH_1):PAGE180_I9@PURE_QUANTA.EMMITSBURG_REV0P9(CHIPS)':
 C_PATH='@s9s_mb_2u_lib.s9s_mb_2u(sch_1):page180_i9@pure_quanta.emmitsburg_rev0p~
9(chips)',
 P_PATH='@s9s_mb_2u_lib.s9s_mb_2u(sch_1):page188_i9@pure_quanta.emmitsburg_rev0p~
9(chips)',
 PATH='I9',
 DRAWING='@S9S_MB_2U_LIB.S9S_MB_2U(SCH_1):PAGE180',
 PHYS_PAGE='188',
 XY='(3300,1500)',
 ROT='0',
 VER='11',
 CDS_LIB='pure_quanta',
 CDS_PART_NAME='EMMITSBURG_REV0P9-GFNOCPU04302A',
 PART_TYPE='SMLF',
 MATERIAL='IC',
 VALUE='GFNOCPU04302300-QV2N-MM#99A1WT',
 PRIM_FILE='./archive_libs/logical/emmitsburg_rev0p9/chips/chips.prt';

PART_NAME
 U13 '9SQ440NQQI8-9SQ440NQQI8,SMLF,IA':;

SECTION_NUMBER 1
 '@S9S_MB_2U_LIB.S9S_MB_2U(SCH_1):PAGE197_I180@PURE_QUANTA.9SQ440NQQI8(CHIPS)':
 C_PATH='@s9s_mb_2u_lib.s9s_mb_2u(sch_1):page197_i180@pure_quanta.\9sq440nqqi8\(~
chips)',
 P_PATH='@s9s_mb_2u_lib.s9s_mb_2u(sch_1):page208_i180@pure_quanta.\9sq440nqqi8\(~
chips)',
 PATH='I180',
 DRAWING='@S9S_MB_2U_LIB.S9S_MB_2U(SCH_1):PAGE197',
 PHYS_PAGE='208',
 XY='(-300,7325)',
 ROT='0',
 VER='1',
 CDS_LIB='pure_quanta',
 CDS_PART_NAME='9SQ440NQQI8-9SQ440NQQI8,SMLF,IA',
 PART_TYPE='SMLF',
 MATERIAL='IC',
 VALUE='9SQ440NQQI8',
 PRIM_FILE='./archive_libs/logical/9sq440nqqi8/chips/chips.prt';

SECTION_NUMBER 2
 '@S9S_MB_2U_LIB.S9S_MB_2U(SCH_1):PAGE197_I288@PURE_QUANTA.9SQ440NQQI8(CHIPS)':
 C_PATH='@s9s_mb_2u_lib.s9s_mb_2u(sch_1):page197_i288@pure_quanta.\9sq440nqqi8\(~
chips)',
 P_PATH='@s9s_mb_2u_lib.s9s_mb_2u(sch_1):page208_i288@pure_quanta.\9sq440nqqi8\(~
chips)',
 PATH='I288',
 DRAWING='@S9S_MB_2U_LIB.S9S_MB_2U(SCH_1):PAGE197',
 PHYS_PAGE='208',
 XY='(-25,10275)',
 ROT='0',
 VER='2',
 CDS_LIB='pure_quanta',
 CDS_PART_NAME='9SQ440NQQI8-9SQ440NQQI8,SMLF,IA',
 PART_TYPE='SMLF',
 MATERIAL='IC',
 VALUE='9SQ440NQQI8',
 PRIM_FILE='./archive_libs/logical/9sq440nqqi8/chips/chips.prt';

PART_NAME
 U14 'QS3VH257QG8_SMLF-QS3VH257QG8,IA':;

SECTION_NUMBER 1
 '@S9S_MB_2U_LIB.S9S_MB_2U(SCH_1):PAGE218_I12@PURE_QUANTA.QS3VH257QG8(CHIPS)':
 C_PATH='@s9s_mb_2u_lib.s9s_mb_2u(sch_1):page218_i12@pure_quanta.qs3vh257qg8(chi~
ps)',
 P_PATH='@s9s_mb_2u_lib.s9s_mb_2u(sch_1):page230_i12@pure_quanta.qs3vh257qg8(chi~
ps)',
 PATH='I12',
 DRAWING='@S9S_MB_2U_LIB.S9S_MB_2U(SCH_1):PAGE218',
 PHYS_PAGE='230',
 XY='(650,1750)',
 ROT='2',
 VER='1',
 PACK_TYPE='SMLF',
 LOCATION='U14',
 CDS_LIB='pure_quanta',
 CDS_PART_NAME='QS3VH257QG8_SMLF-QS3VH257QG8,IA',
 MATERIAL='IC',
 VALUE='QS3VH257QG8',
 PRIM_FILE='./archive_libs/logical/qs3vh257qg8/chips/chips.prt';

PART_NAME
 U15 'QS3VH257QG8_SMLF-QS3VH257QG8,IA':;

SECTION_NUMBER 1
 '@S9S_MB_2U_LIB.S9S_MB_2U(SCH_1):PAGE217_I19@PURE_QUANTA.QS3VH257QG8(CHIPS)':
 C_PATH='@s9s_mb_2u_lib.s9s_mb_2u(sch_1):page217_i19@pure_quanta.qs3vh257qg8(chi~
ps)',
 P_PATH='@s9s_mb_2u_lib.s9s_mb_2u(sch_1):page229_i19@pure_quanta.qs3vh257qg8(chi~
ps)',
 PATH='I19',
 DRAWING='@S9S_MB_2U_LIB.S9S_MB_2U(SCH_1):PAGE217',
 PHYS_PAGE='229',
 XY='(-1350,1650)',
 ROT='2',
 VER='1',
 PACK_TYPE='SMLF',
 LOCATION='U15',
 CDS_LIB='pure_quanta',
 CDS_PART_NAME='QS3VH257QG8_SMLF-QS3VH257QG8,IA',
 MATERIAL='IC',
 VALUE='QS3VH257QG8',
 PRIM_FILE='./archive_libs/logical/qs3vh257qg8/chips/chips.prt';

PART_NAME
 U16 '74LVC1G66GV-74LVC1G66GV,SMLF,IA':;

SECTION_NUMBER 1
 '@S9S_MB_2U_LIB.S9S_MB_2U(SCH_1):PAGE135_I115@PURE_QUANTA.74LVC1G66GV(CHIPS)':
 C_PATH='@s9s_mb_2u_lib.s9s_mb_2u(sch_1):page135_i115@pure_quanta.\74lvc1g66gv\(~
chips)',
 P_PATH='@s9s_mb_2u_lib.s9s_mb_2u(sch_1):page133_i115@pure_quanta.\74lvc1g66gv\(~
chips)',
 PATH='I115',
 DRAWING='@S9S_MB_2U_LIB.S9S_MB_2U(SCH_1):PAGE135',
 PIN_NAMES_ROTATE='True',
 PHYS_PAGE='133',
 XY='(3375,250)',
 ROT='2',
 VER='1',
 LOCATION='U16',
 SEC='1',
 CDS_LIB='pure_quanta',
 CDS_PART_NAME='74LVC1G66GV-74LVC1G66GV,SMLF,IA',
 SEC_TYPE='',
 PART_TYPE='SMLF',
 MATERIAL='IC',
 VALUE='74LVC1G66GV',
 PRIM_FILE='./archive_libs/logical/74lvc1g66gv/chips/chips.prt';

PART_NAME
 U17 '74CBTLV3126PW-74CBTLV3126PW,SMA':;

SECTION_NUMBER 1
 '@S9S_MB_2U_LIB.S9S_MB_2U(SCH_1):PAGE134_I80@PURE_QUANTA.74CBTLV3126PW(CHIPS)':
 C_PATH='@s9s_mb_2u_lib.s9s_mb_2u(sch_1):page134_i80@pure_quanta.\74cbtlv3126pw\~
(chips)',
 P_PATH='@s9s_mb_2u_lib.s9s_mb_2u(sch_1):page132_i80@pure_quanta.\74cbtlv3126pw\~
(chips)',
 PATH='I80',
 DRAWING='@S9S_MB_2U_LIB.S9S_MB_2U(SCH_1):PAGE134',
 PHYS_PAGE='132',
 XY='(-350,3600)',
 ROT='0',
 VER='1',
 SEC='1',
 CDS_LIB='pure_quanta',
 CDS_PART_NAME='74CBTLV3126PW-74CBTLV3126PW,SMA',
 SEC_TYPE='',
 PART_TYPE='SMLF',
 MATERIAL='IC',
 VALUE='74CBTLV3126PW',
 PRIM_FILE='./archive_libs/logical/74cbtlv3126pw/chips/chips.prt';

PART_NAME
 U18 '74CBTLV3126PW-74CBTLV3126PW,SMA':;

SECTION_NUMBER 1
 '@S9S_MB_2U_LIB.S9S_MB_2U(SCH_1):PAGE134_I129@PURE_QUANTA.74CBTLV3126PW(CHIPS)':
 C_PATH='@s9s_mb_2u_lib.s9s_mb_2u(sch_1):page134_i129@pure_quanta.\74cbtlv3126pw~
\(chips)',
 P_PATH='@s9s_mb_2u_lib.s9s_mb_2u(sch_1):page132_i129@pure_quanta.\74cbtlv3126pw~
\(chips)',
 PATH='I129',
 DRAWING='@S9S_MB_2U_LIB.S9S_MB_2U(SCH_1):PAGE134',
 PHYS_PAGE='132',
 XY='(-350,1700)',
 ROT='0',
 VER='1',
 SEC='1',
 CDS_LIB='pure_quanta',
 CDS_PART_NAME='74CBTLV3126PW-74CBTLV3126PW,SMA',
 SEC_TYPE='',
 PART_TYPE='SMLF',
 MATERIAL='IC',
 VALUE='74CBTLV3126PW',
 PRIM_FILE='./archive_libs/logical/74cbtlv3126pw/chips/chips.prt';

PART_NAME
 U21 'NC7SB3157_SMLF-NC7SB3157P6X,NCA':;

SECTION_NUMBER 1
 '@S9S_MB_2U_LIB.S9S_MB_2U(SCH_1):PAGE135_I58@PURE_QUANTA.NC7SB3157(CHIPS)':
 C_PATH='@s9s_mb_2u_lib.s9s_mb_2u(sch_1):page135_i58@pure_quanta.nc7sb3157(chips~
)',
 P_PATH='@s9s_mb_2u_lib.s9s_mb_2u(sch_1):page133_i58@pure_quanta.nc7sb3157(chips~
)',
 PATH='I58',
 DRAWING='@S9S_MB_2U_LIB.S9S_MB_2U(SCH_1):PAGE135',
 PHYS_PAGE='133',
 XY='(-600,3550)',
 ROT='2',
 VER='1',
 PACK_TYPE='SMLF',
 CDS_LIB='pure_quanta',
 CDS_PART_NAME='NC7SB3157_SMLF-NC7SB3157P6X,NCA',
 MANUF_PN='NC7SB3157P6X',
 MATERIAL='IC',
 VALUE='NC7SB3157P6X',
 PRIM_FILE='./archive_libs/logical/nc7sb3157/chips/chips.prt';

PART_NAME
 U22 'NC7SB3157_SMLF-NC7SB3157P6X,NCA':;

SECTION_NUMBER 1
 '@S9S_MB_2U_LIB.S9S_MB_2U(SCH_1):PAGE135_I71@PURE_QUANTA.NC7SB3157(CHIPS)':
 C_PATH='@s9s_mb_2u_lib.s9s_mb_2u(sch_1):page135_i71@pure_quanta.nc7sb3157(chips~
)',
 P_PATH='@s9s_mb_2u_lib.s9s_mb_2u(sch_1):page133_i71@pure_quanta.nc7sb3157(chips~
)',
 PATH='I71',
 DRAWING='@S9S_MB_2U_LIB.S9S_MB_2U(SCH_1):PAGE135',
 PHYS_PAGE='133',
 XY='(-600,2000)',
 ROT='2',
 VER='1',
 PACK_TYPE='SMLF',
 CDS_LIB='pure_quanta',
 CDS_PART_NAME='NC7SB3157_SMLF-NC7SB3157P6X,NCA',
 MANUF_PN='NC7SB3157P6X',
 MATERIAL='IC',
 VALUE='NC7SB3157P6X',
 PRIM_FILE='./archive_libs/logical/nc7sb3157/chips/chips.prt';

PART_NAME
 U23 '74LVC1G02GW_SMLF-74LVC1G02GW,IA':;

SECTION_NUMBER 1
 '@S9S_MB_2U_LIB.S9S_MB_2U(SCH_1):PAGE135_I96@PURE_QUANTA.74LVC1G02GW(CHIPS)':
 C_PATH='@s9s_mb_2u_lib.s9s_mb_2u(sch_1):page135_i96@pure_quanta.\74lvc1g02gw\(c~
hips)',
 P_PATH='@s9s_mb_2u_lib.s9s_mb_2u(sch_1):page133_i96@pure_quanta.\74lvc1g02gw\(c~
hips)',
 PATH='I96',
 DRAWING='@S9S_MB_2U_LIB.S9S_MB_2U(SCH_1):PAGE135',
 PHYS_PAGE='133',
 XY='(900,200)',
 ROT='0',
 VER='1',
 PACK_TYPE='SMLF',
 CDS_LIB='pure_quanta',
 CDS_PART_NAME='74LVC1G02GW_SMLF-74LVC1G02GW,IA',
 MATERIAL='IC',
 VALUE='74LVC1G02GW',
 PRIM_FILE='./archive_libs/logical/74lvc1g02gw/chips/chips.prt';

PART_NAME
 U28 'PCA9617ADP-PCA9617ADP,SMLF,IC,A':;

SECTION_NUMBER 1
 '@S9S_MB_2U_LIB.S9S_MB_2U(SCH_1):PAGE223_I39@PURE_QUANTA.PCA9617ADP(CHIPS)':
 C_PATH='@s9s_mb_2u_lib.s9s_mb_2u(sch_1):page223_i39@pure_quanta.pca9617adp(chip~
s)',
 P_PATH='@s9s_mb_2u_lib.s9s_mb_2u(sch_1):page235_i39@pure_quanta.pca9617adp(chip~
s)',
 PATH='I39',
 DRAWING='@S9S_MB_2U_LIB.S9S_MB_2U(SCH_1):PAGE223',
 PHYS_PAGE='235',
 XY='(-3675,7075)',
 ROT='0',
 VER='1',
 SEC='1',
 CDS_LIB='pure_quanta',
 CDS_PART_NAME='PCA9617ADP-PCA9617ADP,SMLF,IC,A',
 SEC_TYPE='',
 PART_TYPE='SMLF',
 MATERIAL='IC',
 VALUE='PCA9617ADP',
 PRIM_FILE='./archive_libs/logical/pca9617adp/chips/chips.prt';

PART_NAME
 U29 'PCA9617ADP-PCA9617ADP,SMLF,IC,A':;

SECTION_NUMBER 1
 '@S9S_MB_2U_LIB.S9S_MB_2U(SCH_1):PAGE223_I43@PURE_QUANTA.PCA9617ADP(CHIPS)':
 C_PATH='@s9s_mb_2u_lib.s9s_mb_2u(sch_1):page223_i43@pure_quanta.pca9617adp(chip~
s)',
 P_PATH='@s9s_mb_2u_lib.s9s_mb_2u(sch_1):page235_i43@pure_quanta.pca9617adp(chip~
s)',
 PATH='I43',
 DRAWING='@S9S_MB_2U_LIB.S9S_MB_2U(SCH_1):PAGE223',
 PHYS_PAGE='235',
 XY='(-3675,5475)',
 ROT='0',
 VER='1',
 SEC='1',
 CDS_LIB='pure_quanta',
 CDS_PART_NAME='PCA9617ADP-PCA9617ADP,SMLF,IC,A',
 SEC_TYPE='',
 PART_TYPE='SMLF',
 MATERIAL='IC',
 VALUE='PCA9617ADP',
 PRIM_FILE='./archive_libs/logical/pca9617adp/chips/chips.prt';

PART_NAME
 U30 'PCA9517AD-PCA9517AD,SMLF,IC,ALA':;

SECTION_NUMBER 1
 '@S9S_MB_2U_LIB.S9S_MB_2U(SCH_1):PAGE224_I28@PURE_QUANTA.PCA9517AD(CHIPS)':
 C_PATH='@s9s_mb_2u_lib.s9s_mb_2u(sch_1):page224_i28@pure_quanta.pca9517ad(chips~
)',
 P_PATH='@s9s_mb_2u_lib.s9s_mb_2u(sch_1):page236_i28@pure_quanta.pca9517ad(chips~
)',
 PATH='I28',
 DRAWING='@S9S_MB_2U_LIB.S9S_MB_2U(SCH_1):PAGE224',
 PHYS_PAGE='236',
 XY='(-1125,5700)',
 ROT='0',
 VER='1',
 CDS_LIB='pure_quanta',
 CDS_PART_NAME='PCA9517AD-PCA9517AD,SMLF,IC,ALA',
 PART_TYPE='SMLF',
 MATERIAL='IC',
 VALUE='PCA9517AD',
 PRIM_FILE='./archive_libs/logical/pca9517ad/chips/chips.prt';

PART_NAME
 U31 'PCA9517AD-PCA9517AD,SMLF,IC,ALA':;

SECTION_NUMBER 1
 '@S9S_MB_2U_LIB.S9S_MB_2U(SCH_1):PAGE224_I37@PURE_QUANTA.PCA9517AD(CHIPS)':
 C_PATH='@s9s_mb_2u_lib.s9s_mb_2u(sch_1):page224_i37@pure_quanta.pca9517ad(chips~
)',
 P_PATH='@s9s_mb_2u_lib.s9s_mb_2u(sch_1):page236_i37@pure_quanta.pca9517ad(chips~
)',
 PATH='I37',
 DRAWING='@S9S_MB_2U_LIB.S9S_MB_2U(SCH_1):PAGE224',
 PHYS_PAGE='236',
 XY='(-1125,3900)',
 ROT='0',
 VER='1',
 CDS_LIB='pure_quanta',
 CDS_PART_NAME='PCA9517AD-PCA9517AD,SMLF,IC,ALA',
 PART_TYPE='SMLF',
 MATERIAL='IC',
 VALUE='PCA9517AD',
 PRIM_FILE='./archive_libs/logical/pca9517ad/chips/chips.prt';

PART_NAME
 U36 'TCA9548APWR-TCA9548APWR,SMLF,IA':;

SECTION_NUMBER 1
 '@S9S_MB_2U_LIB.S9S_MB_2U(SCH_1):PAGE219_I45@PURE_QUANTA.TCA9548APWR(CHIPS)':
 C_PATH='@s9s_mb_2u_lib.s9s_mb_2u(sch_1):page219_i45@pure_quanta.tca9548apwr(chi~
ps)',
 P_PATH='@s9s_mb_2u_lib.s9s_mb_2u(sch_1):page231_i45@pure_quanta.tca9548apwr(chi~
ps)',
 PATH='I45',
 DRAWING='@S9S_MB_2U_LIB.S9S_MB_2U(SCH_1):PAGE219',
 PHYS_PAGE='231',
 XY='(2075,2750)',
 ROT='0',
 VER='1',
 LOCATION='U36',
 SEC='1',
 CDS_LIB='pure_quanta',
 CDS_PART_NAME='TCA9548APWR-TCA9548APWR,SMLF,IA',
 SEC_TYPE='',
 PART_TYPE='SMLF',
 MATERIAL='IC',
 VALUE='TCA9548APWR',
 PRIM_FILE='./archive_libs/logical/tca9548apwr/chips/chips.prt';

PART_NAME
 U38 '9QXL2001BNHGI8-9QXL2001BNHGI8,A':;

SECTION_NUMBER 1
 '@S9S_MB_2U_LIB.S9S_MB_2U(SCH_1):PAGE195_I119@PURE_QUANTA.9QXL2001BNHGI8(CHIPS)':
 C_PATH='@s9s_mb_2u_lib.s9s_mb_2u(sch_1):page195_i119@pure_quanta.\9qxl2001bnhgi~
8\(chips)',
 P_PATH='@s9s_mb_2u_lib.s9s_mb_2u(sch_1):page206_i119@pure_quanta.\9qxl2001bnhgi~
8\(chips)',
 PATH='I119',
 DRAWING='@S9S_MB_2U_LIB.S9S_MB_2U(SCH_1):PAGE195',
 PHYS_PAGE='206',
 XY='(-3200,2275)',
 ROT='0',
 VER='1',
 CDS_LIB='pure_quanta',
 CDS_PART_NAME='9QXL2001BNHGI8-9QXL2001BNHGI8,A',
 PART_TYPE='SMLF',
 MATERIAL='IC',
 VALUE='9QXL2001BNHGI8',
 PRIM_FILE='./archive_libs/logical/9qxl2001bnhgi8/chips/chips.prt';

PART_NAME
 U39 'TCA9548APWR-TCA9548APWR,SMLF,IA':;

SECTION_NUMBER 1
 '@S9S_MB_2U_LIB.S9S_MB_2U(SCH_1):PAGE221_I103@PURE_QUANTA.TCA9548APWR(CHIPS)':
 C_PATH='@s9s_mb_2u_lib.s9s_mb_2u(sch_1):page221_i103@pure_quanta.tca9548apwr(ch~
ips)',
 P_PATH='@s9s_mb_2u_lib.s9s_mb_2u(sch_1):page233_i103@pure_quanta.tca9548apwr(ch~
ips)',
 PATH='I103',
 DRAWING='@S9S_MB_2U_LIB.S9S_MB_2U(SCH_1):PAGE221',
 PHYS_PAGE='233',
 XY='(250,2525)',
 ROT='0',
 VER='1',
 LOCATION='U39',
 SEC='1',
 CDS_LIB='pure_quanta',
 CDS_PART_NAME='TCA9548APWR-TCA9548APWR,SMLF,IA',
 SEC_TYPE='',
 PART_TYPE='SMLF',
 MATERIAL='IC',
 VALUE='TCA9548APWR',
 PRIM_FILE='./archive_libs/logical/tca9548apwr/chips/chips.prt';

PART_NAME
 U49 'MOSFET_N_SMLF-BSS138K,BSS138K,A':;

SECTION_NUMBER 1
 '@S9S_MB_2U_LIB.S9S_MB_2U(SCH_1):PAGE154_I177@PURE_QUANTA.MOSFET_N(CHIPS)':
 C_PATH='@s9s_mb_2u_lib.s9s_mb_2u(sch_1):page154_i177@pure_quanta.mosfet_n(chips~
)',
 P_PATH='@s9s_mb_2u_lib.s9s_mb_2u(sch_1):page158_i177@pure_quanta.mosfet_n(chips~
)',
 PATH='I177',
 DRAWING='@S9S_MB_2U_LIB.S9S_MB_2U(SCH_1):PAGE154',
 PHYS_PAGE='158',
 XY='(-4050,4900)',
 ROT='0',
 VER='1',
 PACK_TYPE='SMLF',
 CDS_LIB='pure_quanta',
 CDS_PART_NAME='MOSFET_N_SMLF-BSS138K,BSS138K,A',
 MANUF_PN='BSS138K',
 MATERIAL='IC',
 VALUE='BSS138K',
 PRIM_FILE='./archive_libs/logical/mosfet_n/chips/chips.prt';

PART_NAME
 U50 '74LVC1G08W57-74LVC1G08W5-7,SMLA':;

SECTION_NUMBER 1
 '@S9S_MB_2U_LIB.S9S_MB_2U(SCH_1):PAGE132_I9@PURE_QUANTA.74LVC1G08W57(CHIPS)':
 C_PATH='@s9s_mb_2u_lib.s9s_mb_2u(sch_1):page132_i9@pure_quanta.\74lvc1g08w57\(c~
hips)',
 P_PATH='@s9s_mb_2u_lib.s9s_mb_2u(sch_1):page164_i9@pure_quanta.\74lvc1g08w57\(c~
hips)',
 PATH='I9',
 DRAWING='@S9S_MB_2U_LIB.S9S_MB_2U(SCH_1):PAGE132',
 PHYS_PAGE='164',
 XY='(-3175,-1025)',
 ROT='0',
 VER='1',
 LOCATION='U50',
 CDS_LIB='pure_quanta',
 CDS_PART_NAME='74LVC1G08W57-74LVC1G08W5-7,SMLA',
 PART_TYPE='SMLF',
 MATERIAL='IC',
 VALUE='74LVC1G08W5-7',
 PRIM_FILE='./archive_libs/logical/74lvc1g08w57/chips/chips.prt';

PART_NAME
 U51 'PCA9555APW-PCA9555APW,SMLF,IC,A':;

SECTION_NUMBER 1
 '@S9S_MB_2U_LIB.S9S_MB_2U(SCH_1):PAGE132_I66@PURE_QUANTA.PCA9555APW(CHIPS)':
 C_PATH='@s9s_mb_2u_lib.s9s_mb_2u(sch_1):page132_i66@pure_quanta.pca9555apw(chip~
s)',
 P_PATH='@s9s_mb_2u_lib.s9s_mb_2u(sch_1):page164_i66@pure_quanta.pca9555apw(chip~
s)',
 PATH='I66',
 DRAWING='@S9S_MB_2U_LIB.S9S_MB_2U(SCH_1):PAGE132',
 PHYS_PAGE='164',
 XY='(-1775,3125)',
 ROT='0',
 VER='1',
 LOCATION='U51',
 CDS_LIB='pure_quanta',
 CDS_PART_NAME='PCA9555APW-PCA9555APW,SMLF,IC,A',
 PART_TYPE='SMLF',
 MATERIAL='IC',
 VALUE='PCA9555APW',
 PRIM_FILE='./archive_libs/logical/pca9555apw/chips/chips.prt';

PART_NAME
 U52 'APX80929SAG7-APX809-29SAG-7,SMA':;

SECTION_NUMBER 1
 '@S9S_MB_2U_LIB.S9S_MB_2U(SCH_1):PAGE154_I228@PURE_QUANTA.APX80929SAG7(CHIPS)':
 C_PATH='@s9s_mb_2u_lib.s9s_mb_2u(sch_1):page154_i228@pure_quanta.apx80929sag7(c~
hips)',
 P_PATH='@s9s_mb_2u_lib.s9s_mb_2u(sch_1):page158_i228@pure_quanta.apx80929sag7(c~
hips)',
 PATH='I228',
 DRAWING='@S9S_MB_2U_LIB.S9S_MB_2U(SCH_1):PAGE154',
 PHYS_PAGE='158',
 XY='(-3475,7325)',
 ROT='2',
 VER='1',
 LOCATION='U52',
 CDS_LIB='pure_quanta',
 CDS_PART_NAME='APX80929SAG7-APX809-29SAG-7,SMA',
 PART_TYPE='SMLF',
 MATERIAL='IC',
 VALUE='APX809-29SAG-7',
 PRIM_FILE='./archive_libs/logical/apx80929sag7/chips/chips.prt';

PART_NAME
 U53 '74LVC1G08W57-74LVC1G08W5-7,SMLA':;

SECTION_NUMBER 1
 '@S9S_MB_2U_LIB.S9S_MB_2U(SCH_1):PAGE132_I56@PURE_QUANTA.74LVC1G08W57(CHIPS)':
 C_PATH='@s9s_mb_2u_lib.s9s_mb_2u(sch_1):page132_i56@pure_quanta.\74lvc1g08w57\(~
chips)',
 P_PATH='@s9s_mb_2u_lib.s9s_mb_2u(sch_1):page164_i56@pure_quanta.\74lvc1g08w57\(~
chips)',
 PATH='I56',
 DRAWING='@S9S_MB_2U_LIB.S9S_MB_2U(SCH_1):PAGE132',
 PHYS_PAGE='164',
 XY='(2075,850)',
 ROT='0',
 VER='1',
 LOCATION='U53',
 CDS_LIB='pure_quanta',
 CDS_PART_NAME='74LVC1G08W57-74LVC1G08W5-7,SMLA',
 PART_TYPE='SMLF',
 MATERIAL='IC',
 VALUE='74LVC1G08W5-7',
 PRIM_FILE='./archive_libs/logical/74lvc1g08w57/chips/chips.prt';

PART_NAME
 U58 '74LVC2G07DW7-74LVC2G07DW-7,SMLA':;

SECTION_NUMBER 1
 '@S9S_MB_2U_LIB.S9S_MB_2U(SCH_1):PAGE131_I25@PURE_QUANTA.74LVC2G07DW7(CHIPS)':
 C_PATH='@s9s_mb_2u_lib.s9s_mb_2u(sch_1):page131_i25@pure_quanta.\74lvc2g07dw7\(~
chips)',
 P_PATH='@s9s_mb_2u_lib.s9s_mb_2u(sch_1):page162_i25@pure_quanta.\74lvc2g07dw7\(~
chips)',
 PATH='I25',
 DRAWING='@S9S_MB_2U_LIB.S9S_MB_2U(SCH_1):PAGE131',
 PHYS_PAGE='162',
 XY='(-1175,-1750)',
 ROT='0',
 VER='1',
 LOCATION='U58',
 CDS_LIB='pure_quanta',
 CDS_PART_NAME='74LVC2G07DW7-74LVC2G07DW-7,SMLA',
 PART_TYPE='SMLF',
 MATERIAL='IC',
 VALUE='74LVC2G07DW-7',
 PRIM_FILE='./archive_libs/logical/74lvc2g07dw7/chips/chips.prt';

PART_NAME
 U59 '74LVC2G07DW7-74LVC2G07DW-7,SMLA':;

SECTION_NUMBER 1
 '@S9S_MB_2U_LIB.S9S_MB_2U(SCH_1):PAGE131_I19@PURE_QUANTA.74LVC2G07DW7(CHIPS)':
 C_PATH='@s9s_mb_2u_lib.s9s_mb_2u(sch_1):page131_i19@pure_quanta.\74lvc2g07dw7\(~
chips)',
 P_PATH='@s9s_mb_2u_lib.s9s_mb_2u(sch_1):page162_i19@pure_quanta.\74lvc2g07dw7\(~
chips)',
 PATH='I19',
 DRAWING='@S9S_MB_2U_LIB.S9S_MB_2U(SCH_1):PAGE131',
 PHYS_PAGE='162',
 XY='(-1175,-2650)',
 ROT='0',
 VER='1',
 LOCATION='U59',
 CDS_LIB='pure_quanta',
 CDS_PART_NAME='74LVC2G07DW7-74LVC2G07DW-7,SMLA',
 PART_TYPE='SMLF',
 MATERIAL='IC',
 VALUE='74LVC2G07DW-7',
 PRIM_FILE='./archive_libs/logical/74lvc2g07dw7/chips/chips.prt';

PART_NAME
 U60 'NC7SB3157_SMLF-NC7SB3157P6X,NCA':;

SECTION_NUMBER 1
 '@S9S_MB_2U_LIB.S9S_MB_2U(SCH_1):PAGE190_I34@PURE_QUANTA.NC7SB3157(CHIPS)':
 C_PATH='@s9s_mb_2u_lib.s9s_mb_2u(sch_1):page190_i34@pure_quanta.nc7sb3157(chips~
)',
 P_PATH='@s9s_mb_2u_lib.s9s_mb_2u(sch_1):page202_i34@pure_quanta.nc7sb3157(chips~
)',
 PATH='I34',
 DRAWING='@S9S_MB_2U_LIB.S9S_MB_2U(SCH_1):PAGE190',
 PHYS_PAGE='202',
 XY='(1000,3900)',
 ROT='0',
 VER='1',
 PACK_TYPE='SMLF',
 SEC='1',
 CDS_LIB='pure_quanta',
 CDS_PART_NAME='NC7SB3157_SMLF-NC7SB3157P6X,NCA',
 MANUF_PN='NC7SB3157P6X',
 SEC_TYPE='SMLF',
 MATERIAL='IC',
 VALUE='NC7SB3157P6X',
 PRIM_FILE='./archive_libs/logical/nc7sb3157/chips/chips.prt';

PART_NAME
 U61 'NC7SB3157_SMLF-NC7SB3157P6X,NCA':;

SECTION_NUMBER 1
 '@S9S_MB_2U_LIB.S9S_MB_2U(SCH_1):PAGE190_I39@PURE_QUANTA.NC7SB3157(CHIPS)':
 C_PATH='@s9s_mb_2u_lib.s9s_mb_2u(sch_1):page190_i39@pure_quanta.nc7sb3157(chips~
)',
 P_PATH='@s9s_mb_2u_lib.s9s_mb_2u(sch_1):page202_i39@pure_quanta.nc7sb3157(chips~
)',
 PATH='I39',
 DRAWING='@S9S_MB_2U_LIB.S9S_MB_2U(SCH_1):PAGE190',
 PHYS_PAGE='202',
 XY='(1000,2725)',
 ROT='0',
 VER='1',
 PACK_TYPE='SMLF',
 SEC='1',
 CDS_LIB='pure_quanta',
 CDS_PART_NAME='NC7SB3157_SMLF-NC7SB3157P6X,NCA',
 MANUF_PN='NC7SB3157P6X',
 SEC_TYPE='SMLF',
 MATERIAL='IC',
 VALUE='NC7SB3157P6X',
 PRIM_FILE='./archive_libs/logical/nc7sb3157/chips/chips.prt';

PART_NAME
 U62 'BAS70057F-BAS70-05-7-F,SMLF,ICA':;

SECTION_NUMBER 1
 '@S9S_MB_2U_LIB.S9S_MB_2U(SCH_1):PAGE177_I64@PURE_QUANTA.BAS70057F(CHIPS)':
 C_PATH='@s9s_mb_2u_lib.s9s_mb_2u(sch_1):page177_i64@pure_quanta.bas70057f(chips~
)',
 P_PATH='@s9s_mb_2u_lib.s9s_mb_2u(sch_1):page185_i64@pure_quanta.bas70057f(chips~
)',
 PATH='I64',
 DRAWING='@S9S_MB_2U_LIB.S9S_MB_2U(SCH_1):PAGE177',
 PHYS_PAGE='185',
 XY='(4700,400)',
 ROT='7',
 VER='1',
 CDS_LIB='pure_quanta',
 CDS_PART_NAME='BAS70057F-BAS70-05-7-F,SMLF,ICA',
 PART_TYPE='SMLF',
 MATERIAL='IC',
 VALUE='BAS70-05-7-F',
 PRIM_FILE='./archive_libs/logical/bas70057f/chips/chips.prt';

PART_NAME
 U64 'M24128BWMN6TP-M24128-BWMN6TP,SA':;

SECTION_NUMBER 1
 '@S9S_MB_2U_LIB.S9S_MB_2U(SCH_1):PAGE231_I35@PURE_QUANTA.M24128BWMN6TP(CHIPS)':
 C_PATH='@s9s_mb_2u_lib.s9s_mb_2u(sch_1):page231_i35@pure_quanta.m24128bwmn6tp(c~
hips)',
 P_PATH='@s9s_mb_2u_lib.s9s_mb_2u(sch_1):page243_i35@pure_quanta.m24128bwmn6tp(c~
hips)',
 PATH='I35',
 DRAWING='@S9S_MB_2U_LIB.S9S_MB_2U(SCH_1):PAGE231',
 PHYS_PAGE='243',
 XY='(100,2250)',
 ROT='0',
 VER='1',
 CDS_LIB='pure_quanta',
 CDS_PART_NAME='M24128BWMN6TP-M24128-BWMN6TP,SA',
 PART_TYPE='SMLF',
 MATERIAL='IC',
 VALUE='M24128-BWMN6TP',
 PRIM_FILE='./archive_libs/logical/m24128bwmn6tp/chips/chips.prt';

PART_NAME
 U66 '74LVC1G126SE7-74LVC1G126SE-7,SA':;

SECTION_NUMBER 1
 '@S9S_MB_2U_LIB.S9S_MB_2U(SCH_1):PAGE151_I15@PURE_QUANTA.74LVC1G126SE7(CHIPS)':
 C_PATH='@s9s_mb_2u_lib.s9s_mb_2u(sch_1):page151_i15@pure_quanta.\74lvc1g126se7\~
(chips)',
 P_PATH='@s9s_mb_2u_lib.s9s_mb_2u(sch_1):page154_i15@pure_quanta.\74lvc1g126se7\~
(chips)',
 PATH='I15',
 DRAWING='@S9S_MB_2U_LIB.S9S_MB_2U(SCH_1):PAGE151',
 PHYS_PAGE='154',
 XY='(-3050,3725)',
 ROT='0',
 VER='1',
 LOCATION='U66',
 SEC='1',
 CDS_LIB='pure_quanta',
 CDS_PART_NAME='74LVC1G126SE7-74LVC1G126SE-7,SA',
 SEC_TYPE='',
 PART_TYPE='SMLF',
 MATERIAL='IC',
 VALUE='74LVC1G126SE-7',
 PRIM_FILE='./archive_libs/logical/74lvc1g126se7/chips/chips.prt';

PART_NAME
 U67 '74CBTLV3126PW-74CBTLV3126PW,SMA':;

SECTION_NUMBER 1
 '@S9S_MB_2U_LIB.S9S_MB_2U(SCH_1):PAGE151_I39@PURE_QUANTA.74CBTLV3126PW(CHIPS)':
 C_PATH='@s9s_mb_2u_lib.s9s_mb_2u(sch_1):page151_i39@pure_quanta.\74cbtlv3126pw\~
(chips)',
 P_PATH='@s9s_mb_2u_lib.s9s_mb_2u(sch_1):page154_i39@pure_quanta.\74cbtlv3126pw\~
(chips)',
 PATH='I39',
 DRAWING='@S9S_MB_2U_LIB.S9S_MB_2U(SCH_1):PAGE151',
 PHYS_PAGE='154',
 XY='(-1625,6425)',
 ROT='2',
 VER='1',
 CDS_LIB='pure_quanta',
 CDS_PART_NAME='74CBTLV3126PW-74CBTLV3126PW,SMA',
 PART_TYPE='SMLF',
 MATERIAL='IC',
 VALUE='74CBTLV3126PW',
 PRIM_FILE='./archive_libs/logical/74cbtlv3126pw/chips/chips.prt';

PART_NAME
 U68 '74CBTLV3126PW-74CBTLV3126PW,SMA':;

SECTION_NUMBER 1
 '@S9S_MB_2U_LIB.S9S_MB_2U(SCH_1):PAGE151_I30@PURE_QUANTA.74CBTLV3126PW(CHIPS)':
 C_PATH='@s9s_mb_2u_lib.s9s_mb_2u(sch_1):page151_i30@pure_quanta.\74cbtlv3126pw\~
(chips)',
 P_PATH='@s9s_mb_2u_lib.s9s_mb_2u(sch_1):page154_i30@pure_quanta.\74cbtlv3126pw\~
(chips)',
 PATH='I30',
 DRAWING='@S9S_MB_2U_LIB.S9S_MB_2U(SCH_1):PAGE151',
 PHYS_PAGE='154',
 XY='(-1625,5000)',
 ROT='2',
 VER='1',
 CDS_LIB='pure_quanta',
 CDS_PART_NAME='74CBTLV3126PW-74CBTLV3126PW,SMA',
 PART_TYPE='SMLF',
 MATERIAL='IC',
 VALUE='74CBTLV3126PW',
 PRIM_FILE='./archive_libs/logical/74cbtlv3126pw/chips/chips.prt';

PART_NAME
 U70 'MOSFET_N_SMLF-BSS138K,BSS138K,A':;

SECTION_NUMBER 1
 '@S9S_MB_2U_LIB.S9S_MB_2U(SCH_1):PAGE212_I19@PURE_QUANTA.MOSFET_N(CHIPS)':
 C_PATH='@s9s_mb_2u_lib.s9s_mb_2u(sch_1):page212_i19@pure_quanta.mosfet_n(chips)~
',
 P_PATH='@s9s_mb_2u_lib.s9s_mb_2u(sch_1):page223_i19@pure_quanta.mosfet_n(chips)~
',
 PATH='I19',
 DRAWING='@S9S_MB_2U_LIB.S9S_MB_2U(SCH_1):PAGE212',
 PHYS_PAGE='223',
 XY='(-2800,675)',
 ROT='0',
 VER='1',
 PACK_TYPE='SMLF',
 CDS_LIB='pure_quanta',
 CDS_PART_NAME='MOSFET_N_SMLF-BSS138K,BSS138K,A',
 MANUF_PN='BSS138K',
 MATERIAL='IC',
 VALUE='BSS138K',
 PRIM_FILE='./archive_libs/logical/mosfet_n/chips/chips.prt';

PART_NAME
 U75 '74LVC1G17GW-74LVC1G17GW,SMLF,IA':;

SECTION_NUMBER 1
 '@S9S_MB_2U_LIB.S9S_MB_2U(SCH_1):PAGE152_I1@PURE_QUANTA.74LVC1G17GW(CHIPS)':
 C_PATH='@s9s_mb_2u_lib.s9s_mb_2u(sch_1):page152_i1@pure_quanta.\74lvc1g17gw\(ch~
ips)',
 P_PATH='@s9s_mb_2u_lib.s9s_mb_2u(sch_1):page155_i1@pure_quanta.\74lvc1g17gw\(ch~
ips)',
 PATH='I1',
 DRAWING='@S9S_MB_2U_LIB.S9S_MB_2U(SCH_1):PAGE152',
 PIN_NAMES_ROTATE='True',
 PHYS_PAGE='155',
 XY='(-7700,7225)',
 ROT='0',
 VER='1',
 SEC='1',
 CDS_LIB='pure_quanta',
 CDS_PART_NAME='74LVC1G17GW-74LVC1G17GW,SMLF,IA',
 SEC_TYPE='',
 PART_TYPE='SMLF',
 MATERIAL='IC',
 VALUE='74LVC1G17GW',
 PRIM_FILE='./archive_libs/logical/74lvc1g17gw/chips/chips.prt';

PART_NAME
 U82 '74LVC1G126SE7-74LVC1G126SE-7,SA':;

SECTION_NUMBER 1
 '@S9S_MB_2U_LIB.S9S_MB_2U(SCH_1):PAGE152_I79@PURE_QUANTA.74LVC1G126SE7(CHIPS)':
 C_PATH='@s9s_mb_2u_lib.s9s_mb_2u(sch_1):page152_i79@pure_quanta.\74lvc1g126se7\~
(chips)',
 P_PATH='@s9s_mb_2u_lib.s9s_mb_2u(sch_1):page155_i79@pure_quanta.\74lvc1g126se7\~
(chips)',
 PATH='I79',
 DRAWING='@S9S_MB_2U_LIB.S9S_MB_2U(SCH_1):PAGE152',
 PHYS_PAGE='155',
 XY='(-8350,4100)',
 ROT='0',
 VER='1',
 LOCATION='U82',
 CDS_LIB='pure_quanta',
 CDS_PART_NAME='74LVC1G126SE7-74LVC1G126SE-7,SA',
 PART_TYPE='SMLF',
 MATERIAL='IC',
 VALUE='74LVC1G126SE-7',
 PRIM_FILE='./archive_libs/logical/74lvc1g126se7/chips/chips.prt';

PART_NAME
 U83 'GTL2014PW-GTL2014PW,SMLF,IC,ALA':;

SECTION_NUMBER 1
 '@S9S_MB_2U_LIB.S9S_MB_2U(SCH_1):PAGE226_I45@PURE_QUANTA.GTL2014PW(CHIPS)':
 C_PATH='@s9s_mb_2u_lib.s9s_mb_2u(sch_1):page226_i45@pure_quanta.gtl2014pw(chips~
)',
 P_PATH='@s9s_mb_2u_lib.s9s_mb_2u(sch_1):page239_i45@pure_quanta.gtl2014pw(chips~
)',
 PATH='I45',
 DRAWING='@S9S_MB_2U_LIB.S9S_MB_2U(SCH_1):PAGE226',
 PHYS_PAGE='239',
 XY='(-11350,1575)',
 ROT='2',
 VER='1',
 SEC='1',
 CDS_LIB='pure_quanta',
 CDS_PART_NAME='GTL2014PW-GTL2014PW,SMLF,IC,ALA',
 SEC_TYPE='',
 PART_TYPE='SMLF',
 MATERIAL='IC',
 VALUE='GTL2014PW',
 PRIM_FILE='./archive_libs/logical/gtl2014pw/chips/chips.prt';

PART_NAME
 U84 'GTL2014PW-GTL2014PW,SMLF,IC,ALA':;

SECTION_NUMBER 1
 '@S9S_MB_2U_LIB.S9S_MB_2U(SCH_1):PAGE226_I18@PURE_QUANTA.GTL2014PW(CHIPS)':
 C_PATH='@s9s_mb_2u_lib.s9s_mb_2u(sch_1):page226_i18@pure_quanta.gtl2014pw(chips~
)',
 P_PATH='@s9s_mb_2u_lib.s9s_mb_2u(sch_1):page239_i18@pure_quanta.gtl2014pw(chips~
)',
 PATH='I18',
 DRAWING='@S9S_MB_2U_LIB.S9S_MB_2U(SCH_1):PAGE226',
 PHYS_PAGE='239',
 XY='(-11325,3150)',
 ROT='2',
 VER='1',
 SEC='1',
 CDS_LIB='pure_quanta',
 CDS_PART_NAME='GTL2014PW-GTL2014PW,SMLF,IC,ALA',
 SEC_TYPE='',
 PART_TYPE='SMLF',
 MATERIAL='IC',
 VALUE='GTL2014PW',
 PRIM_FILE='./archive_libs/logical/gtl2014pw/chips/chips.prt';

PART_NAME
 U85 'NC7SB3157_SMLF-NC7SB3157P6X,NCA':;

SECTION_NUMBER 1
 '@S9S_MB_2U_LIB.S9S_MB_2U(SCH_1):PAGE137_I109@PURE_QUANTA.NC7SB3157(CHIPS)':
 C_PATH='@s9s_mb_2u_lib.s9s_mb_2u(sch_1):page137_i109@pure_quanta.nc7sb3157(chip~
s)',
 P_PATH='@s9s_mb_2u_lib.s9s_mb_2u(sch_1):page134_i109@pure_quanta.nc7sb3157(chip~
s)',
 PATH='I109',
 DRAWING='@S9S_MB_2U_LIB.S9S_MB_2U(SCH_1):PAGE137',
 PHYS_PAGE='134',
 XY='(-8600,-2475)',
 ROT='2',
 VER='1',
 PACK_TYPE='SMLF',
 CDS_LIB='pure_quanta',
 CDS_PART_NAME='NC7SB3157_SMLF-NC7SB3157P6X,NCA',
 MANUF_PN='NC7SB3157P6X',
 MATERIAL='IC',
 VALUE='NC7SB3157P6X',
 PRIM_FILE='./archive_libs/logical/nc7sb3157/chips/chips.prt';

PART_NAME
 U86 '74CBTLV3126PW-74CBTLV3126PW,SMA':;

SECTION_NUMBER 1
 '@S9S_MB_2U_LIB.S9S_MB_2U(SCH_1):PAGE137_I84@PURE_QUANTA.74CBTLV3126PW(CHIPS)':
 C_PATH='@s9s_mb_2u_lib.s9s_mb_2u(sch_1):page137_i84@pure_quanta.\74cbtlv3126pw\~
(chips)',
 P_PATH='@s9s_mb_2u_lib.s9s_mb_2u(sch_1):page134_i84@pure_quanta.\74cbtlv3126pw\~
(chips)',
 PATH='I84',
 DRAWING='@S9S_MB_2U_LIB.S9S_MB_2U(SCH_1):PAGE137',
 PHYS_PAGE='134',
 XY='(-6025,-2450)',
 ROT='0',
 VER='1',
 CDS_LIB='pure_quanta',
 CDS_PART_NAME='74CBTLV3126PW-74CBTLV3126PW,SMA',
 PART_TYPE='SMLF',
 MATERIAL='IC',
 VALUE='74CBTLV3126PW',
 PRIM_FILE='./archive_libs/logical/74cbtlv3126pw/chips/chips.prt';

PART_NAME
 U87 'MOSFET_N_SMLF-BSS138K,BSS138K,A':;

SECTION_NUMBER 1
 '@S9S_MB_2U_LIB.S9S_MB_2U(SCH_1):PAGE137_I96@PURE_QUANTA.MOSFET_N(CHIPS)':
 C_PATH='@s9s_mb_2u_lib.s9s_mb_2u(sch_1):page137_i96@pure_quanta.mosfet_n(chips)~
',
 P_PATH='@s9s_mb_2u_lib.s9s_mb_2u(sch_1):page134_i96@pure_quanta.mosfet_n(chips)~
',
 PATH='I96',
 DRAWING='@S9S_MB_2U_LIB.S9S_MB_2U(SCH_1):PAGE137',
 PHYS_PAGE='134',
 XY='(-7275,-1375)',
 ROT='0',
 VER='1',
 PACK_TYPE='SMLF',
 CDS_LIB='pure_quanta',
 CDS_PART_NAME='MOSFET_N_SMLF-BSS138K,BSS138K,A',
 MANUF_PN='BSS138K',
 MATERIAL='IC',
 VALUE='BSS138K',
 PRIM_FILE='./archive_libs/logical/mosfet_n/chips/chips.prt';

PART_NAME
 U89 'MOSFET_N_SMLF-BSS138K,BSS138K,A':;

SECTION_NUMBER 1
 '@S9S_MB_2U_LIB.S9S_MB_2U(SCH_1):PAGE207_I236@PURE_QUANTA.MOSFET_N(CHIPS)':
 C_PATH='@s9s_mb_2u_lib.s9s_mb_2u(sch_1):page207_i236@pure_quanta.mosfet_n(chips~
)',
 P_PATH='@s9s_mb_2u_lib.s9s_mb_2u(sch_1):page218_i236@pure_quanta.mosfet_n(chips~
)',
 PATH='I236',
 DRAWING='@S9S_MB_2U_LIB.S9S_MB_2U(SCH_1):PAGE207',
 PHYS_PAGE='218',
 XY='(-1525,4525)',
 ROT='0',
 VER='1',
 PACK_TYPE='SMLF',
 CDS_LIB='pure_quanta',
 CDS_PART_NAME='MOSFET_N_SMLF-BSS138K,BSS138K,A',
 MANUF_PN='BSS138K',
 MATERIAL='IC',
 VALUE='BSS138K',
 PRIM_FILE='./archive_libs/logical/mosfet_n/chips/chips.prt';

PART_NAME
 U90 'PI6CV304LE-PI6CV304LE,SMLF,IC,A':;

SECTION_NUMBER 1
 '@S9S_MB_2U_LIB.S9S_MB_2U(SCH_1):PAGE152_I46@PURE_QUANTA.PI6CV304LE(CHIPS)':
 C_PATH='@s9s_mb_2u_lib.s9s_mb_2u(sch_1):page152_i46@pure_quanta.pi6cv304le(chip~
s)',
 P_PATH='@s9s_mb_2u_lib.s9s_mb_2u(sch_1):page155_i46@pure_quanta.pi6cv304le(chip~
s)',
 PATH='I46',
 DRAWING='@S9S_MB_2U_LIB.S9S_MB_2U(SCH_1):PAGE152',
 PHYS_PAGE='155',
 XY='(-7150,2300)',
 ROT='0',
 VER='1',
 CDS_LIB='pure_quanta',
 CDS_PART_NAME='PI6CV304LE-PI6CV304LE,SMLF,IC,A',
 PART_TYPE='SMLF',
 MATERIAL='IC',
 VALUE='PI6CV304LE',
 PRIM_FILE='./archive_libs/logical/pi6cv304le/chips/chips.prt';

PART_NAME
 U94 'ADM1086AKSZREEL7-ADM1086AKSZ-RA':
 ROOM='DELAY1_BOM1';

SECTION_NUMBER 1
 '@S9S_MB_2U_LIB.S9S_MB_2U(SCH_1):PAGE232_I27@PURE_QUANTA.ADM1086AKSZREEL7(CHIPS)':
 C_PATH='@s9s_mb_2u_lib.s9s_mb_2u(sch_1):page232_i27@pure_quanta.adm1086akszreel~
7(chips)',
 P_PATH='@s9s_mb_2u_lib.s9s_mb_2u(sch_1):page244_i27@pure_quanta.adm1086akszreel~
7(chips)',
 PATH='I27',
 DRAWING='@S9S_MB_2U_LIB.S9S_MB_2U(SCH_1):PAGE232',
 PHYS_PAGE='244',
 XY='(75,1775)',
 ROT='0',
 VER='1',
 CDS_LIB='pure_quanta',
 CDS_PART_NAME='ADM1086AKSZREEL7-ADM1086AKSZ-RA',
 PART_TYPE='SMLF',
 MATERIAL='IC',
 ROOM='DELAY1_BOM1',
 VALUE='ADM1086AKSZ-REEL7',
 PRIM_FILE='./archive_libs/logical/adm1086akszreel7/chips/chips.prt';

PART_NAME
 U95 '74LVC1G07SE7-74LVC1G07SE-7,SMLA':;

SECTION_NUMBER 1
 '@S9S_MB_2U_LIB.S9S_MB_2U(SCH_1):PAGE232_I11@PURE_QUANTA.74LVC1G07SE7(CHIPS)':
 C_PATH='@s9s_mb_2u_lib.s9s_mb_2u(sch_1):page232_i11@pure_quanta.\74lvc1g07se7\(~
chips)',
 P_PATH='@s9s_mb_2u_lib.s9s_mb_2u(sch_1):page244_i11@pure_quanta.\74lvc1g07se7\(~
chips)',
 PATH='I11',
 DRAWING='@S9S_MB_2U_LIB.S9S_MB_2U(SCH_1):PAGE232',
 PHYS_PAGE='244',
 XY='(-800,-2300)',
 ROT='0',
 VER='1',
 SEC='1',
 CDS_LIB='pure_quanta',
 CDS_PART_NAME='74LVC1G07SE7-74LVC1G07SE-7,SMLA',
 SEC_TYPE='',
 PART_TYPE='SMLF',
 MATERIAL='IC',
 VALUE='74LVC1G07SE-7',
 PRIM_FILE='./archive_libs/logical/74lvc1g07se7/chips/chips.prt';

PART_NAME
 U96 'NX3L2267GM-NX3L2267GM,SMLF,IC,A':;

SECTION_NUMBER 1
 '@S9S_MB_2U_LIB.S9S_MB_2U(SCH_1):PAGE226_I68@PURE_QUANTA.NX3L2267GM(CHIPS)':
 C_PATH='@s9s_mb_2u_lib.s9s_mb_2u(sch_1):page226_i68@pure_quanta.nx3l2267gm(chip~
s)',
 P_PATH='@s9s_mb_2u_lib.s9s_mb_2u(sch_1):page239_i68@pure_quanta.nx3l2267gm(chip~
s)',
 PATH='I68',
 DRAWING='@S9S_MB_2U_LIB.S9S_MB_2U(SCH_1):PAGE226',
 PHYS_PAGE='239',
 XY='(-12475,-200)',
 ROT='0',
 VER='1',
 SEC='1',
 CDS_LIB='pure_quanta',
 CDS_PART_NAME='NX3L2267GM-NX3L2267GM,SMLF,IC,A',
 SEC_TYPE='',
 PART_TYPE='SMLF',
 MATERIAL='IC',
 VALUE='NX3L2267GM',
 PRIM_FILE='./archive_libs/logical/nx3l2267gm/chips/chips.prt';

PART_NAME
 U97 'NX3L2267GM-NX3L2267GM,SMLF,IC,A':;

SECTION_NUMBER 1
 '@S9S_MB_2U_LIB.S9S_MB_2U(SCH_1):PAGE226_I38@PURE_QUANTA.NX3L2267GM(CHIPS)':
 C_PATH='@s9s_mb_2u_lib.s9s_mb_2u(sch_1):page226_i38@pure_quanta.nx3l2267gm(chip~
s)',
 P_PATH='@s9s_mb_2u_lib.s9s_mb_2u(sch_1):page239_i38@pure_quanta.nx3l2267gm(chip~
s)',
 PATH='I38',
 DRAWING='@S9S_MB_2U_LIB.S9S_MB_2U(SCH_1):PAGE226',
 PHYS_PAGE='239',
 XY='(-8425,-200)',
 ROT='0',
 VER='1',
 SEC='1',
 CDS_LIB='pure_quanta',
 CDS_PART_NAME='NX3L2267GM-NX3L2267GM,SMLF,IC,A',
 SEC_TYPE='',
 PART_TYPE='SMLF',
 MATERIAL='IC',
 VALUE='NX3L2267GM',
 PRIM_FILE='./archive_libs/logical/nx3l2267gm/chips/chips.prt';

PART_NAME
 U98 'PCA9306DP1-PCA9306DP1,SMLF,IC,A':;

SECTION_NUMBER 1
 '@S9S_MB_2U_LIB.S9S_MB_2U(SCH_1):PAGE183_I27@PURE_QUANTA.PCA9306DP1(CHIPS)':
 C_PATH='@s9s_mb_2u_lib.s9s_mb_2u(sch_1):page183_i27@pure_quanta.pca9306dp1(chip~
s)',
 P_PATH='@s9s_mb_2u_lib.s9s_mb_2u(sch_1):page194_i27@pure_quanta.pca9306dp1(chip~
s)',
 PATH='I27',
 DRAWING='@S9S_MB_2U_LIB.S9S_MB_2U(SCH_1):PAGE183',
 PHYS_PAGE='194',
 XY='(725,3400)',
 ROT='2',
 VER='1',
 CDS_LIB='pure_quanta',
 CDS_PART_NAME='PCA9306DP1-PCA9306DP1,SMLF,IC,A',
 PART_TYPE='SMLF',
 MATERIAL='IC',
 VALUE='PCA9306DP1',
 PRIM_FILE='./archive_libs/logical/pca9306dp1/chips/chips.prt';

PART_NAME
 U99 'RT9818C44GV-RT9818C-44GV,SMLF,A':;

SECTION_NUMBER 1
 '@S9S_MB_2U_LIB.S9S_MB_2U(SCH_1):PAGE246_I4@PURE_QUANTA.RT9818C44GV(CHIPS)':
 C_PATH='@s9s_mb_2u_lib.s9s_mb_2u(sch_1):page246_i4@pure_quanta.rt9818c44gv(chip~
s)',
 P_PATH='@s9s_mb_2u_lib.s9s_mb_2u(sch_1):page260_i4@pure_quanta.rt9818c44gv(chip~
s)',
 PATH='I4',
 DRAWING='@S9S_MB_2U_LIB.S9S_MB_2U(SCH_1):PAGE246',
 BOM_COST='VR_SYSTEM ',
 PIN_NAMES_ROTATE='TRUE',
 PHYS_PAGE='260',
 XY='(-3400,3625)',
 ROT='2',
 VER='1',
 CDS_LIB='pure_quanta',
 CDS_PART_NAME='RT9818C44GV-RT9818C-44GV,SMLF,A',
 PART_TYPE='SMLF',
 MATERIAL='IC',
 VALUE='RT9818C-44GV',
 PRIM_FILE='./archive_libs/logical/rt9818c44gv/chips/chips.prt';

PART_NAME
 U102 'INA183A1IDBVR-INA183A1IDBVR,SMA':;

SECTION_NUMBER 1
 '@S9S_MB_2U_LIB.S9S_MB_2U(SCH_1):PAGE240_I29@PURE_QUANTA.INA183A1IDBVR(CHIPS)':
 C_PATH='@s9s_mb_2u_lib.s9s_mb_2u(sch_1):page240_i29@pure_quanta.ina183a1idbvr(c~
hips)',
 P_PATH='@s9s_mb_2u_lib.s9s_mb_2u(sch_1):page251_i29@pure_quanta.ina183a1idbvr(c~
hips)',
 PATH='I29',
 DRAWING='@S9S_MB_2U_LIB.S9S_MB_2U(SCH_1):PAGE240',
 PHYS_PAGE='251',
 XY='(1850,-2550)',
 ROT='0',
 VER='1',
 LOCATION='U102',
 SEC='1',
 CDS_LIB='pure_quanta',
 CDS_PART_NAME='INA183A1IDBVR-INA183A1IDBVR,SMA',
 SEC_TYPE='',
 PART_TYPE='SMLF',
 MATERIAL='EMPTY',
 VALUE='INA183A1IDBVR',
 PRIM_FILE='./archive_libs/logical/ina183a1idbvr/chips/chips.prt';

PART_NAME
 U103 'INA183A1IDBVR-INA183A1IDBVR,SMA':;

SECTION_NUMBER 1
 '@S9S_MB_2U_LIB.S9S_MB_2U(SCH_1):PAGE240_I22@PURE_QUANTA.INA183A1IDBVR(CHIPS)':
 C_PATH='@s9s_mb_2u_lib.s9s_mb_2u(sch_1):page240_i22@pure_quanta.ina183a1idbvr(c~
hips)',
 P_PATH='@s9s_mb_2u_lib.s9s_mb_2u(sch_1):page251_i22@pure_quanta.ina183a1idbvr(c~
hips)',
 PATH='I22',
 DRAWING='@S9S_MB_2U_LIB.S9S_MB_2U(SCH_1):PAGE240',
 PHYS_PAGE='251',
 XY='(1850,-3975)',
 ROT='0',
 VER='1',
 LOCATION='U103',
 SEC='1',
 CDS_LIB='pure_quanta',
 CDS_PART_NAME='INA183A1IDBVR-INA183A1IDBVR,SMA',
 SEC_TYPE='',
 PART_TYPE='SMLF',
 MATERIAL='EMPTY',
 VALUE='INA183A1IDBVR',
 PRIM_FILE='./archive_libs/logical/ina183a1idbvr/chips/chips.prt';

PART_NAME
 U104 '74LVC1G07GV-74LVC1G07GV,SMLF,IA':;

SECTION_NUMBER 1
 '@S9S_MB_2U_LIB.S9S_MB_2U(SCH_1):PAGE152_I63@PURE_QUANTA.74LVC1G07GV(CHIPS)':
 C_PATH='@s9s_mb_2u_lib.s9s_mb_2u(sch_1):page152_i63@pure_quanta.\74lvc1g07gv\(c~
hips)',
 P_PATH='@s9s_mb_2u_lib.s9s_mb_2u(sch_1):page155_i63@pure_quanta.\74lvc1g07gv\(c~
hips)',
 PATH='I63',
 DRAWING='@S9S_MB_2U_LIB.S9S_MB_2U(SCH_1):PAGE152',
 PHYS_PAGE='155',
 XY='(-7425,5675)',
 ROT='0',
 VER='1',
 CDS_LIB='pure_quanta',
 CDS_PART_NAME='74LVC1G07GV-74LVC1G07GV,SMLF,IA',
 PART_TYPE='SMLF',
 MATERIAL='IC',
 VALUE='74LVC1G07GV',
 PRIM_FILE='./archive_libs/logical/74lvc1g07gv/chips/chips.prt';

PART_NAME
 U117 'TPS3895ADRYR-TPS3895ADRYR,SMLFA':
 ROOM='DELAY1_BOM2';

SECTION_NUMBER 1
 '@S9S_MB_2U_LIB.S9S_MB_2U(SCH_1):PAGE232_I26@PURE_QUANTA.TPS3895ADRYR(CHIPS)':
 C_PATH='@s9s_mb_2u_lib.s9s_mb_2u(sch_1):page232_i26@pure_quanta.tps3895adryr(ch~
ips)',
 P_PATH='@s9s_mb_2u_lib.s9s_mb_2u(sch_1):page244_i26@pure_quanta.tps3895adryr(ch~
ips)',
 PATH='I26',
 DRAWING='@S9S_MB_2U_LIB.S9S_MB_2U(SCH_1):PAGE232',
 PHYS_PAGE='244',
 XY='(50,1150)',
 ROT='0',
 VER='1',
 LOCATION='U117',
 CDS_LIB='pure_quanta',
 CDS_PART_NAME='TPS3895ADRYR-TPS3895ADRYR,SMLFA',
 PART_TYPE='SMLF',
 MATERIAL='EMPTY',
 ROOM='DELAY1_BOM2',
 VALUE='TPS3895ADRYR',
 PRIM_FILE='./archive_libs/logical/tps3895adryr/chips/chips.prt';

PART_NAME
 U134 '74LVC2G07DW7-74LVC2G07DW-7,SMLA':;

SECTION_NUMBER 1
 '@S9S_MB_2U_LIB.S9S_MB_2U(SCH_1):PAGE297_I305@PURE_QUANTA.74LVC2G07DW7(CHIPS)':
 C_PATH='@s9s_mb_2u_lib.s9s_mb_2u(sch_1):page297_i305@pure_quanta.\74lvc2g07dw7\~
(chips)',
 P_PATH='@s9s_mb_2u_lib.s9s_mb_2u(sch_1):page191_i305@pure_quanta.\74lvc2g07dw7\~
(chips)',
 PATH='I305',
 DRAWING='@S9S_MB_2U_LIB.S9S_MB_2U(SCH_1):PAGE297',
 PHYS_PAGE='191',
 XY='(250,-600)',
 ROT='0',
 VER='1',
 LOCATION='U134',
 CDS_LIB='pure_quanta',
 CDS_PART_NAME='74LVC2G07DW7-74LVC2G07DW-7,SMLA',
 PART_TYPE='SMLF',
 MATERIAL='IC',
 VALUE='74LVC2G07DW-7',
 PRIM_FILE='./archive_libs/logical/74lvc2g07dw7/chips/chips.prt';

PART_NAME
 U142 'NC7SB3157_SMLF-NC7SB3157P6X,NCA':;

SECTION_NUMBER 1
 '@S9S_MB_2U_LIB.S9S_MB_2U(SCH_1):PAGE185_I35@PURE_QUANTA.NC7SB3157(CHIPS)':
 C_PATH='@s9s_mb_2u_lib.s9s_mb_2u(sch_1):page185_i35@pure_quanta.nc7sb3157(chips~
)',
 P_PATH='@s9s_mb_2u_lib.s9s_mb_2u(sch_1):page197_i35@pure_quanta.nc7sb3157(chips~
)',
 PATH='I35',
 DRAWING='@S9S_MB_2U_LIB.S9S_MB_2U(SCH_1):PAGE185',
 PHYS_PAGE='197',
 XY='(-5450,4075)',
 ROT='0',
 VER='1',
 PACK_TYPE='SMLF',
 SEC='1',
 CDS_LIB='pure_quanta',
 CDS_PART_NAME='NC7SB3157_SMLF-NC7SB3157P6X,NCA',
 MANUF_PN='NC7SB3157P6X',
 SEC_TYPE='SMLF',
 MATERIAL='IC',
 VALUE='NC7SB3157P6X',
 PRIM_FILE='./archive_libs/logical/nc7sb3157/chips/chips.prt';

PART_NAME
 U143 'PCA9545APW-PCA9545APW,SMLF,IC,A':;

SECTION_NUMBER 1
 '@S9S_MB_2U_LIB.S9S_MB_2U(SCH_1):PAGE224_I106@PURE_QUANTA.PCA9545APW(CHIPS)':
 C_PATH='@s9s_mb_2u_lib.s9s_mb_2u(sch_1):page224_i106@pure_quanta.pca9545apw(chi~
ps)',
 P_PATH='@s9s_mb_2u_lib.s9s_mb_2u(sch_1):page236_i106@pure_quanta.pca9545apw(chi~
ps)',
 PATH='I106',
 DRAWING='@S9S_MB_2U_LIB.S9S_MB_2U(SCH_1):PAGE224',
 PHYS_PAGE='236',
 XY='(-250,8400)',
 ROT='0',
 VER='1',
 LOCATION='U143',
 SEC='1',
 CDS_LIB='pure_quanta',
 CDS_PART_NAME='PCA9545APW-PCA9545APW,SMLF,IC,A',
 SEC_TYPE='',
 PART_TYPE='SMLF',
 MATERIAL='IC',
 VALUE='PCA9545APW',
 PRIM_FILE='./archive_libs/logical/pca9545apw/chips/chips.prt';

PART_NAME
 U145 '74LVC1G126SE7-74LVC1G126SE-7,SA':;

SECTION_NUMBER 1
 '@S9S_MB_2U_LIB.S9S_MB_2U(SCH_1):PAGE297_I163@PURE_QUANTA.74LVC1G126SE7(CHIPS)':
 C_PATH='@s9s_mb_2u_lib.s9s_mb_2u(sch_1):page297_i163@pure_quanta.\74lvc1g126se7~
\(chips)',
 P_PATH='@s9s_mb_2u_lib.s9s_mb_2u(sch_1):page191_i163@pure_quanta.\74lvc1g126se7~
\(chips)',
 PATH='I163',
 DRAWING='@S9S_MB_2U_LIB.S9S_MB_2U(SCH_1):PAGE297',
 PHYS_PAGE='191',
 XY='(3675,875)',
 ROT='0',
 VER='1',
 SEC='1',
 CDS_LIB='pure_quanta',
 CDS_PART_NAME='74LVC1G126SE7-74LVC1G126SE-7,SA',
 SEC_TYPE='',
 PART_TYPE='SMLF',
 MATERIAL='IC',
 VALUE='74LVC1G126SE-7',
 PRIM_FILE='./archive_libs/logical/74lvc1g126se7/chips/chips.prt';

PART_NAME
 U150 '74LVC2G17GW-74LVC2G17GW,SMLF,IA':;

SECTION_NUMBER 1
 '@S9S_MB_2U_LIB.S9S_MB_2U(SCH_1):PAGE213_I2@PURE_QUANTA.74LVC2G17GW(CHIPS)':
 C_PATH='@s9s_mb_2u_lib.s9s_mb_2u(sch_1):page213_i2@pure_quanta.\74lvc2g17gw\(ch~
ips)',
 P_PATH='@s9s_mb_2u_lib.s9s_mb_2u(sch_1):page224_i2@pure_quanta.\74lvc2g17gw\(ch~
ips)',
 PATH='I2',
 DRAWING='@S9S_MB_2U_LIB.S9S_MB_2U(SCH_1):PAGE213',
 PHYS_PAGE='224',
 XY='(-8000,4825)',
 ROT='0',
 VER='1',
 CDS_LIB='pure_quanta',
 CDS_PART_NAME='74LVC2G17GW-74LVC2G17GW,SMLF,IA',
 PART_TYPE='SMLF',
 MATERIAL='IC',
 VALUE='74LVC2G17GW',
 PRIM_FILE='./archive_libs/logical/74lvc2g17gw/chips/chips.prt';

PART_NAME
 U154 '74LVC1G07SE7-74LVC1G07SE-7,SMLA':;

SECTION_NUMBER 1
 '@S9S_MB_2U_LIB.S9S_MB_2U(SCH_1):PAGE190_I95@PURE_QUANTA.74LVC1G07SE7(CHIPS)':
 C_PATH='@s9s_mb_2u_lib.s9s_mb_2u(sch_1):page190_i95@pure_quanta.\74lvc1g07se7\(~
chips)',
 P_PATH='@s9s_mb_2u_lib.s9s_mb_2u(sch_1):page202_i95@pure_quanta.\74lvc1g07se7\(~
chips)',
 PATH='I95',
 DRAWING='@S9S_MB_2U_LIB.S9S_MB_2U(SCH_1):PAGE190',
 PHYS_PAGE='202',
 XY='(1700,1400)',
 ROT='0',
 VER='1',
 LOCATION='U154',
 CDS_LIB='pure_quanta',
 CDS_PART_NAME='74LVC1G07SE7-74LVC1G07SE-7,SMLA',
 PART_TYPE='SMLF',
 MATERIAL='IC',
 VALUE='74LVC1G07SE-7',
 PRIM_FILE='./archive_libs/logical/74lvc1g07se7/chips/chips.prt';

PART_NAME
 U157 '74LVC1G07GV-74LVC1G07GV,SMLF,IA':;

SECTION_NUMBER 1
 '@S9S_MB_2U_LIB.S9S_MB_2U(SCH_1):PAGE152_I65@PURE_QUANTA.74LVC1G07GV(CHIPS)':
 C_PATH='@s9s_mb_2u_lib.s9s_mb_2u(sch_1):page152_i65@pure_quanta.\74lvc1g07gv\(c~
hips)',
 P_PATH='@s9s_mb_2u_lib.s9s_mb_2u(sch_1):page155_i65@pure_quanta.\74lvc1g07gv\(c~
hips)',
 PATH='I65',
 DRAWING='@S9S_MB_2U_LIB.S9S_MB_2U(SCH_1):PAGE152',
 PHYS_PAGE='155',
 XY='(-5125,4100)',
 ROT='0',
 VER='1',
 CDS_LIB='pure_quanta',
 CDS_PART_NAME='74LVC1G07GV-74LVC1G07GV,SMLF,IA',
 PART_TYPE='SMLF',
 MATERIAL='IC',
 VALUE='74LVC1G07GV',
 PRIM_FILE='./archive_libs/logical/74lvc1g07gv/chips/chips.prt';

PART_NAME
 U158 'MOSFET_NCH_GDS_ESD_PROTECTED-2A':;

SECTION_NUMBER 1
 '@S9S_MB_2U_LIB.S9S_MB_2U(SCH_1):PAGE234_I6@PURE_QUANTA.MOSFET_NCH_GDS_ESD_PROTECTED(CHIPS)':
 C_PATH='@s9s_mb_2u_lib.s9s_mb_2u(sch_1):page234_i6@pure_quanta.mosfet_nch_gds_e~
sd_protected(chips)',
 P_PATH='@s9s_mb_2u_lib.s9s_mb_2u(sch_1):page247_i6@pure_quanta.mosfet_nch_gds_e~
sd_protected(chips)',
 PATH='I6',
 DRAWING='@S9S_MB_2U_LIB.S9S_MB_2U(SCH_1):PAGE234',
 PHYS_PAGE='247',
 XY='(11625,3125)',
 ROT='0',
 VER='1',
 CDS_LIB='pure_quanta',
 CDS_PART_NAME='MOSFET_NCH_GDS_ESD_PROTECTED-2A',
 PART_TYPE='SMLF',
 MATERIAL='IC',
 VALUE='2N7002K',
 PRIM_FILE='./archive_libs/logical/mosfet_nch_gds_esd_protected/chips/chips.prt';

PART_NAME
 U175 'LTC4307CMS8-LTC4307CMS8,SMLF,IA':;

SECTION_NUMBER 1
 '@S9S_MB_2U_LIB.S9S_MB_2U(SCH_1):PAGE222_I50@PURE_QUANTA.LTC4307CMS8(CHIPS)':
 C_PATH='@s9s_mb_2u_lib.s9s_mb_2u(sch_1):page222_i50@pure_quanta.ltc4307cms8(chi~
ps)',
 P_PATH='@s9s_mb_2u_lib.s9s_mb_2u(sch_1):page234_i50@pure_quanta.ltc4307cms8(chi~
ps)',
 PATH='I50',
 DRAWING='@S9S_MB_2U_LIB.S9S_MB_2U(SCH_1):PAGE222',
 PHYS_PAGE='234',
 XY='(-4625,8750)',
 ROT='0',
 VER='1',
 LOCATION='U175',
 CDS_LIB='pure_quanta',
 CDS_PART_NAME='LTC4307CMS8-LTC4307CMS8,SMLF,IA',
 PART_TYPE='SMLF',
 MATERIAL='IC',
 VALUE='LTC4307CMS8',
 PRIM_FILE='./archive_libs/logical/ltc4307cms8/chips/chips.prt';

PART_NAME
 U176 'LTC4307CMS8-LTC4307CMS8,SMLF,EA':;

SECTION_NUMBER 1
 '@S9S_MB_2U_LIB.S9S_MB_2U(SCH_1):PAGE222_I31@PURE_QUANTA.LTC4307CMS8(CHIPS)':
 C_PATH='@s9s_mb_2u_lib.s9s_mb_2u(sch_1):page222_i31@pure_quanta.ltc4307cms8(chi~
ps)',
 P_PATH='@s9s_mb_2u_lib.s9s_mb_2u(sch_1):page234_i31@pure_quanta.ltc4307cms8(chi~
ps)',
 PATH='I31',
 DRAWING='@S9S_MB_2U_LIB.S9S_MB_2U(SCH_1):PAGE222',
 PHYS_PAGE='234',
 XY='(-2275,4600)',
 ROT='0',
 VER='1',
 LOCATION='U176',
 CDS_LIB='pure_quanta',
 CDS_PART_NAME='LTC4307CMS8-LTC4307CMS8,SMLF,EA',
 PART_TYPE='SMLF',
 MATERIAL='EMPTY',
 VALUE='LTC4307CMS8',
 PRIM_FILE='./archive_libs/logical/ltc4307cms8/chips/chips.prt';

PART_NAME
 U181 'PCA9539RPW-PCA9539RPW,SMLF,IC,A':;

SECTION_NUMBER 1
 '@S9S_MB_2U_LIB.S9S_MB_2U(SCH_1):PAGE214_I66@PURE_QUANTA.PCA9539RPW(CHIPS)':
 C_PATH='@s9s_mb_2u_lib.s9s_mb_2u(sch_1):page214_i66@pure_quanta.pca9539rpw(chip~
s)',
 P_PATH='@s9s_mb_2u_lib.s9s_mb_2u(sch_1):page227_i66@pure_quanta.pca9539rpw(chip~
s)',
 PATH='I66',
 DRAWING='@S9S_MB_2U_LIB.S9S_MB_2U(SCH_1):PAGE214',
 PHYS_PAGE='227',
 XY='(7875,5200)',
 ROT='0',
 VER='1',
 LOCATION='U181',
 SEC='1',
 CDS_LIB='pure_quanta',
 CDS_PART_NAME='PCA9539RPW-PCA9539RPW,SMLF,IC,A',
 SEC_TYPE='',
 PART_TYPE='SMLF',
 MATERIAL='IC',
 VALUE='PCA9539RPW',
 PRIM_FILE='./archive_libs/logical/pca9539rpw/chips/chips.prt';

PART_NAME
 U192 'LTC4307CMS8-LTC4307CMS8,SMLF,IA':;

SECTION_NUMBER 1
 '@S9S_MB_2U_LIB.S9S_MB_2U(SCH_1):PAGE233_I16@PURE_QUANTA.LTC4307CMS8(CHIPS)':
 C_PATH='@s9s_mb_2u_lib.s9s_mb_2u(sch_1):page233_i16@pure_quanta.ltc4307cms8(chi~
ps)',
 P_PATH='@s9s_mb_2u_lib.s9s_mb_2u(sch_1):page245_i16@pure_quanta.ltc4307cms8(chi~
ps)',
 PATH='I16',
 DRAWING='@S9S_MB_2U_LIB.S9S_MB_2U(SCH_1):PAGE233',
 PHYS_PAGE='245',
 XY='(-2550,-2175)',
 ROT='0',
 VER='1',
 CDS_LIB='pure_quanta',
 CDS_PART_NAME='LTC4307CMS8-LTC4307CMS8,SMLF,IA',
 PART_TYPE='SMLF',
 MATERIAL='IC',
 VALUE='LTC4307CMS8',
 PRIM_FILE='./archive_libs/logical/ltc4307cms8/chips/chips.prt';

PART_NAME
 U193 'MAX11617EEET-MAX11617EEE+T,SMLA':
 ROOM='ADC1_BOM1';

SECTION_NUMBER 1
 '@S9S_MB_2U_LIB.S9S_MB_2U(SCH_1):PAGE239_I57@PURE_QUANTA.MAX11617EEET(CHIPS)':
 C_PATH='@s9s_mb_2u_lib.s9s_mb_2u(sch_1):page239_i57@pure_quanta.max11617eeet(ch~
ips)',
 P_PATH='@s9s_mb_2u_lib.s9s_mb_2u(sch_1):page250_i57@pure_quanta.max11617eeet(ch~
ips)',
 PATH='I57',
 DRAWING='@S9S_MB_2U_LIB.S9S_MB_2U(SCH_1):PAGE239',
 PHYS_PAGE='250',
 XY='(5475,4100)',
 ROT='0',
 VER='1',
 SEC='1',
 CDS_LIB='pure_quanta',
 CDS_PART_NAME='MAX11617EEET-MAX11617EEE+T,SMLA',
 SEC_TYPE='',
 PART_TYPE='SMLF',
 MATERIAL='EMPTY',
 ROOM='ADC1_BOM1',
 VALUE='MAX11617EEE+T',
 PRIM_FILE='./archive_libs/logical/max11617eeet/chips/chips.prt';

PART_NAME
 U194 'LTC4307CMS8-LTC4307CMS8,SMLF,IA':;

SECTION_NUMBER 1
 '@S9S_MB_2U_LIB.S9S_MB_2U(SCH_1):PAGE222_I63@PURE_QUANTA.LTC4307CMS8(CHIPS)':
 C_PATH='@s9s_mb_2u_lib.s9s_mb_2u(sch_1):page222_i63@pure_quanta.ltc4307cms8(chi~
ps)',
 P_PATH='@s9s_mb_2u_lib.s9s_mb_2u(sch_1):page234_i63@pure_quanta.ltc4307cms8(chi~
ps)',
 PATH='I63',
 DRAWING='@S9S_MB_2U_LIB.S9S_MB_2U(SCH_1):PAGE222',
 PHYS_PAGE='234',
 XY='(-2250,7375)',
 ROT='0',
 VER='1',
 LOCATION='U194',
 CDS_LIB='pure_quanta',
 CDS_PART_NAME='LTC4307CMS8-LTC4307CMS8,SMLF,IA',
 PART_TYPE='SMLF',
 MATERIAL='IC',
 VALUE='LTC4307CMS8',
 PRIM_FILE='./archive_libs/logical/ltc4307cms8/chips/chips.prt';

PART_NAME
 U195 '74LVC2G17GW-74LVC2G17GW,SMLF,IA':;

SECTION_NUMBER 1
 '@S9S_MB_2U_LIB.S9S_MB_2U(SCH_1):PAGE140_I65@PURE_QUANTA.74LVC2G17GW(CHIPS)':
 C_PATH='@s9s_mb_2u_lib.s9s_mb_2u(sch_1):page140_i65@pure_quanta.\74lvc2g17gw\(c~
hips)',
 P_PATH='@s9s_mb_2u_lib.s9s_mb_2u(sch_1):page151_i65@pure_quanta.\74lvc2g17gw\(c~
hips)',
 PATH='I65',
 DRAWING='@S9S_MB_2U_LIB.S9S_MB_2U(SCH_1):PAGE140',
 PHYS_PAGE='151',
 XY='(1475,2450)',
 ROT='0',
 VER='1',
 CDS_LIB='pure_quanta',
 CDS_PART_NAME='74LVC2G17GW-74LVC2G17GW,SMLF,IA',
 PART_TYPE='SMLF',
 MATERIAL='IC',
 VALUE='74LVC2G17GW',
 PRIM_FILE='./archive_libs/logical/74lvc2g17gw/chips/chips.prt';

PART_NAME
 U196 '74LVC2G17GW-74LVC2G17GW,SMLF,IA':;

SECTION_NUMBER 1
 '@S9S_MB_2U_LIB.S9S_MB_2U(SCH_1):PAGE140_I127@PURE_QUANTA.74LVC2G17GW(CHIPS)':
 C_PATH='@s9s_mb_2u_lib.s9s_mb_2u(sch_1):page140_i127@pure_quanta.\74lvc2g17gw\(~
chips)',
 P_PATH='@s9s_mb_2u_lib.s9s_mb_2u(sch_1):page151_i127@pure_quanta.\74lvc2g17gw\(~
chips)',
 PATH='I127',
 DRAWING='@S9S_MB_2U_LIB.S9S_MB_2U(SCH_1):PAGE140',
 PHYS_PAGE='151',
 XY='(1475,50)',
 ROT='0',
 VER='1',
 CDS_LIB='pure_quanta',
 CDS_PART_NAME='74LVC2G17GW-74LVC2G17GW,SMLF,IA',
 PART_TYPE='SMLF',
 MATERIAL='IC',
 VALUE='74LVC2G17GW',
 PRIM_FILE='./archive_libs/logical/74lvc2g17gw/chips/chips.prt';

PART_NAME
 U200 'LTC4307CMS8-LTC4307CMS8,SMLF,IA':;

SECTION_NUMBER 1
 '@S9S_MB_2U_LIB.S9S_MB_2U(SCH_1):PAGE222_I11@PURE_QUANTA.LTC4307CMS8(CHIPS)':
 C_PATH='@s9s_mb_2u_lib.s9s_mb_2u(sch_1):page222_i11@pure_quanta.ltc4307cms8(chi~
ps)',
 P_PATH='@s9s_mb_2u_lib.s9s_mb_2u(sch_1):page234_i11@pure_quanta.ltc4307cms8(chi~
ps)',
 PATH='I11',
 DRAWING='@S9S_MB_2U_LIB.S9S_MB_2U(SCH_1):PAGE222',
 PHYS_PAGE='234',
 XY='(-4850,6025)',
 ROT='0',
 VER='1',
 LOCATION='U200',
 CDS_LIB='pure_quanta',
 CDS_PART_NAME='LTC4307CMS8-LTC4307CMS8,SMLF,IA',
 PART_TYPE='SMLF',
 MATERIAL='IC',
 VALUE='LTC4307CMS8',
 PRIM_FILE='./archive_libs/logical/ltc4307cms8/chips/chips.prt';

PART_NAME
 U204 '74LVC1G126SE7-74LVC1G126SE-7,SA':;

SECTION_NUMBER 1
 '@S9S_MB_2U_LIB.S9S_MB_2U(SCH_1):PAGE140_I195@PURE_QUANTA.74LVC1G126SE7(CHIPS)':
 C_PATH='@s9s_mb_2u_lib.s9s_mb_2u(sch_1):page140_i195@pure_quanta.\74lvc1g126se7~
\(chips)',
 P_PATH='@s9s_mb_2u_lib.s9s_mb_2u(sch_1):page151_i195@pure_quanta.\74lvc1g126se7~
\(chips)',
 PATH='I195',
 DRAWING='@S9S_MB_2U_LIB.S9S_MB_2U(SCH_1):PAGE140',
 PHYS_PAGE='151',
 XY='(-550,-1900)',
 ROT='0',
 VER='1',
 LOCATION='U204',
 CDS_LIB='pure_quanta',
 CDS_PART_NAME='74LVC1G126SE7-74LVC1G126SE-7,SA',
 PART_TYPE='SMLF',
 MATERIAL='IC',
 VALUE='74LVC1G126SE-7',
 PRIM_FILE='./archive_libs/logical/74lvc1g126se7/chips/chips.prt';

PART_NAME
 U205 'TPS3700DDCR-TPS3700DDCR,SMLF,EA':;

SECTION_NUMBER 1
 '@S9S_MB_2U_LIB.S9S_MB_2U(SCH_1):PAGE326_I5@PURE_QUANTA.TPS3700DDCR(CHIPS)':
 C_PATH='@s9s_mb_2u_lib.s9s_mb_2u(sch_1):page326_i5@pure_quanta.tps3700ddcr(chip~
s)',
 P_PATH='@s9s_mb_2u_lib.s9s_mb_2u(sch_1):page306_i5@pure_quanta.tps3700ddcr(chip~
s)',
 PATH='I5',
 DRAWING='@S9S_MB_2U_LIB.S9S_MB_2U(SCH_1):PAGE326',
 PHYS_PAGE='306',
 XY='(-725,-1425)',
 ROT='0',
 VER='1',
 CDS_LIB='pure_quanta',
 CDS_PART_NAME='TPS3700DDCR-TPS3700DDCR,SMLF,EA',
 PART_TYPE='SMLF',
 MATERIAL='EMPTY',
 VALUE='TPS3700DDCR',
 PRIM_FILE='./archive_libs/logical/tps3700ddcr/chips/chips.prt';

PART_NAME
 U206 'LT6700CS61TRPBF-LT6700CS6-1#TRA':;

SECTION_NUMBER 1
 '@S9S_MB_2U_LIB.S9S_MB_2U(SCH_1):PAGE326_I102@PURE_QUANTA.LT6700CS61TRPBF(CHIPS)':
 C_PATH='@s9s_mb_2u_lib.s9s_mb_2u(sch_1):page326_i102@pure_quanta.lt6700cs61trpb~
f(chips)',
 P_PATH='@s9s_mb_2u_lib.s9s_mb_2u(sch_1):page306_i102@pure_quanta.lt6700cs61trpb~
f(chips)',
 PATH='I102',
 DRAWING='@S9S_MB_2U_LIB.S9S_MB_2U(SCH_1):PAGE326',
 PHYS_PAGE='306',
 XY='(1850,-175)',
 ROT='0',
 VER='1',
 LOCATION='U206',
 CDS_LIB='pure_quanta',
 CDS_PART_NAME='LT6700CS61TRPBF-LT6700CS6-1#TRA',
 PART_TYPE='SMLF',
 MATERIAL='IC',
 VALUE='LT6700CS6-1#TRPBF',
 PRIM_FILE='./archive_libs/logical/lt6700cs61trpbf/chips/chips.prt';

PART_NAME
 U207 '74LVC1G17GW-74LVC1G17GW,SMLF,IA':;

SECTION_NUMBER 1
 '@S9S_MB_2U_LIB.S9S_MB_2U(SCH_1):PAGE156_I35@PURE_QUANTA.74LVC1G17GW(CHIPS)':
 C_PATH='@s9s_mb_2u_lib.s9s_mb_2u(sch_1):page156_i35@pure_quanta.\74lvc1g17gw\(c~
hips)',
 P_PATH='@s9s_mb_2u_lib.s9s_mb_2u(sch_1):page161_i35@pure_quanta.\74lvc1g17gw\(c~
hips)',
 PATH='I35',
 DRAWING='@S9S_MB_2U_LIB.S9S_MB_2U(SCH_1):PAGE156',
 PIN_NAMES_ROTATE='True',
 PHYS_PAGE='161',
 XY='(5550,1100)',
 ROT='0',
 VER='1',
 SEC='1',
 CDS_LIB='pure_quanta',
 CDS_PART_NAME='74LVC1G17GW-74LVC1G17GW,SMLF,IA',
 SEC_TYPE='',
 PART_TYPE='SMLF',
 MATERIAL='IC',
 VALUE='74LVC1G17GW',
 PRIM_FILE='./archive_libs/logical/74lvc1g17gw/chips/chips.prt';

PART_NAME
 U208 '74LVC1G08W57-74LVC1G08W5-7,SMLA':;

SECTION_NUMBER 1
 '@S9S_MB_2U_LIB.S9S_MB_2U(SCH_1):PAGE154_I190@PURE_QUANTA.74LVC1G08W57(CHIPS)':
 C_PATH='@s9s_mb_2u_lib.s9s_mb_2u(sch_1):page154_i190@pure_quanta.\74lvc1g08w57\~
(chips)',
 P_PATH='@s9s_mb_2u_lib.s9s_mb_2u(sch_1):page158_i190@pure_quanta.\74lvc1g08w57\~
(chips)',
 PATH='I190',
 DRAWING='@S9S_MB_2U_LIB.S9S_MB_2U(SCH_1):PAGE154',
 PHYS_PAGE='158',
 XY='(-2925,5125)',
 ROT='0',
 VER='1',
 CDS_LIB='pure_quanta',
 CDS_PART_NAME='74LVC1G08W57-74LVC1G08W5-7,SMLA',
 PART_TYPE='SMLF',
 MATERIAL='IC',
 VALUE='74LVC1G08W5-7',
 PRIM_FILE='./archive_libs/logical/74lvc1g08w57/chips/chips.prt';

PART_NAME
 U209 'PCA9555APW-PCA9555APW,SMLF,IC,A':;

SECTION_NUMBER 1
 '@S9S_MB_2U_LIB.S9S_MB_2U(SCH_1):PAGE154_I206@PURE_QUANTA.PCA9555APW(CHIPS)':
 C_PATH='@s9s_mb_2u_lib.s9s_mb_2u(sch_1):page154_i206@pure_quanta.pca9555apw(chi~
ps)',
 P_PATH='@s9s_mb_2u_lib.s9s_mb_2u(sch_1):page158_i206@pure_quanta.pca9555apw(chi~
ps)',
 PATH='I206',
 DRAWING='@S9S_MB_2U_LIB.S9S_MB_2U(SCH_1):PAGE154',
 PHYS_PAGE='158',
 XY='(-1425,9250)',
 ROT='0',
 VER='1',
 LOCATION='U209',
 SEC='1',
 CDS_LIB='pure_quanta',
 CDS_PART_NAME='PCA9555APW-PCA9555APW,SMLF,IC,A',
 SEC_TYPE='',
 PART_TYPE='SMLF',
 MATERIAL='IC',
 VALUE='PCA9555APW',
 PRIM_FILE='./archive_libs/logical/pca9555apw/chips/chips.prt';

PART_NAME
 U210 '74LVC1G08W57-74LVC1G08W5-7,SMLA':;

SECTION_NUMBER 1
 '@S9S_MB_2U_LIB.S9S_MB_2U(SCH_1):PAGE154_I189@PURE_QUANTA.74LVC1G08W57(CHIPS)':
 C_PATH='@s9s_mb_2u_lib.s9s_mb_2u(sch_1):page154_i189@pure_quanta.\74lvc1g08w57\~
(chips)',
 P_PATH='@s9s_mb_2u_lib.s9s_mb_2u(sch_1):page158_i189@pure_quanta.\74lvc1g08w57\~
(chips)',
 PATH='I189',
 DRAWING='@S9S_MB_2U_LIB.S9S_MB_2U(SCH_1):PAGE154',
 PHYS_PAGE='158',
 XY='(2400,6975)',
 ROT='0',
 VER='1',
 CDS_LIB='pure_quanta',
 CDS_PART_NAME='74LVC1G08W57-74LVC1G08W5-7,SMLA',
 PART_TYPE='SMLF',
 MATERIAL='IC',
 VALUE='74LVC1G08W5-7',
 PRIM_FILE='./archive_libs/logical/74lvc1g08w57/chips/chips.prt';

PART_NAME
 U211 '74LVC2G07DW7-74LVC2G07DW-7,SMLA':;

SECTION_NUMBER 1
 '@S9S_MB_2U_LIB.S9S_MB_2U(SCH_1):PAGE153_I26@PURE_QUANTA.74LVC2G07DW7(CHIPS)':
 C_PATH='@s9s_mb_2u_lib.s9s_mb_2u(sch_1):page153_i26@pure_quanta.\74lvc2g07dw7\(~
chips)',
 P_PATH='@s9s_mb_2u_lib.s9s_mb_2u(sch_1):page156_i26@pure_quanta.\74lvc2g07dw7\(~
chips)',
 PATH='I26',
 DRAWING='@S9S_MB_2U_LIB.S9S_MB_2U(SCH_1):PAGE153',
 PHYS_PAGE='156',
 XY='(5175,9425)',
 ROT='0',
 VER='1',
 CDS_LIB='pure_quanta',
 CDS_PART_NAME='74LVC2G07DW7-74LVC2G07DW-7,SMLA',
 PART_TYPE='SMLF',
 MATERIAL='IC',
 VALUE='74LVC2G07DW-7',
 PRIM_FILE='./archive_libs/logical/74lvc2g07dw7/chips/chips.prt';

PART_NAME
 U212 '74LVC2G07DW7-74LVC2G07DW-7,SMLA':;

SECTION_NUMBER 1
 '@S9S_MB_2U_LIB.S9S_MB_2U(SCH_1):PAGE153_I23@PURE_QUANTA.74LVC2G07DW7(CHIPS)':
 C_PATH='@s9s_mb_2u_lib.s9s_mb_2u(sch_1):page153_i23@pure_quanta.\74lvc2g07dw7\(~
chips)',
 P_PATH='@s9s_mb_2u_lib.s9s_mb_2u(sch_1):page156_i23@pure_quanta.\74lvc2g07dw7\(~
chips)',
 PATH='I23',
 DRAWING='@S9S_MB_2U_LIB.S9S_MB_2U(SCH_1):PAGE153',
 PHYS_PAGE='156',
 XY='(5175,8525)',
 ROT='0',
 VER='1',
 CDS_LIB='pure_quanta',
 CDS_PART_NAME='74LVC2G07DW7-74LVC2G07DW-7,SMLA',
 PART_TYPE='SMLF',
 MATERIAL='IC',
 VALUE='74LVC2G07DW-7',
 PRIM_FILE='./archive_libs/logical/74lvc2g07dw7/chips/chips.prt';

PART_NAME
 U215 'MOSFET_N_SMLF-BSS138K,BSS138K,A':;

SECTION_NUMBER 1
 '@S9S_MB_2U_LIB.S9S_MB_2U(SCH_1):PAGE132_I3@PURE_QUANTA.MOSFET_N(CHIPS)':
 C_PATH='@s9s_mb_2u_lib.s9s_mb_2u(sch_1):page132_i3@pure_quanta.mosfet_n(chips)',
 P_PATH='@s9s_mb_2u_lib.s9s_mb_2u(sch_1):page164_i3@pure_quanta.mosfet_n(chips)',
 PATH='I3',
 DRAWING='@S9S_MB_2U_LIB.S9S_MB_2U(SCH_1):PAGE132',
 PHYS_PAGE='164',
 XY='(-4300,-1250)',
 ROT='0',
 VER='1',
 PACK_TYPE='SMLF',
 CDS_LIB='pure_quanta',
 CDS_PART_NAME='MOSFET_N_SMLF-BSS138K,BSS138K,A',
 MANUF_PN='BSS138K',
 MATERIAL='IC',
 VALUE='BSS138K',
 PRIM_FILE='./archive_libs/logical/mosfet_n/chips/chips.prt';

PART_NAME
 U216 'APX80929SAG7-APX809-29SAG-7,SMA':;

SECTION_NUMBER 1
 '@S9S_MB_2U_LIB.S9S_MB_2U(SCH_1):PAGE132_I85@PURE_QUANTA.APX80929SAG7(CHIPS)':
 C_PATH='@s9s_mb_2u_lib.s9s_mb_2u(sch_1):page132_i85@pure_quanta.apx80929sag7(ch~
ips)',
 P_PATH='@s9s_mb_2u_lib.s9s_mb_2u(sch_1):page164_i85@pure_quanta.apx80929sag7(ch~
ips)',
 PATH='I85',
 DRAWING='@S9S_MB_2U_LIB.S9S_MB_2U(SCH_1):PAGE132',
 PHYS_PAGE='164',
 XY='(-3800,1200)',
 ROT='2',
 VER='1',
 CDS_LIB='pure_quanta',
 CDS_PART_NAME='APX80929SAG7-APX809-29SAG-7,SMA',
 PART_TYPE='SMLF',
 MATERIAL='IC',
 VALUE='APX809-29SAG-7',
 PRIM_FILE='./archive_libs/logical/apx80929sag7/chips/chips.prt';

PART_NAME
 U217 '74LVC1G126SE7-74LVC1G126SE-7,SA':;

SECTION_NUMBER 1
 '@S9S_MB_2U_LIB.S9S_MB_2U(SCH_1):PAGE156_I79@PURE_QUANTA.74LVC1G126SE7(CHIPS)':
 C_PATH='@s9s_mb_2u_lib.s9s_mb_2u(sch_1):page156_i79@pure_quanta.\74lvc1g126se7\~
(chips)',
 P_PATH='@s9s_mb_2u_lib.s9s_mb_2u(sch_1):page161_i79@pure_quanta.\74lvc1g126se7\~
(chips)',
 PATH='I79',
 DRAWING='@S9S_MB_2U_LIB.S9S_MB_2U(SCH_1):PAGE156',
 PHYS_PAGE='161',
 XY='(4900,-1775)',
 ROT='0',
 VER='1',
 LOCATION='U217',
 CDS_LIB='pure_quanta',
 CDS_PART_NAME='74LVC1G126SE7-74LVC1G126SE-7,SA',
 PART_TYPE='SMLF',
 MATERIAL='IC',
 VALUE='74LVC1G126SE-7',
 PRIM_FILE='./archive_libs/logical/74lvc1g126se7/chips/chips.prt';

PART_NAME
 U218 '74LVC1G07GV-74LVC1G07GV,SMLF,IA':;

SECTION_NUMBER 1
 '@S9S_MB_2U_LIB.S9S_MB_2U(SCH_1):PAGE156_I31@PURE_QUANTA.74LVC1G07GV(CHIPS)':
 C_PATH='@s9s_mb_2u_lib.s9s_mb_2u(sch_1):page156_i31@pure_quanta.\74lvc1g07gv\(c~
hips)',
 P_PATH='@s9s_mb_2u_lib.s9s_mb_2u(sch_1):page161_i31@pure_quanta.\74lvc1g07gv\(c~
hips)',
 PATH='I31',
 DRAWING='@S9S_MB_2U_LIB.S9S_MB_2U(SCH_1):PAGE156',
 PHYS_PAGE='161',
 XY='(5825,-450)',
 ROT='0',
 VER='1',
 CDS_LIB='pure_quanta',
 CDS_PART_NAME='74LVC1G07GV-74LVC1G07GV,SMLF,IA',
 PART_TYPE='SMLF',
 MATERIAL='IC',
 VALUE='74LVC1G07GV',
 PRIM_FILE='./archive_libs/logical/74lvc1g07gv/chips/chips.prt';

PART_NAME
 U219 '74LVC1G07GV-74LVC1G07GV,SMLF,IA':;

SECTION_NUMBER 1
 '@S9S_MB_2U_LIB.S9S_MB_2U(SCH_1):PAGE156_I61@PURE_QUANTA.74LVC1G07GV(CHIPS)':
 C_PATH='@s9s_mb_2u_lib.s9s_mb_2u(sch_1):page156_i61@pure_quanta.\74lvc1g07gv\(c~
hips)',
 P_PATH='@s9s_mb_2u_lib.s9s_mb_2u(sch_1):page161_i61@pure_quanta.\74lvc1g07gv\(c~
hips)',
 PATH='I61',
 DRAWING='@S9S_MB_2U_LIB.S9S_MB_2U(SCH_1):PAGE156',
 PHYS_PAGE='161',
 XY='(8125,-1775)',
 ROT='0',
 VER='1',
 CDS_LIB='pure_quanta',
 CDS_PART_NAME='74LVC1G07GV-74LVC1G07GV,SMLF,IA',
 PART_TYPE='SMLF',
 MATERIAL='IC',
 VALUE='74LVC1G07GV',
 PRIM_FILE='./archive_libs/logical/74lvc1g07gv/chips/chips.prt';

PART_NAME
 U222 '74CBTLV3126PW-74CBTLV3126PW,SMA':;

SECTION_NUMBER 1
 '@S9S_MB_2U_LIB.S9S_MB_2U(SCH_1):PAGE307_I32@PURE_QUANTA.74CBTLV3126PW(CHIPS)':
 C_PATH='@s9s_mb_2u_lib.s9s_mb_2u(sch_1):page307_i32@pure_quanta.\74cbtlv3126pw\~
(chips)',
 P_PATH='@s9s_mb_2u_lib.s9s_mb_2u(sch_1):page160_i32@pure_quanta.\74cbtlv3126pw\~
(chips)',
 PATH='I32',
 DRAWING='@S9S_MB_2U_LIB.S9S_MB_2U(SCH_1):PAGE307',
 PHYS_PAGE='160',
 XY='(225,2275)',
 ROT='2',
 VER='1',
 CDS_LIB='pure_quanta',
 CDS_PART_NAME='74CBTLV3126PW-74CBTLV3126PW,SMA',
 PART_TYPE='SMLF',
 MATERIAL='IC',
 VALUE='74CBTLV3126PW',
 PRIM_FILE='./archive_libs/logical/74cbtlv3126pw/chips/chips.prt';

PART_NAME
 U223 '74CBTLV3126PW-74CBTLV3126PW,SMA':;

SECTION_NUMBER 1
 '@S9S_MB_2U_LIB.S9S_MB_2U(SCH_1):PAGE307_I78@PURE_QUANTA.74CBTLV3126PW(CHIPS)':
 C_PATH='@s9s_mb_2u_lib.s9s_mb_2u(sch_1):page307_i78@pure_quanta.\74cbtlv3126pw\~
(chips)',
 P_PATH='@s9s_mb_2u_lib.s9s_mb_2u(sch_1):page160_i78@pure_quanta.\74cbtlv3126pw\~
(chips)',
 PATH='I78',
 DRAWING='@S9S_MB_2U_LIB.S9S_MB_2U(SCH_1):PAGE307',
 PHYS_PAGE='160',
 XY='(225,850)',
 ROT='2',
 VER='1',
 CDS_LIB='pure_quanta',
 CDS_PART_NAME='74CBTLV3126PW-74CBTLV3126PW,SMA',
 PART_TYPE='SMLF',
 MATERIAL='IC',
 VALUE='74CBTLV3126PW',
 PRIM_FILE='./archive_libs/logical/74cbtlv3126pw/chips/chips.prt';

PART_NAME
 U224 '74LVC1G126SE7-74LVC1G126SE-7,SA':;

SECTION_NUMBER 1
 '@S9S_MB_2U_LIB.S9S_MB_2U(SCH_1):PAGE151_I7@PURE_QUANTA.74LVC1G126SE7(CHIPS)':
 C_PATH='@s9s_mb_2u_lib.s9s_mb_2u(sch_1):page151_i7@pure_quanta.\74lvc1g126se7\(~
chips)',
 P_PATH='@s9s_mb_2u_lib.s9s_mb_2u(sch_1):page154_i7@pure_quanta.\74lvc1g126se7\(~
chips)',
 PATH='I7',
 DRAWING='@S9S_MB_2U_LIB.S9S_MB_2U(SCH_1):PAGE151',
 PHYS_PAGE='154',
 XY='(-3375,2000)',
 ROT='0',
 VER='1',
 LOCATION='U224',
 CDS_LIB='pure_quanta',
 CDS_PART_NAME='74LVC1G126SE7-74LVC1G126SE-7,SA',
 PART_TYPE='SMLF',
 MATERIAL='IC',
 VALUE='74LVC1G126SE-7',
 PRIM_FILE='./archive_libs/logical/74lvc1g126se7/chips/chips.prt';

PART_NAME
 U225 '74LVC1G126SE7-74LVC1G126SE-7,SA':;

SECTION_NUMBER 1
 '@S9S_MB_2U_LIB.S9S_MB_2U(SCH_1):PAGE156_I74@PURE_QUANTA.74LVC1G126SE7(CHIPS)':
 C_PATH='@s9s_mb_2u_lib.s9s_mb_2u(sch_1):page156_i74@pure_quanta.\74lvc1g126se7\~
(chips)',
 P_PATH='@s9s_mb_2u_lib.s9s_mb_2u(sch_1):page161_i74@pure_quanta.\74lvc1g126se7\~
(chips)',
 PATH='I74',
 DRAWING='@S9S_MB_2U_LIB.S9S_MB_2U(SCH_1):PAGE156',
 PHYS_PAGE='161',
 XY='(5925,-3175)',
 ROT='0',
 VER='1',
 LOCATION='U225',
 CDS_LIB='pure_quanta',
 CDS_PART_NAME='74LVC1G126SE7-74LVC1G126SE-7,SA',
 PART_TYPE='SMLF',
 MATERIAL='IC',
 VALUE='74LVC1G126SE-7',
 PRIM_FILE='./archive_libs/logical/74lvc1g126se7/chips/chips.prt';

PART_NAME
 U235 'PCA9617ADP-PCA9617ADP,SMLF,IC,A':;

SECTION_NUMBER 1
 '@S9S_MB_2U_LIB.S9S_MB_2U(SCH_1):PAGE216_I5@PURE_QUANTA.PCA9617ADP(CHIPS)':
 C_PATH='@s9s_mb_2u_lib.s9s_mb_2u(sch_1):page216_i5@pure_quanta.pca9617adp(chips~
)',
 P_PATH='@s9s_mb_2u_lib.s9s_mb_2u(sch_1):page238_i5@pure_quanta.pca9617adp(chips~
)',
 PATH='I5',
 DRAWING='@S9S_MB_2U_LIB.S9S_MB_2U(SCH_1):PAGE216',
 PHYS_PAGE='238',
 XY='(-7150,3450)',
 ROT='0',
 VER='1',
 CDS_LIB='pure_quanta',
 CDS_PART_NAME='PCA9617ADP-PCA9617ADP,SMLF,IC,A',
 PART_TYPE='SMLF',
 MATERIAL='IC',
 VALUE='PCA9617ADP',
 PRIM_FILE='./archive_libs/logical/pca9617adp/chips/chips.prt';

PART_NAME
 U236 'PCA9617ADP-PCA9617ADP,SMLF,IC,A':;

SECTION_NUMBER 1
 '@S9S_MB_2U_LIB.S9S_MB_2U(SCH_1):PAGE216_I28@PURE_QUANTA.PCA9617ADP(CHIPS)':
 C_PATH='@s9s_mb_2u_lib.s9s_mb_2u(sch_1):page216_i28@pure_quanta.pca9617adp(chip~
s)',
 P_PATH='@s9s_mb_2u_lib.s9s_mb_2u(sch_1):page238_i28@pure_quanta.pca9617adp(chip~
s)',
 PATH='I28',
 DRAWING='@S9S_MB_2U_LIB.S9S_MB_2U(SCH_1):PAGE216',
 PHYS_PAGE='238',
 XY='(-7125,5275)',
 ROT='0',
 VER='1',
 CDS_LIB='pure_quanta',
 CDS_PART_NAME='PCA9617ADP-PCA9617ADP,SMLF,IC,A',
 PART_TYPE='SMLF',
 MATERIAL='IC',
 VALUE='PCA9617ADP',
 PRIM_FILE='./archive_libs/logical/pca9617adp/chips/chips.prt';

PART_NAME
 U237 'PI3EQX12902AZLEX-PI3EQX12902AZA':
 ROOM='PCIE REDRIVER1_BOM1';

SECTION_NUMBER 1
 '@S9S_MB_2U_LIB.S9S_MB_2U(SCH_1):PAGE136_I50@PURE_QUANTA.PI3EQX12902AZLEX(CHIPS)':
 C_PATH='@s9s_mb_2u_lib.s9s_mb_2u(sch_1):page136_i50@pure_quanta.pi3eqx12902azle~
x(chips)',
 P_PATH='@s9s_mb_2u_lib.s9s_mb_2u(sch_1):page166_i50@pure_quanta.pi3eqx12902azle~
x(chips)',
 PATH='I50',
 DRAWING='@S9S_MB_2U_LIB.S9S_MB_2U(SCH_1):PAGE136',
 PHYS_PAGE='166',
 XY='(-1300,1525)',
 ROT='0',
 VER='1',
 CDS_LIB='pure_quanta',
 CDS_PART_NAME='PI3EQX12902AZLEX-PI3EQX12902AZA',
 PART_TYPE='SMLF',
 MATERIAL='IC',
 ROOM='PCIE REDRIVER1_BOM1',
 VALUE='PI3EQX12902AZLEX',
 PRIM_FILE='./archive_libs/logical/pi3eqx12902azlex/chips/chips.prt';

PART_NAME
 U239 '74LVC1G126SE7-74LVC1G126SE-7,SA':;

SECTION_NUMBER 1
 '@S9S_MB_2U_LIB.S9S_MB_2U(SCH_1):PAGE182_I315@PURE_QUANTA.74LVC1G126SE7(CHIPS)':
 C_PATH='@s9s_mb_2u_lib.s9s_mb_2u(sch_1):page182_i315@pure_quanta.\74lvc1g126se7~
\(chips)',
 P_PATH='@s9s_mb_2u_lib.s9s_mb_2u(sch_1):page190_i315@pure_quanta.\74lvc1g126se7~
\(chips)',
 PATH='I315',
 DRAWING='@S9S_MB_2U_LIB.S9S_MB_2U(SCH_1):PAGE182',
 PHYS_PAGE='190',
 XY='(9350,1175)',
 ROT='0',
 VER='1',
 CDS_LIB='pure_quanta',
 CDS_PART_NAME='74LVC1G126SE7-74LVC1G126SE-7,SA',
 PART_TYPE='SMLF',
 MATERIAL='IC',
 VALUE='74LVC1G126SE-7',
 PRIM_FILE='./archive_libs/logical/74lvc1g126se7/chips/chips.prt';

PART_NAME
 U240 '74LVC2G08DP-74LVC2G08DP,SMLF,IA':;

SECTION_NUMBER 1
 '@S9S_MB_2U_LIB.S9S_MB_2U(SCH_1):PAGE170_I11@PURE_QUANTA.74LVC2G08DP(CHIPS)':
 C_PATH='@s9s_mb_2u_lib.s9s_mb_2u(sch_1):page170_i11@pure_quanta.\74lvc2g08dp\(c~
hips)',
 P_PATH='@s9s_mb_2u_lib.s9s_mb_2u(sch_1):page165_i11@pure_quanta.\74lvc2g08dp\(c~
hips)',
 PATH='I11',
 DRAWING='@S9S_MB_2U_LIB.S9S_MB_2U(SCH_1):PAGE170',
 PHYS_PAGE='165',
 XY='(-1725,2850)',
 ROT='0',
 VER='1',
 CDS_LIB='pure_quanta',
 CDS_PART_NAME='74LVC2G08DP-74LVC2G08DP,SMLF,IA',
 PART_TYPE='SMLF',
 MATERIAL='IC',
 VALUE='74LVC2G08DP',
 PRIM_FILE='./archive_libs/logical/74lvc2g08dp/chips/chips.prt';

SECTION_NUMBER 2
 '@S9S_MB_2U_LIB.S9S_MB_2U(SCH_1):PAGE170_I12@PURE_QUANTA.74LVC2G08DP(CHIPS)':
 C_PATH='@s9s_mb_2u_lib.s9s_mb_2u(sch_1):page170_i12@pure_quanta.\74lvc2g08dp\(c~
hips)',
 P_PATH='@s9s_mb_2u_lib.s9s_mb_2u(sch_1):page165_i12@pure_quanta.\74lvc2g08dp\(c~
hips)',
 PATH='I12',
 DRAWING='@S9S_MB_2U_LIB.S9S_MB_2U(SCH_1):PAGE170',
 PHYS_PAGE='165',
 XY='(-1725,1950)',
 ROT='0',
 VER='2',
 CDS_LIB='pure_quanta',
 CDS_PART_NAME='74LVC2G08DP-74LVC2G08DP,SMLF,IA',
 PART_TYPE='SMLF',
 MATERIAL='IC',
 VALUE='74LVC2G08DP',
 PRIM_FILE='./archive_libs/logical/74lvc2g08dp/chips/chips.prt';

PART_NAME
 U241 '74LVC2G08DP-74LVC2G08DP,SMLF,IA':;

SECTION_NUMBER 1
 '@S9S_MB_2U_LIB.S9S_MB_2U(SCH_1):PAGE170_I1@PURE_QUANTA.74LVC2G08DP(CHIPS)':
 C_PATH='@s9s_mb_2u_lib.s9s_mb_2u(sch_1):page170_i1@pure_quanta.\74lvc2g08dp\(ch~
ips)',
 P_PATH='@s9s_mb_2u_lib.s9s_mb_2u(sch_1):page165_i1@pure_quanta.\74lvc2g08dp\(ch~
ips)',
 PATH='I1',
 DRAWING='@S9S_MB_2U_LIB.S9S_MB_2U(SCH_1):PAGE170',
 PHYS_PAGE='165',
 XY='(-1725,750)',
 ROT='0',
 VER='1',
 CDS_LIB='pure_quanta',
 CDS_PART_NAME='74LVC2G08DP-74LVC2G08DP,SMLF,IA',
 PART_TYPE='SMLF',
 MATERIAL='IC',
 VALUE='74LVC2G08DP',
 PRIM_FILE='./archive_libs/logical/74lvc2g08dp/chips/chips.prt';

SECTION_NUMBER 2
 '@S9S_MB_2U_LIB.S9S_MB_2U(SCH_1):PAGE170_I2@PURE_QUANTA.74LVC2G08DP(CHIPS)':
 C_PATH='@s9s_mb_2u_lib.s9s_mb_2u(sch_1):page170_i2@pure_quanta.\74lvc2g08dp\(ch~
ips)',
 P_PATH='@s9s_mb_2u_lib.s9s_mb_2u(sch_1):page165_i2@pure_quanta.\74lvc2g08dp\(ch~
ips)',
 PATH='I2',
 DRAWING='@S9S_MB_2U_LIB.S9S_MB_2U(SCH_1):PAGE170',
 PHYS_PAGE='165',
 XY='(-1725,-150)',
 ROT='0',
 VER='2',
 CDS_LIB='pure_quanta',
 CDS_PART_NAME='74LVC2G08DP-74LVC2G08DP,SMLF,IA',
 PART_TYPE='SMLF',
 MATERIAL='IC',
 VALUE='74LVC2G08DP',
 PRIM_FILE='./archive_libs/logical/74lvc2g08dp/chips/chips.prt';

PART_NAME
 U242 '74LVC2G08DP-74LVC2G08DP,SMLF,IA':;

SECTION_NUMBER 1
 '@S9S_MB_2U_LIB.S9S_MB_2U(SCH_1):PAGE170_I13@PURE_QUANTA.74LVC2G08DP(CHIPS)':
 C_PATH='@s9s_mb_2u_lib.s9s_mb_2u(sch_1):page170_i13@pure_quanta.\74lvc2g08dp\(c~
hips)',
 P_PATH='@s9s_mb_2u_lib.s9s_mb_2u(sch_1):page165_i13@pure_quanta.\74lvc2g08dp\(c~
hips)',
 PATH='I13',
 DRAWING='@S9S_MB_2U_LIB.S9S_MB_2U(SCH_1):PAGE170',
 PHYS_PAGE='165',
 XY='(-400,2400)',
 ROT='0',
 VER='1',
 CDS_LIB='pure_quanta',
 CDS_PART_NAME='74LVC2G08DP-74LVC2G08DP,SMLF,IA',
 PART_TYPE='SMLF',
 MATERIAL='IC',
 VALUE='74LVC2G08DP',
 PRIM_FILE='./archive_libs/logical/74lvc2g08dp/chips/chips.prt';

SECTION_NUMBER 2
 '@S9S_MB_2U_LIB.S9S_MB_2U(SCH_1):PAGE170_I14@PURE_QUANTA.74LVC2G08DP(CHIPS)':
 C_PATH='@s9s_mb_2u_lib.s9s_mb_2u(sch_1):page170_i14@pure_quanta.\74lvc2g08dp\(c~
hips)',
 P_PATH='@s9s_mb_2u_lib.s9s_mb_2u(sch_1):page165_i14@pure_quanta.\74lvc2g08dp\(c~
hips)',
 PATH='I14',
 DRAWING='@S9S_MB_2U_LIB.S9S_MB_2U(SCH_1):PAGE170',
 PHYS_PAGE='165',
 XY='(-400,275)',
 ROT='0',
 VER='2',
 CDS_LIB='pure_quanta',
 CDS_PART_NAME='74LVC2G08DP-74LVC2G08DP,SMLF,IA',
 PART_TYPE='SMLF',
 MATERIAL='IC',
 VALUE='74LVC2G08DP',
 PRIM_FILE='./archive_libs/logical/74lvc2g08dp/chips/chips.prt';

PART_NAME
 U243 'NC7SB3157_SMLF-NC7SB3157P6X,NCB':;

SECTION_NUMBER 1
 '@S9S_MB_2U_LIB.S9S_MB_2U(SCH_1):PAGE170_I15@PURE_QUANTA.NC7SB3157(CHIPS)':
 C_PATH='@s9s_mb_2u_lib.s9s_mb_2u(sch_1):page170_i15@pure_quanta.nc7sb3157(chips~
)',
 P_PATH='@s9s_mb_2u_lib.s9s_mb_2u(sch_1):page165_i15@pure_quanta.nc7sb3157(chips~
)',
 PATH='I15',
 DRAWING='@S9S_MB_2U_LIB.S9S_MB_2U(SCH_1):PAGE170',
 PHYS_PAGE='165',
 XY='(2025,2400)',
 ROT='2',
 VER='1',
 PACK_TYPE='SMLF',
 CDS_LIB='pure_quanta',
 CDS_PART_NAME='NC7SB3157_SMLF-NC7SB3157P6X,NCB',
 MANUF_PN='NC7SB3157P6X',
 MATERIAL='EMPTY',
 VALUE='NC7SB3157P6X',
 PRIM_FILE='./archive_libs/logical/nc7sb3157/chips/chips.prt';

PART_NAME
 U244 'NC7SB3157_SMLF-NC7SB3157P6X,NCB':;

SECTION_NUMBER 1
 '@S9S_MB_2U_LIB.S9S_MB_2U(SCH_1):PAGE170_I16@PURE_QUANTA.NC7SB3157(CHIPS)':
 C_PATH='@s9s_mb_2u_lib.s9s_mb_2u(sch_1):page170_i16@pure_quanta.nc7sb3157(chips~
)',
 P_PATH='@s9s_mb_2u_lib.s9s_mb_2u(sch_1):page165_i16@pure_quanta.nc7sb3157(chips~
)',
 PATH='I16',
 DRAWING='@S9S_MB_2U_LIB.S9S_MB_2U(SCH_1):PAGE170',
 PHYS_PAGE='165',
 XY='(2025,1550)',
 ROT='2',
 VER='1',
 PACK_TYPE='SMLF',
 CDS_LIB='pure_quanta',
 CDS_PART_NAME='NC7SB3157_SMLF-NC7SB3157P6X,NCB',
 MANUF_PN='NC7SB3157P6X',
 MATERIAL='EMPTY',
 VALUE='NC7SB3157P6X',
 PRIM_FILE='./archive_libs/logical/nc7sb3157/chips/chips.prt';

PART_NAME
 U245 'NC7SB3157_SMLF-NC7SB3157P6X,NCB':;

SECTION_NUMBER 1
 '@S9S_MB_2U_LIB.S9S_MB_2U(SCH_1):PAGE170_I18@PURE_QUANTA.NC7SB3157(CHIPS)':
 C_PATH='@s9s_mb_2u_lib.s9s_mb_2u(sch_1):page170_i18@pure_quanta.nc7sb3157(chips~
)',
 P_PATH='@s9s_mb_2u_lib.s9s_mb_2u(sch_1):page165_i18@pure_quanta.nc7sb3157(chips~
)',
 PATH='I18',
 DRAWING='@S9S_MB_2U_LIB.S9S_MB_2U(SCH_1):PAGE170',
 PHYS_PAGE='165',
 XY='(2175,-575)',
 ROT='2',
 VER='1',
 PACK_TYPE='SMLF',
 CDS_LIB='pure_quanta',
 CDS_PART_NAME='NC7SB3157_SMLF-NC7SB3157P6X,NCB',
 MANUF_PN='NC7SB3157P6X',
 MATERIAL='EMPTY',
 VALUE='NC7SB3157P6X',
 PRIM_FILE='./archive_libs/logical/nc7sb3157/chips/chips.prt';

PART_NAME
 U246 'NC7SB3157_SMLF-NC7SB3157P6X,NCB':;

SECTION_NUMBER 1
 '@S9S_MB_2U_LIB.S9S_MB_2U(SCH_1):PAGE170_I17@PURE_QUANTA.NC7SB3157(CHIPS)':
 C_PATH='@s9s_mb_2u_lib.s9s_mb_2u(sch_1):page170_i17@pure_quanta.nc7sb3157(chips~
)',
 P_PATH='@s9s_mb_2u_lib.s9s_mb_2u(sch_1):page165_i17@pure_quanta.nc7sb3157(chips~
)',
 PATH='I17',
 DRAWING='@S9S_MB_2U_LIB.S9S_MB_2U(SCH_1):PAGE170',
 PHYS_PAGE='165',
 XY='(2200,275)',
 ROT='2',
 VER='1',
 PACK_TYPE='SMLF',
 CDS_LIB='pure_quanta',
 CDS_PART_NAME='NC7SB3157_SMLF-NC7SB3157P6X,NCB',
 MANUF_PN='NC7SB3157P6X',
 MATERIAL='EMPTY',
 VALUE='NC7SB3157P6X',
 PRIM_FILE='./archive_libs/logical/nc7sb3157/chips/chips.prt';

PART_NAME
 U247 '9FGL0251DKILFT-9FGL0251DKILFT,A':;

SECTION_NUMBER 1
 '@S9S_MB_2U_LIB.S9S_MB_2U(SCH_1):PAGE201_I167@PURE_QUANTA.9FGL0251DKILFT(CHIPS)':
 C_PATH='@s9s_mb_2u_lib.s9s_mb_2u(sch_1):page201_i167@pure_quanta.\9fgl0251dkilf~
t\(chips)',
 P_PATH='@s9s_mb_2u_lib.s9s_mb_2u(sch_1):page212_i167@pure_quanta.\9fgl0251dkilf~
t\(chips)',
 PATH='I167',
 DRAWING='@S9S_MB_2U_LIB.S9S_MB_2U(SCH_1):PAGE201',
 PHYS_PAGE='212',
 XY='(-1400,3500)',
 ROT='0',
 VER='1',
 LOCATION='U247',
 CDS_LIB='pure_quanta',
 CDS_PART_NAME='9FGL0251DKILFT-9FGL0251DKILFT,A',
 PART_TYPE='SMLF',
 MATERIAL='IC',
 VALUE='9FGL0251DKILFT',
 PRIM_FILE='./archive_libs/logical/9fgl0251dkilft/chips/chips.prt';

PART_NAME
 U248 '74LVC1G32GW_SMLF-74LVC1G32GW,IA':;

SECTION_NUMBER 1
 '@S9S_MB_2U_LIB.S9S_MB_2U(SCH_1):PAGE201_I158@PURE_QUANTA.74LVC1G32GW(CHIPS)':
 C_PATH='@s9s_mb_2u_lib.s9s_mb_2u(sch_1):page201_i158@pure_quanta.\74lvc1g32gw\(~
chips)',
 P_PATH='@s9s_mb_2u_lib.s9s_mb_2u(sch_1):page212_i158@pure_quanta.\74lvc1g32gw\(~
chips)',
 PATH='I158',
 DRAWING='@S9S_MB_2U_LIB.S9S_MB_2U(SCH_1):PAGE201',
 PHYS_PAGE='212',
 XY='(-2225,1250)',
 ROT='0',
 VER='1',
 PACK_TYPE='SMLF',
 LOCATION='U248',
 CDS_LIB='pure_quanta',
 CDS_PART_NAME='74LVC1G32GW_SMLF-74LVC1G32GW,IA',
 MATERIAL='IC',
 VALUE='74LVC1G32GW',
 PRIM_FILE='./archive_libs/logical/74lvc1g32gw/chips/chips.prt';

PART_NAME
 U249 'LCMXO3LF9400C5BG484C-LCMXO3LF-A':;

SECTION_NUMBER 1
 '@S9S_MB_2U_LIB.S9S_MB_2U(SCH_1):PAGE311_I33@PURE_QUANTA.LCMXO3LF9400C5BG484C(CHIPS)':
 C_PATH='@s9s_mb_2u_lib.s9s_mb_2u(sch_1):page311_i33@pure_quanta.lcmxo3lf9400c5b~
g484c(chips)',
 P_PATH='@s9s_mb_2u_lib.s9s_mb_2u(sch_1):page216_i33@pure_quanta.lcmxo3lf9400c5b~
g484c(chips)',
 PATH='I33',
 DRAWING='@S9S_MB_2U_LIB.S9S_MB_2U(SCH_1):PAGE311',
 PHYS_PAGE='216',
 XY='(-875,2075)',
 ROT='0',
 VER='1',
 CDS_LIB='pure_quanta',
 CDS_PART_NAME='LCMXO3LF9400C5BG484C-LCMXO3LF-A',
 PART_TYPE='SMLF',
 MATERIAL='IC',
 VALUE='LCMXO3LF-9400C-5BG484C',
 PRIM_FILE='./archive_libs/logical/lcmxo3lf9400c5bg484c/chips/chips.prt';

SECTION_NUMBER 2
 '@S9S_MB_2U_LIB.S9S_MB_2U(SCH_1):PAGE312_I1@PURE_QUANTA.LCMXO3LF9400C5BG484C(CHIPS)':
 C_PATH='@s9s_mb_2u_lib.s9s_mb_2u(sch_1):page312_i1@pure_quanta.lcmxo3lf9400c5bg~
484c(chips)',
 P_PATH='@s9s_mb_2u_lib.s9s_mb_2u(sch_1):page215_i1@pure_quanta.lcmxo3lf9400c5bg~
484c(chips)',
 PATH='I1',
 DRAWING='@S9S_MB_2U_LIB.S9S_MB_2U(SCH_1):PAGE312',
 PHYS_PAGE='215',
 XY='(-2000,2525)',
 ROT='0',
 VER='2',
 CDS_LIB='pure_quanta',
 CDS_PART_NAME='LCMXO3LF9400C5BG484C-LCMXO3LF-A',
 PART_TYPE='SMLF',
 MATERIAL='IC',
 VALUE='LCMXO3LF-9400C-5BG484C',
 PRIM_FILE='./archive_libs/logical/lcmxo3lf9400c5bg484c/chips/chips.prt';

SECTION_NUMBER 3
 '@S9S_MB_2U_LIB.S9S_MB_2U(SCH_1):PAGE314_I188@PURE_QUANTA.LCMXO3LF9400C5BG484C(CHIPS)':
 C_PATH='@s9s_mb_2u_lib.s9s_mb_2u(sch_1):page314_i188@pure_quanta.lcmxo3lf9400c5~
bg484c(chips)',
 P_PATH='@s9s_mb_2u_lib.s9s_mb_2u(sch_1):page213_i188@pure_quanta.lcmxo3lf9400c5~
bg484c(chips)',
 PATH='I188',
 DRAWING='@S9S_MB_2U_LIB.S9S_MB_2U(SCH_1):PAGE314',
 PHYS_PAGE='213',
 XY='(800,2675)',
 ROT='0',
 VER='3',
 CDS_LIB='pure_quanta',
 CDS_PART_NAME='LCMXO3LF9400C5BG484C-LCMXO3LF-A',
 PART_TYPE='SMLF',
 MATERIAL='IC',
 VALUE='LCMXO3LF-9400C-5BG484C',
 PRIM_FILE='./archive_libs/logical/lcmxo3lf9400c5bg484c/chips/chips.prt';

SECTION_NUMBER 4
 '@S9S_MB_2U_LIB.S9S_MB_2U(SCH_1):PAGE311_I70@PURE_QUANTA.LCMXO3LF9400C5BG484C(CHIPS)':
 C_PATH='@s9s_mb_2u_lib.s9s_mb_2u(sch_1):page311_i70@pure_quanta.lcmxo3lf9400c5b~
g484c(chips)',
 P_PATH='@s9s_mb_2u_lib.s9s_mb_2u(sch_1):page216_i70@pure_quanta.lcmxo3lf9400c5b~
g484c(chips)',
 PATH='I70',
 DRAWING='@S9S_MB_2U_LIB.S9S_MB_2U(SCH_1):PAGE311',
 PHYS_PAGE='216',
 XY='(-925,-175)',
 ROT='0',
 VER='4',
 CDS_LIB='pure_quanta',
 CDS_PART_NAME='LCMXO3LF9400C5BG484C-LCMXO3LF-A',
 PART_TYPE='SMLF',
 MATERIAL='IC',
 VALUE='LCMXO3LF-9400C-5BG484C',
 PRIM_FILE='./archive_libs/logical/lcmxo3lf9400c5bg484c/chips/chips.prt';

SECTION_NUMBER 5
 '@S9S_MB_2U_LIB.S9S_MB_2U(SCH_1):PAGE202_I102@PURE_QUANTA.LCMXO3LF9400C5BG484C(CHIPS)':
 C_PATH='@s9s_mb_2u_lib.s9s_mb_2u(sch_1):page202_i102@pure_quanta.lcmxo3lf9400c5~
bg484c(chips)',
 P_PATH='@s9s_mb_2u_lib.s9s_mb_2u(sch_1):page217_i102@pure_quanta.lcmxo3lf9400c5~
bg484c(chips)',
 PATH='I102',
 DRAWING='@S9S_MB_2U_LIB.S9S_MB_2U(SCH_1):PAGE202',
 PHYS_PAGE='217',
 XY='(-4950,1400)',
 ROT='0',
 VER='5',
 CDS_LIB='pure_quanta',
 CDS_PART_NAME='LCMXO3LF9400C5BG484C-LCMXO3LF-A',
 PART_TYPE='SMLF',
 MATERIAL='IC',
 VALUE='LCMXO3LF-9400C-5BG484C',
 PRIM_FILE='./archive_libs/logical/lcmxo3lf9400c5bg484c/chips/chips.prt';

SECTION_NUMBER 6
 '@S9S_MB_2U_LIB.S9S_MB_2U(SCH_1):PAGE202_I1@PURE_QUANTA.LCMXO3LF9400C5BG484C(CHIPS)':
 C_PATH='@s9s_mb_2u_lib.s9s_mb_2u(sch_1):page202_i1@pure_quanta.lcmxo3lf9400c5bg~
484c(chips)',
 P_PATH='@s9s_mb_2u_lib.s9s_mb_2u(sch_1):page217_i1@pure_quanta.lcmxo3lf9400c5bg~
484c(chips)',
 PATH='I1',
 DRAWING='@S9S_MB_2U_LIB.S9S_MB_2U(SCH_1):PAGE202',
 PHYS_PAGE='217',
 XY='(-2975,1100)',
 ROT='0',
 VER='6',
 CDS_LIB='pure_quanta',
 CDS_PART_NAME='LCMXO3LF9400C5BG484C-LCMXO3LF-A',
 PART_TYPE='SMLF',
 MATERIAL='IC',
 VALUE='LCMXO3LF-9400C-5BG484C',
 PRIM_FILE='./archive_libs/logical/lcmxo3lf9400c5bg484c/chips/chips.prt';

SECTION_NUMBER 7
 '@S9S_MB_2U_LIB.S9S_MB_2U(SCH_1):PAGE313_I1@PURE_QUANTA.LCMXO3LF9400C5BG484C(CHIPS)':
 C_PATH='@s9s_mb_2u_lib.s9s_mb_2u(sch_1):page313_i1@pure_quanta.lcmxo3lf9400c5bg~
484c(chips)',
 P_PATH='@s9s_mb_2u_lib.s9s_mb_2u(sch_1):page214_i1@pure_quanta.lcmxo3lf9400c5bg~
484c(chips)',
 PATH='I1',
 DRAWING='@S9S_MB_2U_LIB.S9S_MB_2U(SCH_1):PAGE313',
 PHYS_PAGE='214',
 XY='(575,500)',
 ROT='0',
 VER='7',
 CDS_LIB='pure_quanta',
 CDS_PART_NAME='LCMXO3LF9400C5BG484C-LCMXO3LF-A',
 PART_TYPE='SMLF',
 MATERIAL='IC',
 VALUE='LCMXO3LF-9400C-5BG484C',
 PRIM_FILE='./archive_libs/logical/lcmxo3lf9400c5bg484c/chips/chips.prt';

PART_NAME
 U252 '74LVC2G17GW-74LVC2G17GW,SMLF,IA':;

SECTION_NUMBER 1
 '@S9S_MB_2U_LIB.S9S_MB_2U(SCH_1):PAGE160_I153@PURE_QUANTA.74LVC2G17GW(CHIPS)':
 C_PATH='@s9s_mb_2u_lib.s9s_mb_2u(sch_1):page160_i153@pure_quanta.\74lvc2g17gw\(~
chips)',
 P_PATH='@s9s_mb_2u_lib.s9s_mb_2u(sch_1):page149_i153@pure_quanta.\74lvc2g17gw\(~
chips)',
 PATH='I153',
 DRAWING='@S9S_MB_2U_LIB.S9S_MB_2U(SCH_1):PAGE160',
 PHYS_PAGE='149',
 XY='(-6250,1575)',
 ROT='0',
 VER='1',
 CDS_LIB='pure_quanta',
 CDS_PART_NAME='74LVC2G17GW-74LVC2G17GW,SMLF,IA',
 PART_TYPE='SMLF',
 MATERIAL='IC',
 VALUE='74LVC2G17GW',
 PRIM_FILE='./archive_libs/logical/74lvc2g17gw/chips/chips.prt';

PART_NAME
 U253 '74LVC2G17GW-74LVC2G17GW,SMLF,IA':;

SECTION_NUMBER 1
 '@S9S_MB_2U_LIB.S9S_MB_2U(SCH_1):PAGE160_I26@PURE_QUANTA.74LVC2G17GW(CHIPS)':
 C_PATH='@s9s_mb_2u_lib.s9s_mb_2u(sch_1):page160_i26@pure_quanta.\74lvc2g17gw\(c~
hips)',
 P_PATH='@s9s_mb_2u_lib.s9s_mb_2u(sch_1):page149_i26@pure_quanta.\74lvc2g17gw\(c~
hips)',
 PATH='I26',
 DRAWING='@S9S_MB_2U_LIB.S9S_MB_2U(SCH_1):PAGE160',
 PHYS_PAGE='149',
 XY='(-6125,3575)',
 ROT='0',
 VER='1',
 CDS_LIB='pure_quanta',
 CDS_PART_NAME='74LVC2G17GW-74LVC2G17GW,SMLF,IA',
 PART_TYPE='SMLF',
 MATERIAL='IC',
 VALUE='74LVC2G17GW',
 PRIM_FILE='./archive_libs/logical/74lvc2g17gw/chips/chips.prt';

PART_NAME
 U255 '74LVC2G07DW7-74LVC2G07DW-7,SMLA':;

SECTION_NUMBER 1
 '@S9S_MB_2U_LIB.S9S_MB_2U(SCH_1):PAGE296_I16@PURE_QUANTA.74LVC2G07DW7(CHIPS)':
 C_PATH='@s9s_mb_2u_lib.s9s_mb_2u(sch_1):page296_i16@pure_quanta.\74lvc2g07dw7\(~
chips)',
 P_PATH='@s9s_mb_2u_lib.s9s_mb_2u(sch_1):page150_i16@pure_quanta.\74lvc2g07dw7\(~
chips)',
 PATH='I16',
 DRAWING='@S9S_MB_2U_LIB.S9S_MB_2U(SCH_1):PAGE296',
 PHYS_PAGE='150',
 XY='(775,3750)',
 ROT='0',
 VER='1',
 CDS_LIB='pure_quanta',
 CDS_PART_NAME='74LVC2G07DW7-74LVC2G07DW-7,SMLA',
 PART_TYPE='SMLF',
 MATERIAL='IC',
 VALUE='74LVC2G07DW-7',
 PRIM_FILE='./archive_libs/logical/74lvc2g07dw7/chips/chips.prt';

PART_NAME
 U256 '74LVC2G17GW-74LVC2G17GW,SMLF,IA':;

SECTION_NUMBER 1
 '@S9S_MB_2U_LIB.S9S_MB_2U(SCH_1):PAGE160_I173@PURE_QUANTA.74LVC2G17GW(CHIPS)':
 C_PATH='@s9s_mb_2u_lib.s9s_mb_2u(sch_1):page160_i173@pure_quanta.\74lvc2g17gw\(~
chips)',
 P_PATH='@s9s_mb_2u_lib.s9s_mb_2u(sch_1):page149_i173@pure_quanta.\74lvc2g17gw\(~
chips)',
 PATH='I173',
 DRAWING='@S9S_MB_2U_LIB.S9S_MB_2U(SCH_1):PAGE160',
 PHYS_PAGE='149',
 XY='(-6325,-275)',
 ROT='0',
 VER='1',
 CDS_LIB='pure_quanta',
 CDS_PART_NAME='74LVC2G17GW-74LVC2G17GW,SMLF,IA',
 PART_TYPE='SMLF',
 MATERIAL='IC',
 VALUE='74LVC2G17GW',
 PRIM_FILE='./archive_libs/logical/74lvc2g17gw/chips/chips.prt';

PART_NAME
 U257 '74LVC2G07DW7-74LVC2G07DW-7,SMLA':;

SECTION_NUMBER 1
 '@S9S_MB_2U_LIB.S9S_MB_2U(SCH_1):PAGE296_I50@PURE_QUANTA.74LVC2G07DW7(CHIPS)':
 C_PATH='@s9s_mb_2u_lib.s9s_mb_2u(sch_1):page296_i50@pure_quanta.\74lvc2g07dw7\(~
chips)',
 P_PATH='@s9s_mb_2u_lib.s9s_mb_2u(sch_1):page150_i50@pure_quanta.\74lvc2g07dw7\(~
chips)',
 PATH='I50',
 DRAWING='@S9S_MB_2U_LIB.S9S_MB_2U(SCH_1):PAGE296',
 PHYS_PAGE='150',
 XY='(775,1250)',
 ROT='0',
 VER='1',
 CDS_LIB='pure_quanta',
 CDS_PART_NAME='74LVC2G07DW7-74LVC2G07DW-7,SMLA',
 PART_TYPE='SMLF',
 MATERIAL='IC',
 VALUE='74LVC2G07DW-7',
 PRIM_FILE='./archive_libs/logical/74lvc2g07dw7/chips/chips.prt';

PART_NAME
 U259 'SN74LVC2G07DCKR_SMLF-SN74LVC2GA':;

SECTION_NUMBER 1
 '@S9S_MB_2U_LIB.S9S_MB_2U(SCH_1):PAGE182_I327@PURE_QUANTA.SN74LVC2G07DCKR(CHIPS)':
 C_PATH='@s9s_mb_2u_lib.s9s_mb_2u(sch_1):page182_i327@pure_quanta.sn74lvc2g07dck~
r(chips)',
 P_PATH='@s9s_mb_2u_lib.s9s_mb_2u(sch_1):page190_i327@pure_quanta.sn74lvc2g07dck~
r(chips)',
 PATH='I327',
 DRAWING='@S9S_MB_2U_LIB.S9S_MB_2U(SCH_1):PAGE182',
 PHYS_PAGE='190',
 XY='(7675,-400)',
 ROT='0',
 VER='1',
 PACK_TYPE='SMLF',
 CDS_LIB='pure_quanta',
 CDS_PART_NAME='SN74LVC2G07DCKR_SMLF-SN74LVC2GA',
 MATERIAL='IC',
 VALUE='SN74LVC2G07DCKR',
 PRIM_FILE='./archive_libs/logical/sn74lvc2g07dckr/chips/chips.prt';

PART_NAME
 U263 'INA230AIRGTR-INA230AIRGTR,SMLFB':;

SECTION_NUMBER 1
 '@S9S_MB_2U_LIB.S9S_MB_2U(SCH_1):PAGE163_I94@PURE_QUANTA.INA230AIRGTR(CHIPS)':
 C_PATH='@s9s_mb_2u_lib.s9s_mb_2u(sch_1):page163_i94@pure_quanta.ina230airgtr(ch~
ips)',
 P_PATH='@s9s_mb_2u_lib.s9s_mb_2u(sch_1):page172_i94@pure_quanta.ina230airgtr(ch~
ips)',
 PATH='I94',
 DRAWING='@S9S_MB_2U_LIB.S9S_MB_2U(SCH_1):PAGE163',
 PHYS_PAGE='172',
 XY='(1725,125)',
 ROT='0',
 VER='1',
 CDS_LIB='pure_quanta',
 CDS_PART_NAME='INA230AIRGTR-INA230AIRGTR,SMLFA',
 PART_TYPE='SMLF',
 MATERIAL='IC',
 VALUE='INA230AIRGTR',
 PRIM_FILE='./archive_libs/logical/ina230airgtr/chips/chips.prt';

PART_NAME
 U264 'INA230AIRGTR-INA230AIRGTR,SMLFB':;

SECTION_NUMBER 1
 '@S9S_MB_2U_LIB.S9S_MB_2U(SCH_1):PAGE163_I46@PURE_QUANTA.INA230AIRGTR(CHIPS)':
 C_PATH='@s9s_mb_2u_lib.s9s_mb_2u(sch_1):page163_i46@pure_quanta.ina230airgtr(ch~
ips)',
 P_PATH='@s9s_mb_2u_lib.s9s_mb_2u(sch_1):page172_i46@pure_quanta.ina230airgtr(ch~
ips)',
 PATH='I46',
 DRAWING='@S9S_MB_2U_LIB.S9S_MB_2U(SCH_1):PAGE163',
 PHYS_PAGE='172',
 XY='(1300,-1975)',
 ROT='0',
 VER='1',
 CDS_LIB='pure_quanta',
 CDS_PART_NAME='INA230AIRGTR-INA230AIRGTR,SMLFA',
 PART_TYPE='SMLF',
 MATERIAL='IC',
 VALUE='INA230AIRGTR',
 PRIM_FILE='./archive_libs/logical/ina230airgtr/chips/chips.prt';

PART_NAME
 U265 'INA230AIRGTR-INA230AIRGTR,SMLFB':;

SECTION_NUMBER 1
 '@S9S_MB_2U_LIB.S9S_MB_2U(SCH_1):PAGE163_I69@PURE_QUANTA.INA230AIRGTR(CHIPS)':
 C_PATH='@s9s_mb_2u_lib.s9s_mb_2u(sch_1):page163_i69@pure_quanta.ina230airgtr(ch~
ips)',
 P_PATH='@s9s_mb_2u_lib.s9s_mb_2u(sch_1):page172_i69@pure_quanta.ina230airgtr(ch~
ips)',
 PATH='I69',
 DRAWING='@S9S_MB_2U_LIB.S9S_MB_2U(SCH_1):PAGE163',
 PHYS_PAGE='172',
 XY='(1425,-4125)',
 ROT='0',
 VER='1',
 CDS_LIB='pure_quanta',
 CDS_PART_NAME='INA230AIRGTR-INA230AIRGTR,SMLFA',
 PART_TYPE='SMLF',
 MATERIAL='IC',
 VALUE='INA230AIRGTR',
 PRIM_FILE='./archive_libs/logical/ina230airgtr/chips/chips.prt';

PART_NAME
 U266 'INA230AIRGTR-INA230AIRGTR,SMLFB':;

SECTION_NUMBER 1
 '@S9S_MB_2U_LIB.S9S_MB_2U(SCH_1):PAGE295_I30@PURE_QUANTA.INA230AIRGTR(CHIPS)':
 C_PATH='@s9s_mb_2u_lib.s9s_mb_2u(sch_1):page295_i30@pure_quanta.ina230airgtr(ch~
ips)',
 P_PATH='@s9s_mb_2u_lib.s9s_mb_2u(sch_1):page171_i30@pure_quanta.ina230airgtr(ch~
ips)',
 PATH='I30',
 DRAWING='@S9S_MB_2U_LIB.S9S_MB_2U(SCH_1):PAGE295',
 PHYS_PAGE='171',
 XY='(2875,3075)',
 ROT='0',
 VER='1',
 CDS_LIB='pure_quanta',
 CDS_PART_NAME='INA230AIRGTR-INA230AIRGTR,SMLFA',
 PART_TYPE='SMLF',
 MATERIAL='IC',
 VALUE='INA230AIRGTR',
 PRIM_FILE='./archive_libs/logical/ina230airgtr/chips/chips.prt';

PART_NAME
 U268 'GL852GOHY60-GL852G-OHY60,SMLF,A':
 ROOM='USB1_BOM1';

SECTION_NUMBER 1
 '@S9S_MB_2U_LIB.S9S_MB_2U(SCH_1):PAGE155_I100@PURE_QUANTA.GL852GOHY60(CHIPS)':
 C_PATH='@s9s_mb_2u_lib.s9s_mb_2u(sch_1):page155_i100@pure_quanta.gl852gohy60(ch~
ips)',
 P_PATH='@s9s_mb_2u_lib.s9s_mb_2u(sch_1):page152_i100@pure_quanta.gl852gohy60(ch~
ips)',
 PATH='I100',
 DRAWING='@S9S_MB_2U_LIB.S9S_MB_2U(SCH_1):PAGE155',
 PHYS_PAGE='152',
 XY='(125,3825)',
 ROT='0',
 VER='1',
 CDS_LIB='pure_quanta',
 CDS_PART_NAME='GL852GOHY60-GL852G-OHY60,SMLF,A',
 PART_TYPE='SMLF',
 MATERIAL='IC',
 ROOM='USB1_BOM1',
 VALUE='GL852G-OHY60',
 PRIM_FILE='./archive_libs/logical/gl852gohy60/chips/chips.prt';

PART_NAME
 U269 'ADC128D818CIMTXNOPB-ADC128D818A':
 ROOM='ADC1_BOM2';

SECTION_NUMBER 1
 '@S9S_MB_2U_LIB.S9S_MB_2U(SCH_1):PAGE239_I103@PURE_QUANTA.ADC128D818CIMTXNOPB(CHIPS)':
 C_PATH='@s9s_mb_2u_lib.s9s_mb_2u(sch_1):page239_i103@pure_quanta.adc128d818cimt~
xnopb(chips)',
 P_PATH='@s9s_mb_2u_lib.s9s_mb_2u(sch_1):page250_i103@pure_quanta.adc128d818cimt~
xnopb(chips)',
 PATH='I103',
 DRAWING='@S9S_MB_2U_LIB.S9S_MB_2U(SCH_1):PAGE239',
 PIN_NAMES_ROTATE='True',
 PHYS_PAGE='250',
 XY='(6275,1300)',
 ROT='0',
 VER='1',
 CDS_LIB='pure_quanta',
 CDS_PART_NAME='ADC128D818CIMTXNOPB-ADC128D818A',
 PART_TYPE='SMLF',
 MATERIAL='IC',
 ROOM='ADC1_BOM2',
 VALUE='ADC128D818CIMTX/NOPB',
 PRIM_FILE='./archive_libs/logical/adc128d818cimtxnopb/chips/chips.prt';

PART_NAME
 U270 'LM75BD-LM75BD,SMLF,IC,AL0075BDA':;

SECTION_NUMBER 1
 '@S9S_MB_2U_LIB.S9S_MB_2U(SCH_1):PAGE161_I164@PURE_QUANTA.LM75BD(CHIPS)':
 C_PATH='@s9s_mb_2u_lib.s9s_mb_2u(sch_1):page161_i164@pure_quanta.lm75bd(chips)',
 P_PATH='@s9s_mb_2u_lib.s9s_mb_2u(sch_1):page170_i164@pure_quanta.lm75bd(chips)',
 PATH='I164',
 DRAWING='@S9S_MB_2U_LIB.S9S_MB_2U(SCH_1):PAGE161',
 PHYS_PAGE='170',
 XY='(2150,1375)',
 ROT='0',
 VER='1',
 LOCATION='U270',
 CDS_LIB='pure_quanta',
 CDS_PART_NAME='LM75BD-LM75BD,SMLF,IC,AL0075BDA',
 PART_TYPE='SMLF',
 MATERIAL='IC',
 VALUE='LM75BD',
 PRIM_FILE='./archive_libs/logical/lm75bd/chips/chips.prt';

PART_NAME
 U271 'LM75BD-LM75BD,SMLF,IC,AL0075BDA':;

SECTION_NUMBER 1
 '@S9S_MB_2U_LIB.S9S_MB_2U(SCH_1):PAGE161_I165@PURE_QUANTA.LM75BD(CHIPS)':
 C_PATH='@s9s_mb_2u_lib.s9s_mb_2u(sch_1):page161_i165@pure_quanta.lm75bd(chips)',
 P_PATH='@s9s_mb_2u_lib.s9s_mb_2u(sch_1):page170_i165@pure_quanta.lm75bd(chips)',
 PATH='I165',
 DRAWING='@S9S_MB_2U_LIB.S9S_MB_2U(SCH_1):PAGE161',
 PHYS_PAGE='170',
 XY='(2100,-100)',
 ROT='0',
 VER='1',
 LOCATION='U271',
 CDS_LIB='pure_quanta',
 CDS_PART_NAME='LM75BD-LM75BD,SMLF,IC,AL0075BDA',
 PART_TYPE='SMLF',
 MATERIAL='IC',
 VALUE='LM75BD',
 PRIM_FILE='./archive_libs/logical/lm75bd/chips/chips.prt';

PART_NAME
 U272 'LM75BD-LM75BD,SMLF,IC,AL0075BDA':;

SECTION_NUMBER 1
 '@S9S_MB_2U_LIB.S9S_MB_2U(SCH_1):PAGE161_I166@PURE_QUANTA.LM75BD(CHIPS)':
 C_PATH='@s9s_mb_2u_lib.s9s_mb_2u(sch_1):page161_i166@pure_quanta.lm75bd(chips)',
 P_PATH='@s9s_mb_2u_lib.s9s_mb_2u(sch_1):page170_i166@pure_quanta.lm75bd(chips)',
 PATH='I166',
 DRAWING='@S9S_MB_2U_LIB.S9S_MB_2U(SCH_1):PAGE161',
 PHYS_PAGE='170',
 XY='(2075,-1575)',
 ROT='0',
 VER='1',
 LOCATION='U272',
 CDS_LIB='pure_quanta',
 CDS_PART_NAME='LM75BD-LM75BD,SMLF,IC,AL0075BDA',
 PART_TYPE='SMLF',
 MATERIAL='IC',
 VALUE='LM75BD',
 PRIM_FILE='./archive_libs/logical/lm75bd/chips/chips.prt';

PART_NAME
 U273 'LM75BD-LM75BD,SMLF,IC,AL0075BDA':;

SECTION_NUMBER 1
 '@S9S_MB_2U_LIB.S9S_MB_2U(SCH_1):PAGE161_I167@PURE_QUANTA.LM75BD(CHIPS)':
 C_PATH='@s9s_mb_2u_lib.s9s_mb_2u(sch_1):page161_i167@pure_quanta.lm75bd(chips)',
 P_PATH='@s9s_mb_2u_lib.s9s_mb_2u(sch_1):page170_i167@pure_quanta.lm75bd(chips)',
 PATH='I167',
 DRAWING='@S9S_MB_2U_LIB.S9S_MB_2U(SCH_1):PAGE161',
 PHYS_PAGE='170',
 XY='(2025,-3050)',
 ROT='0',
 VER='1',
 LOCATION='U273',
 CDS_LIB='pure_quanta',
 CDS_PART_NAME='LM75BD-LM75BD,SMLF,IC,AL0075BDA',
 PART_TYPE='SMLF',
 MATERIAL='IC',
 VALUE='LM75BD',
 PRIM_FILE='./archive_libs/logical/lm75bd/chips/chips.prt';

PART_NAME
 U276 'INA230AIRGTR-INA230AIRGTR,SMLFB':;

SECTION_NUMBER 1
 '@S9S_MB_2U_LIB.S9S_MB_2U(SCH_1):PAGE295_I129@PURE_QUANTA.INA230AIRGTR(CHIPS)':
 C_PATH='@s9s_mb_2u_lib.s9s_mb_2u(sch_1):page295_i129@pure_quanta.ina230airgtr(c~
hips)',
 P_PATH='@s9s_mb_2u_lib.s9s_mb_2u(sch_1):page171_i129@pure_quanta.ina230airgtr(c~
hips)',
 PATH='I129',
 DRAWING='@S9S_MB_2U_LIB.S9S_MB_2U(SCH_1):PAGE295',
 PHYS_PAGE='171',
 XY='(2875,475)',
 ROT='0',
 VER='1',
 CDS_LIB='pure_quanta',
 CDS_PART_NAME='INA230AIRGTR-INA230AIRGTR,SMLFA',
 PART_TYPE='SMLF',
 MATERIAL='IC',
 VALUE='INA230AIRGTR',
 PRIM_FILE='./archive_libs/logical/ina230airgtr/chips/chips.prt';

PART_NAME
 U278 '74LVC1G08W57-74LVC1G08W5-7,SMLA':;

SECTION_NUMBER 1
 '@S9S_MB_2U_LIB.S9S_MB_2U(SCH_1):PAGE230_I31@PURE_QUANTA.74LVC1G08W57(CHIPS)':
 C_PATH='@s9s_mb_2u_lib.s9s_mb_2u(sch_1):page230_i31@pure_quanta.\74lvc1g08w57\(~
chips)',
 P_PATH='@s9s_mb_2u_lib.s9s_mb_2u(sch_1):page246_i31@pure_quanta.\74lvc1g08w57\(~
chips)',
 PATH='I31',
 DRAWING='@S9S_MB_2U_LIB.S9S_MB_2U(SCH_1):PAGE230',
 PHYS_PAGE='246',
 XY='(250,2125)',
 ROT='0',
 VER='1',
 CDS_LIB='pure_quanta',
 CDS_PART_NAME='74LVC1G08W57-74LVC1G08W5-7,SMLA',
 PART_TYPE='SMLF',
 MATERIAL='IC',
 VALUE='74LVC1G08W5-7',
 PRIM_FILE='./archive_libs/logical/74lvc1g08w57/chips/chips.prt';

PART_NAME
 U279 'PCA9617ADP-PCA9617ADP,SMLF,IC,A':;

SECTION_NUMBER 1
 '@S9S_MB_2U_LIB.S9S_MB_2U(SCH_1):PAGE183_I93@PURE_QUANTA.PCA9617ADP(CHIPS)':
 C_PATH='@s9s_mb_2u_lib.s9s_mb_2u(sch_1):page183_i93@pure_quanta.pca9617adp(chip~
s)',
 P_PATH='@s9s_mb_2u_lib.s9s_mb_2u(sch_1):page194_i93@pure_quanta.pca9617adp(chip~
s)',
 PATH='I93',
 DRAWING='@S9S_MB_2U_LIB.S9S_MB_2U(SCH_1):PAGE183',
 PHYS_PAGE='194',
 XY='(850,1175)',
 ROT='2',
 VER='1',
 CDS_LIB='pure_quanta',
 CDS_PART_NAME='PCA9617ADP-PCA9617ADP,SMLF,IC,A',
 PART_TYPE='SMLF',
 MATERIAL='IC',
 VALUE='PCA9617ADP',
 PRIM_FILE='./archive_libs/logical/pca9617adp/chips/chips.prt';

PART_NAME
 U286 '74LVC1G126SE7-74LVC1G126SE-7,SA':;

SECTION_NUMBER 1
 '@S9S_MB_2U_LIB.S9S_MB_2U(SCH_1):PAGE307_I80@PURE_QUANTA.74LVC1G126SE7(CHIPS)':
 C_PATH='@s9s_mb_2u_lib.s9s_mb_2u(sch_1):page307_i80@pure_quanta.\74lvc1g126se7\~
(chips)',
 P_PATH='@s9s_mb_2u_lib.s9s_mb_2u(sch_1):page160_i80@pure_quanta.\74lvc1g126se7\~
(chips)',
 PATH='I80',
 DRAWING='@S9S_MB_2U_LIB.S9S_MB_2U(SCH_1):PAGE307',
 PHYS_PAGE='160',
 XY='(-1300,-425)',
 ROT='0',
 VER='1',
 CDS_LIB='pure_quanta',
 CDS_PART_NAME='74LVC1G126SE7-74LVC1G126SE-7,SA',
 PART_TYPE='SMLF',
 MATERIAL='IC',
 VALUE='74LVC1G126SE-7',
 PRIM_FILE='./archive_libs/logical/74lvc1g126se7/chips/chips.prt';

PART_NAME
 U290 'MOSFET_NCH_GDS_ESD_PROTECTED-2A':;

SECTION_NUMBER 1
 '@S9S_MB_2U_LIB.S9S_MB_2U(SCH_1):PAGE303_I5@PURE_QUANTA.MOSFET_NCH_GDS_ESD_PROTECTED(CHIPS)':
 C_PATH='@s9s_mb_2u_lib.s9s_mb_2u(sch_1):page303_i5@pure_quanta.mosfet_nch_gds_e~
sd_protected(chips)',
 P_PATH='@s9s_mb_2u_lib.s9s_mb_2u(sch_1):page301_i5@pure_quanta.mosfet_nch_gds_e~
sd_protected(chips)',
 PATH='I5',
 DRAWING='@S9S_MB_2U_LIB.S9S_MB_2U(SCH_1):PAGE303',
 PHYS_PAGE='301',
 XY='(-16025,625)',
 ROT='0',
 VER='1',
 CDS_LIB='pure_quanta',
 CDS_PART_NAME='MOSFET_NCH_GDS_ESD_PROTECTED-2A',
 PART_TYPE='SMLF',
 MATERIAL='IC',
 VALUE='2N7002K',
 PRIM_FILE='./archive_libs/logical/mosfet_nch_gds_esd_protected/chips/chips.prt';

PART_NAME
 U301 'GTL2014PW-GTL2014PW,SMLF,IC,ALA':;

SECTION_NUMBER 1
 '@S9S_MB_2U_LIB.S9S_MB_2U(SCH_1):PAGE321_I91@PURE_QUANTA.GTL2014PW(CHIPS)':
 C_PATH='@s9s_mb_2u_lib.s9s_mb_2u(sch_1):page321_i91@pure_quanta.gtl2014pw(chips~
)',
 P_PATH='@s9s_mb_2u_lib.s9s_mb_2u(sch_1):page226_i91@pure_quanta.gtl2014pw(chips~
)',
 PATH='I91',
 DRAWING='@S9S_MB_2U_LIB.S9S_MB_2U(SCH_1):PAGE321',
 PHYS_PAGE='226',
 XY='(-725,1350)',
 ROT='2',
 VER='1',
 SEC='1',
 CDS_LIB='pure_quanta',
 CDS_PART_NAME='GTL2014PW-GTL2014PW,SMLF,IC,ALA',
 SEC_TYPE='',
 PART_TYPE='SMLF',
 MATERIAL='IC',
 VALUE='GTL2014PW',
 PRIM_FILE='./archive_libs/logical/gtl2014pw/chips/chips.prt';

PART_NAME
 U304 'GTL2014PW-GTL2014PW,SMLF,IC,ALA':;

SECTION_NUMBER 1
 '@S9S_MB_2U_LIB.S9S_MB_2U(SCH_1):PAGE322_I27@PURE_QUANTA.GTL2014PW(CHIPS)':
 C_PATH='@s9s_mb_2u_lib.s9s_mb_2u(sch_1):page322_i27@pure_quanta.gtl2014pw(chips~
)',
 P_PATH='@s9s_mb_2u_lib.s9s_mb_2u(sch_1):page225_i27@pure_quanta.gtl2014pw(chips~
)',
 PATH='I27',
 DRAWING='@S9S_MB_2U_LIB.S9S_MB_2U(SCH_1):PAGE322',
 PHYS_PAGE='225',
 XY='(-9475,1675)',
 ROT='2',
 VER='1',
 SEC='1',
 CDS_LIB='pure_quanta',
 CDS_PART_NAME='GTL2014PW-GTL2014PW,SMLF,IC,ALA',
 SEC_TYPE='',
 PART_TYPE='SMLF',
 MATERIAL='IC',
 VALUE='GTL2014PW',
 PRIM_FILE='./archive_libs/logical/gtl2014pw/chips/chips.prt';

PART_NAME
 U305 'GTL2014PW-GTL2014PW,SMLF,IC,ALA':;

SECTION_NUMBER 1
 '@S9S_MB_2U_LIB.S9S_MB_2U(SCH_1):PAGE322_I44@PURE_QUANTA.GTL2014PW(CHIPS)':
 C_PATH='@s9s_mb_2u_lib.s9s_mb_2u(sch_1):page322_i44@pure_quanta.gtl2014pw(chips~
)',
 P_PATH='@s9s_mb_2u_lib.s9s_mb_2u(sch_1):page225_i44@pure_quanta.gtl2014pw(chips~
)',
 PATH='I44',
 DRAWING='@S9S_MB_2U_LIB.S9S_MB_2U(SCH_1):PAGE322',
 PHYS_PAGE='225',
 XY='(-9475,-400)',
 ROT='2',
 VER='1',
 SEC='1',
 CDS_LIB='pure_quanta',
 CDS_PART_NAME='GTL2014PW-GTL2014PW,SMLF,IC,ALA',
 SEC_TYPE='',
 PART_TYPE='SMLF',
 MATERIAL='IC',
 VALUE='GTL2014PW',
 PRIM_FILE='./archive_libs/logical/gtl2014pw/chips/chips.prt';

PART_NAME
 U306 'GTL2014PW-GTL2014PW,SMLF,IC,ALA':;

SECTION_NUMBER 1
 '@S9S_MB_2U_LIB.S9S_MB_2U(SCH_1):PAGE322_I80@PURE_QUANTA.GTL2014PW(CHIPS)':
 C_PATH='@s9s_mb_2u_lib.s9s_mb_2u(sch_1):page322_i80@pure_quanta.gtl2014pw(chips~
)',
 P_PATH='@s9s_mb_2u_lib.s9s_mb_2u(sch_1):page225_i80@pure_quanta.gtl2014pw(chips~
)',
 PATH='I80',
 DRAWING='@S9S_MB_2U_LIB.S9S_MB_2U(SCH_1):PAGE322',
 PHYS_PAGE='225',
 XY='(-9475,-2300)',
 ROT='2',
 VER='1',
 SEC='1',
 CDS_LIB='pure_quanta',
 CDS_PART_NAME='GTL2014PW-GTL2014PW,SMLF,IC,ALA',
 SEC_TYPE='',
 PART_TYPE='SMLF',
 MATERIAL='IC',
 VALUE='GTL2014PW',
 PRIM_FILE='./archive_libs/logical/gtl2014pw/chips/chips.prt';

PART_NAME
 U307 'MOSFET_N_SMLF-BSS138K,BSS138K,A':;

SECTION_NUMBER 1
 '@S9S_MB_2U_LIB.S9S_MB_2U(SCH_1):PAGE243_I15@PURE_QUANTA.MOSFET_N(CHIPS)':
 C_PATH='@s9s_mb_2u_lib.s9s_mb_2u(sch_1):page243_i15@pure_quanta.mosfet_n(chips)~
',
 P_PATH='@s9s_mb_2u_lib.s9s_mb_2u(sch_1):page257_i15@pure_quanta.mosfet_n(chips)~
',
 PATH='I15',
 DRAWING='@S9S_MB_2U_LIB.S9S_MB_2U(SCH_1):PAGE243',
 PHYS_PAGE='257',
 XY='(-8450,12800)',
 ROT='2',
 VER='1',
 PACK_TYPE='SMLF',
 CDS_LIB='pure_quanta',
 CDS_PART_NAME='MOSFET_N_SMLF-BSS138K,BSS138K,A',
 MANUF_PN='BSS138K',
 MATERIAL='IC',
 VALUE='BSS138K',
 PRIM_FILE='./archive_libs/logical/mosfet_n/chips/chips.prt';

PART_NAME
 U308 '74LVC2G07DW7-74LVC2G07DW-7,SMLA':;

SECTION_NUMBER 1
 '@S9S_MB_2U_LIB.S9S_MB_2U(SCH_1):PAGE230_I37@PURE_QUANTA.74LVC2G07DW7(CHIPS)':
 C_PATH='@s9s_mb_2u_lib.s9s_mb_2u(sch_1):page230_i37@pure_quanta.\74lvc2g07dw7\(~
chips)',
 P_PATH='@s9s_mb_2u_lib.s9s_mb_2u(sch_1):page246_i37@pure_quanta.\74lvc2g07dw7\(~
chips)',
 PATH='I37',
 DRAWING='@S9S_MB_2U_LIB.S9S_MB_2U(SCH_1):PAGE230',
 PHYS_PAGE='246',
 XY='(550,225)',
 ROT='0',
 VER='1',
 CDS_LIB='pure_quanta',
 CDS_PART_NAME='74LVC2G07DW7-74LVC2G07DW-7,SMLA',
 PART_TYPE='SMLF',
 MATERIAL='IC',
 VALUE='74LVC2G07DW-7',
 PRIM_FILE='./archive_libs/logical/74lvc2g07dw7/chips/chips.prt';

PART_NAME
 U309 'PI3EQX1002EZREX-PI3EQX1002EZREA':;

SECTION_NUMBER 1
 '@S9S_MB_2U_LIB.S9S_MB_2U(SCH_1):PAGE162_I43@PURE_QUANTA.PI3EQX1002EZREX(CHIPS)':
 C_PATH='@s9s_mb_2u_lib.s9s_mb_2u(sch_1):page162_i43@pure_quanta.pi3eqx1002ezrex~
(chips)',
 P_PATH='@s9s_mb_2u_lib.s9s_mb_2u(sch_1):page169_i43@pure_quanta.pi3eqx1002ezrex~
(chips)',
 PATH='I43',
 DRAWING='@S9S_MB_2U_LIB.S9S_MB_2U(SCH_1):PAGE162',
 PHYS_PAGE='169',
 XY='(-1550,3550)',
 ROT='0',
 VER='1',
 LOCATION='U309',
 CDS_LIB='pure_quanta',
 CDS_PART_NAME='PI3EQX1002EZREX-PI3EQX1002EZREA',
 PART_TYPE='SMLF',
 MATERIAL='IC',
 VALUE='PI3EQX1002EZREX',
 PRIM_FILE='./archive_libs/logical/pi3eqx1002ezrex/chips/chips.prt';

PART_NAME
 U312 'TUSB211IRWBR-TUSB211IRWBR,SMLFA':;

SECTION_NUMBER 1
 '@S9S_MB_2U_LIB.S9S_MB_2U(SCH_1):PAGE194_I20@PURE_QUANTA.TUSB211IRWBR(CHIPS)':
 C_PATH='@s9s_mb_2u_lib.s9s_mb_2u(sch_1):page194_i20@pure_quanta.tusb211irwbr(ch~
ips)',
 P_PATH='@s9s_mb_2u_lib.s9s_mb_2u(sch_1):page196_i20@pure_quanta.tusb211irwbr(ch~
ips)',
 PATH='I20',
 DRAWING='@S9S_MB_2U_LIB.S9S_MB_2U(SCH_1):PAGE194',
 PHYS_PAGE='196',
 XY='(525,-2350)',
 ROT='0',
 VER='1',
 CDS_LIB='pure_quanta',
 CDS_PART_NAME='TUSB211IRWBR-TUSB211IRWBR,SMLFA',
 PART_TYPE='SMLF',
 MATERIAL='EMPTY',
 VALUE='TUSB211IRWBR',
 PRIM_FILE='./archive_libs/logical/tusb211irwbr/chips/chips.prt';

PART_NAME
 U313 'GL852GOHY60-GL852G-OHY60,SMLF,B':;

SECTION_NUMBER 1
 '@S9S_MB_2U_LIB.S9S_MB_2U(SCH_1):PAGE194_I40@PURE_QUANTA.GL852GOHY60(CHIPS)':
 C_PATH='@s9s_mb_2u_lib.s9s_mb_2u(sch_1):page194_i40@pure_quanta.gl852gohy60(chi~
ps)',
 P_PATH='@s9s_mb_2u_lib.s9s_mb_2u(sch_1):page196_i40@pure_quanta.gl852gohy60(chi~
ps)',
 PATH='I40',
 DRAWING='@S9S_MB_2U_LIB.S9S_MB_2U(SCH_1):PAGE194',
 PHYS_PAGE='196',
 XY='(775,1375)',
 ROT='0',
 VER='1',
 CDS_LIB='pure_quanta',
 CDS_PART_NAME='GL852GOHY60-GL852G-OHY60,SMLF,B',
 PART_TYPE='SMLF',
 MATERIAL='EMPTY',
 VALUE='GL852G-OHY60',
 PRIM_FILE='./archive_libs/logical/gl852gohy60/chips/chips.prt';

PART_NAME
 U314 '9ZXL0451EKILFT-9ZXL0451EKILFT,A':;

SECTION_NUMBER 1
 '@S9S_MB_2U_LIB.S9S_MB_2U(SCH_1):PAGE200_I1@PURE_QUANTA.9ZXL0451EKILFT(CHIPS)':
 C_PATH='@s9s_mb_2u_lib.s9s_mb_2u(sch_1):page200_i1@pure_quanta.\9zxl0451ekilft\~
(chips)',
 P_PATH='@s9s_mb_2u_lib.s9s_mb_2u(sch_1):page211_i1@pure_quanta.\9zxl0451ekilft\~
(chips)',
 PATH='I1',
 DRAWING='@S9S_MB_2U_LIB.S9S_MB_2U(SCH_1):PAGE200',
 PHYS_PAGE='211',
 XY='(8675,6000)',
 ROT='0',
 VER='1',
 CDS_LIB='pure_quanta',
 CDS_PART_NAME='9ZXL0451EKILFT-9ZXL0451EKILFT,A',
 PART_TYPE='SMLF',
 MATERIAL='IC',
 VALUE='9ZXL0451EKILFT',
 PRIM_FILE='./archive_libs/logical/9zxl0451ekilft/chips/chips.prt';

PART_NAME
 U315 'PCA9617ADP-PCA9617ADP,SMLF,IC,A':;

SECTION_NUMBER 1
 '@S9S_MB_2U_LIB.S9S_MB_2U(SCH_1):PAGE225_I17@PURE_QUANTA.PCA9617ADP(CHIPS)':
 C_PATH='@s9s_mb_2u_lib.s9s_mb_2u(sch_1):page225_i17@pure_quanta.pca9617adp(chip~
s)',
 P_PATH='@s9s_mb_2u_lib.s9s_mb_2u(sch_1):page237_i17@pure_quanta.pca9617adp(chip~
s)',
 PATH='I17',
 DRAWING='@S9S_MB_2U_LIB.S9S_MB_2U(SCH_1):PAGE225',
 PHYS_PAGE='237',
 XY='(-25,625)',
 ROT='0',
 VER='1',
 CDS_LIB='pure_quanta',
 CDS_PART_NAME='PCA9617ADP-PCA9617ADP,SMLF,IC,A',
 PART_TYPE='SMLF',
 MATERIAL='IC',
 VALUE='PCA9617ADP',
 PRIM_FILE='./archive_libs/logical/pca9617adp/chips/chips.prt';

PART_NAME
 U316 '74LVC2G17GW-74LVC2G17GW,SMLF,IA':;

SECTION_NUMBER 1
 '@S9S_MB_2U_LIB.S9S_MB_2U(SCH_1):PAGE139_I86@PURE_QUANTA.74LVC2G17GW(CHIPS)':
 C_PATH='@s9s_mb_2u_lib.s9s_mb_2u(sch_1):page139_i86@pure_quanta.\74lvc2g17gw\(c~
hips)',
 P_PATH='@s9s_mb_2u_lib.s9s_mb_2u(sch_1):page145_i86@pure_quanta.\74lvc2g17gw\(c~
hips)',
 PATH='I86',
 DRAWING='@S9S_MB_2U_LIB.S9S_MB_2U(SCH_1):PAGE139',
 PHYS_PAGE='145',
 XY='(3975,4600)',
 ROT='0',
 VER='1',
 LOCATION='U316',
 SEC='1',
 CDS_LIB='pure_quanta',
 CDS_PART_NAME='74LVC2G17GW-74LVC2G17GW,SMLF,IA',
 SEC_TYPE='',
 PART_TYPE='SMLF',
 MATERIAL='IC',
 VALUE='74LVC2G17GW',
 PRIM_FILE='./archive_libs/logical/74lvc2g17gw/chips/chips.prt';

PART_NAME
 U320 '74LVC1G66GV-74LVC1G66GV,SMLF,IA':;

SECTION_NUMBER 1
 '@S9S_MB_2U_LIB.S9S_MB_2U(SCH_1):PAGE152_I92@PURE_QUANTA.74LVC1G66GV(CHIPS)':
 C_PATH='@s9s_mb_2u_lib.s9s_mb_2u(sch_1):page152_i92@pure_quanta.\74lvc1g66gv\(c~
hips)',
 P_PATH='@s9s_mb_2u_lib.s9s_mb_2u(sch_1):page155_i92@pure_quanta.\74lvc1g66gv\(c~
hips)',
 PATH='I92',
 DRAWING='@S9S_MB_2U_LIB.S9S_MB_2U(SCH_1):PAGE152',
 PIN_NAMES_ROTATE='True',
 PHYS_PAGE='155',
 XY='(-3350,3125)',
 ROT='0',
 VER='1',
 LOCATION='U320',
 CDS_LIB='pure_quanta',
 CDS_PART_NAME='74LVC1G66GV-74LVC1G66GV,SMLF,IA',
 PART_TYPE='SMLF',
 MATERIAL='IC',
 VALUE='74LVC1G66GV',
 PRIM_FILE='./archive_libs/logical/74lvc1g66gv/chips/chips.prt';

PART_NAME
 U321 '74LVC1G66GV-74LVC1G66GV,SMLF,IA':;

SECTION_NUMBER 1
 '@S9S_MB_2U_LIB.S9S_MB_2U(SCH_1):PAGE156_I92@PURE_QUANTA.74LVC1G66GV(CHIPS)':
 C_PATH='@s9s_mb_2u_lib.s9s_mb_2u(sch_1):page156_i92@pure_quanta.\74lvc1g66gv\(c~
hips)',
 P_PATH='@s9s_mb_2u_lib.s9s_mb_2u(sch_1):page161_i92@pure_quanta.\74lvc1g66gv\(c~
hips)',
 PATH='I92',
 DRAWING='@S9S_MB_2U_LIB.S9S_MB_2U(SCH_1):PAGE156',
 PIN_NAMES_ROTATE='True',
 PHYS_PAGE='161',
 XY='(10175,-3475)',
 ROT='0',
 VER='1',
 LOCATION='U321',
 CDS_LIB='pure_quanta',
 CDS_PART_NAME='74LVC1G66GV-74LVC1G66GV,SMLF,IA',
 PART_TYPE='SMLF',
 MATERIAL='IC',
 VALUE='74LVC1G66GV',
 PRIM_FILE='./archive_libs/logical/74lvc1g66gv/chips/chips.prt';

PART_NAME
 U322 '74LVC1G08W57-74LVC1G08W5-7,SMLA':;

SECTION_NUMBER 1
 '@S9S_MB_2U_LIB.S9S_MB_2U(SCH_1):PAGE154_I221@PURE_QUANTA.74LVC1G08W57(CHIPS)':
 C_PATH='@s9s_mb_2u_lib.s9s_mb_2u(sch_1):page154_i221@pure_quanta.\74lvc1g08w57\~
(chips)',
 P_PATH='@s9s_mb_2u_lib.s9s_mb_2u(sch_1):page158_i221@pure_quanta.\74lvc1g08w57\~
(chips)',
 PATH='I221',
 DRAWING='@S9S_MB_2U_LIB.S9S_MB_2U(SCH_1):PAGE154',
 PHYS_PAGE='158',
 XY='(-125,7125)',
 ROT='0',
 VER='1',
 CDS_LIB='pure_quanta',
 CDS_PART_NAME='74LVC1G08W57-74LVC1G08W5-7,SMLA',
 PART_TYPE='SMLF',
 MATERIAL='IC',
 VALUE='74LVC1G08W5-7',
 PRIM_FILE='./archive_libs/logical/74lvc1g08w57/chips/chips.prt';

PART_NAME
 U323 '74LVC1G08W57-74LVC1G08W5-7,SMLA':;

SECTION_NUMBER 1
 '@S9S_MB_2U_LIB.S9S_MB_2U(SCH_1):PAGE132_I92@PURE_QUANTA.74LVC1G08W57(CHIPS)':
 C_PATH='@s9s_mb_2u_lib.s9s_mb_2u(sch_1):page132_i92@pure_quanta.\74lvc1g08w57\(~
chips)',
 P_PATH='@s9s_mb_2u_lib.s9s_mb_2u(sch_1):page164_i92@pure_quanta.\74lvc1g08w57\(~
chips)',
 PATH='I92',
 DRAWING='@S9S_MB_2U_LIB.S9S_MB_2U(SCH_1):PAGE132',
 PHYS_PAGE='164',
 XY='(-450,1000)',
 ROT='0',
 VER='1',
 CDS_LIB='pure_quanta',
 CDS_PART_NAME='74LVC1G08W57-74LVC1G08W5-7,SMLA',
 PART_TYPE='SMLF',
 MATERIAL='IC',
 VALUE='74LVC1G08W5-7',
 PRIM_FILE='./archive_libs/logical/74lvc1g08w57/chips/chips.prt';

PART_NAME
 U324 'MOSFET_NCH_GDS_ESD_PROTECTED-2A':;

SECTION_NUMBER 1
 '@S9S_MB_2U_LIB.S9S_MB_2U(SCH_1):PAGE246_I67@PURE_QUANTA.MOSFET_NCH_GDS_ESD_PROTECTED(CHIPS)':
 C_PATH='@s9s_mb_2u_lib.s9s_mb_2u(sch_1):page246_i67@pure_quanta.mosfet_nch_gds_~
esd_protected(chips)',
 P_PATH='@s9s_mb_2u_lib.s9s_mb_2u(sch_1):page260_i67@pure_quanta.mosfet_nch_gds_~
esd_protected(chips)',
 PATH='I67',
 DRAWING='@S9S_MB_2U_LIB.S9S_MB_2U(SCH_1):PAGE246',
 PHYS_PAGE='260',
 XY='(-2375,6600)',
 ROT='0',
 VER='1',
 LOCATION='U324',
 CDS_LIB='pure_quanta',
 CDS_PART_NAME='MOSFET_NCH_GDS_ESD_PROTECTED-2A',
 PART_TYPE='SMLF',
 MATERIAL='IC',
 VALUE='2N7002K',
 PRIM_FILE='./archive_libs/logical/mosfet_nch_gds_esd_protected/chips/chips.prt';

PART_NAME
 U325 'MOSFET_N_SMLF-BSS138K,BSS138K,A':;

SECTION_NUMBER 1
 '@S9S_MB_2U_LIB.S9S_MB_2U(SCH_1):PAGE326_I38@PURE_QUANTA.MOSFET_N(CHIPS)':
 C_PATH='@s9s_mb_2u_lib.s9s_mb_2u(sch_1):page326_i38@pure_quanta.mosfet_n(chips)~
',
 P_PATH='@s9s_mb_2u_lib.s9s_mb_2u(sch_1):page306_i38@pure_quanta.mosfet_n(chips)~
',
 PATH='I38',
 DRAWING='@S9S_MB_2U_LIB.S9S_MB_2U(SCH_1):PAGE326',
 PHYS_PAGE='306',
 XY='(4000,-125)',
 ROT='0',
 VER='1',
 PACK_TYPE='SMLF',
 CDS_LIB='pure_quanta',
 CDS_PART_NAME='MOSFET_N_SMLF-BSS138K,BSS138K,A',
 MANUF_PN='BSS138K',
 MATERIAL='IC',
 VALUE='BSS138K',
 PRIM_FILE='./archive_libs/logical/mosfet_n/chips/chips.prt';

PART_NAME
 U327 '74CBTLV3126PW-74CBTLV3126PW,SMA':;

SECTION_NUMBER 1
 '@S9S_MB_2U_LIB.S9S_MB_2U(SCH_1):PAGE235_I19@PURE_QUANTA.74CBTLV3126PW(CHIPS)':
 C_PATH='@s9s_mb_2u_lib.s9s_mb_2u(sch_1):page235_i19@pure_quanta.\74cbtlv3126pw\~
(chips)',
 P_PATH='@s9s_mb_2u_lib.s9s_mb_2u(sch_1):page248_i19@pure_quanta.\74cbtlv3126pw\~
(chips)',
 PATH='I19',
 DRAWING='@S9S_MB_2U_LIB.S9S_MB_2U(SCH_1):PAGE235',
 PHYS_PAGE='248',
 XY='(1575,6475)',
 ROT='0',
 VER='1',
 CDS_LIB='pure_quanta',
 CDS_PART_NAME='74CBTLV3126PW-74CBTLV3126PW,SMA',
 PART_TYPE='SMLF',
 MATERIAL='IC',
 VALUE='74CBTLV3126PW',
 PRIM_FILE='./archive_libs/logical/74cbtlv3126pw/chips/chips.prt';

PART_NAME
 U328 'DS125BR111RTWR-DS125BR111RTWR,A':
 ROOM='PCIE REDRIVER1_BOM2';

SECTION_NUMBER 1
 '@S9S_MB_2U_LIB.S9S_MB_2U(SCH_1):PAGE159_I95@PURE_QUANTA.DS125BR111RTWR(CHIPS)':
 C_PATH='@s9s_mb_2u_lib.s9s_mb_2u(sch_1):page159_i95@pure_quanta.ds125br111rtwr(~
chips)',
 P_PATH='@s9s_mb_2u_lib.s9s_mb_2u(sch_1):page167_i95@pure_quanta.ds125br111rtwr(~
chips)',
 PATH='I95',
 DRAWING='@S9S_MB_2U_LIB.S9S_MB_2U(SCH_1):PAGE159',
 PHYS_PAGE='167',
 XY='(1725,1550)',
 ROT='0',
 VER='1',
 SEC='1',
 CDS_LIB='pure_quanta',
 CDS_PART_NAME='DS125BR111RTWR-DS125BR111RTWR,A',
 SEC_TYPE='',
 PART_TYPE='SMLF',
 MATERIAL='EMPTY',
 ROOM='PCIE REDRIVER1_BOM2',
 VALUE='DS125BR111RTWR',
 PRIM_FILE='./archive_libs/logical/ds125br111rtwr/chips/chips.prt';

PART_NAME
 U329 'MOSFET_NCH_GDS_ESD_PROTECTED-2B':;

SECTION_NUMBER 1
 '@S9S_MB_2U_LIB.S9S_MB_2U(SCH_1):PAGE326_I46@PURE_QUANTA.MOSFET_NCH_GDS_ESD_PROTECTED(CHIPS)':
 C_PATH='@s9s_mb_2u_lib.s9s_mb_2u(sch_1):page326_i46@pure_quanta.mosfet_nch_gds_~
esd_protected(chips)',
 P_PATH='@s9s_mb_2u_lib.s9s_mb_2u(sch_1):page306_i46@pure_quanta.mosfet_nch_gds_~
esd_protected(chips)',
 PATH='I46',
 DRAWING='@S9S_MB_2U_LIB.S9S_MB_2U(SCH_1):PAGE326',
 PHYS_PAGE='306',
 XY='(2825,4100)',
 ROT='0',
 VER='1',
 CDS_LIB='pure_quanta',
 CDS_PART_NAME='MOSFET_NCH_GDS_ESD_PROTECTED-2B',
 PART_TYPE='SMLF',
 MATERIAL='EMPTY',
 VALUE='2N7002K',
 PRIM_FILE='./archive_libs/logical/mosfet_nch_gds_esd_protected/chips/chips.prt';

PART_NAME
 U330 'APX80929SAG7-APX809-29SAG-7,SMA':;

SECTION_NUMBER 1
 '@S9S_MB_2U_LIB.S9S_MB_2U(SCH_1):PAGE246_I105@PURE_QUANTA.APX80929SAG7(CHIPS)':
 C_PATH='@s9s_mb_2u_lib.s9s_mb_2u(sch_1):page246_i105@pure_quanta.apx80929sag7(c~
hips)',
 P_PATH='@s9s_mb_2u_lib.s9s_mb_2u(sch_1):page260_i105@pure_quanta.apx80929sag7(c~
hips)',
 PATH='I105',
 DRAWING='@S9S_MB_2U_LIB.S9S_MB_2U(SCH_1):PAGE246',
 PHYS_PAGE='260',
 XY='(-6650,3200)',
 ROT='2',
 VER='1',
 CDS_LIB='pure_quanta',
 CDS_PART_NAME='APX80929SAG7-APX809-29SAG-7,SMA',
 PART_TYPE='SMLF',
 MATERIAL='IC',
 VALUE='APX809-29SAG-7',
 PRIM_FILE='./archive_libs/logical/apx80929sag7/chips/chips.prt';

PART_NAME
 U331 'INA230AIRGTR-INA230AIRGTR,SMLFA':
 ROOM='HSC1_BOM2';

SECTION_NUMBER 1
 '@S9S_MB_2U_LIB.S9S_MB_2U(SCH_1):PAGE240_I39@PURE_QUANTA.INA230AIRGTR(CHIPS)':
 C_PATH='@s9s_mb_2u_lib.s9s_mb_2u(sch_1):page240_i39@pure_quanta.ina230airgtr(ch~
ips)',
 P_PATH='@s9s_mb_2u_lib.s9s_mb_2u(sch_1):page251_i39@pure_quanta.ina230airgtr(ch~
ips)',
 PATH='I39',
 DRAWING='@S9S_MB_2U_LIB.S9S_MB_2U(SCH_1):PAGE240',
 PHYS_PAGE='251',
 XY='(50,250)',
 ROT='0',
 VER='1',
 LOCATION='U331',
 CDS_LIB='pure_quanta',
 CDS_PART_NAME='INA230AIRGTR-INA230AIRGTR,SMLFB',
 PART_TYPE='SMLF',
 MATERIAL='EMPTY',
 ROOM='HSC1_BOM2',
 VALUE='INA230AIRGTR',
 PRIM_FILE='./archive_libs/logical/ina230airgtr/chips/chips.prt';

PART_NAME
 U332 '74LVC2G07DW7-74LVC2G07DW-7,SMLB':;

SECTION_NUMBER 1
 '@S9S_MB_2U_LIB.S9S_MB_2U(SCH_1):PAGE213_I37@PURE_QUANTA.74LVC2G07DW7(CHIPS)':
 C_PATH='@s9s_mb_2u_lib.s9s_mb_2u(sch_1):page213_i37@pure_quanta.\74lvc2g07dw7\(~
chips)',
 P_PATH='@s9s_mb_2u_lib.s9s_mb_2u(sch_1):page224_i37@pure_quanta.\74lvc2g07dw7\(~
chips)',
 PATH='I37',
 DRAWING='@S9S_MB_2U_LIB.S9S_MB_2U(SCH_1):PAGE213',
 PHYS_PAGE='224',
 XY='(-7250,1000)',
 ROT='0',
 VER='1',
 CDS_LIB='pure_quanta',
 CDS_PART_NAME='74LVC2G07DW7-74LVC2G07DW-7,SMLB',
 PART_TYPE='SMLF',
 MATERIAL='EMPTY',
 VALUE='74LVC2G07DW-7',
 PRIM_FILE='./archive_libs/logical/74lvc2g07dw7/chips/chips.prt';

PART_NAME
 U334 '74LVC1G08W57-74LVC1G08W5-7,SMLA':;

SECTION_NUMBER 1
 '@S9S_MB_2U_LIB.S9S_MB_2U(SCH_1):PAGE154_I243@PURE_QUANTA.74LVC1G08W57(CHIPS)':
 C_PATH='@s9s_mb_2u_lib.s9s_mb_2u(sch_1):page154_i243@pure_quanta.\74lvc1g08w57\~
(chips)',
 P_PATH='@s9s_mb_2u_lib.s9s_mb_2u(sch_1):page158_i243@pure_quanta.\74lvc1g08w57\~
(chips)',
 PATH='I243',
 DRAWING='@S9S_MB_2U_LIB.S9S_MB_2U(SCH_1):PAGE154',
 PHYS_PAGE='158',
 XY='(875,5750)',
 ROT='0',
 VER='1',
 CDS_LIB='pure_quanta',
 CDS_PART_NAME='74LVC1G08W57-74LVC1G08W5-7,SMLA',
 PART_TYPE='SMLF',
 MATERIAL='IC',
 VALUE='74LVC1G08W5-7',
 PRIM_FILE='./archive_libs/logical/74lvc1g08w57/chips/chips.prt';

PART_NAME
 U335 '74LVC1G08W57-74LVC1G08W5-7,SMLA':;

SECTION_NUMBER 1
 '@S9S_MB_2U_LIB.S9S_MB_2U(SCH_1):PAGE132_I108@PURE_QUANTA.74LVC1G08W57(CHIPS)':
 C_PATH='@s9s_mb_2u_lib.s9s_mb_2u(sch_1):page132_i108@pure_quanta.\74lvc1g08w57\~
(chips)',
 P_PATH='@s9s_mb_2u_lib.s9s_mb_2u(sch_1):page164_i108@pure_quanta.\74lvc1g08w57\~
(chips)',
 PATH='I108',
 DRAWING='@S9S_MB_2U_LIB.S9S_MB_2U(SCH_1):PAGE132',
 PHYS_PAGE='164',
 XY='(950,-450)',
 ROT='0',
 VER='1',
 CDS_LIB='pure_quanta',
 CDS_PART_NAME='74LVC1G08W57-74LVC1G08W5-7,SMLA',
 PART_TYPE='SMLF',
 MATERIAL='IC',
 VALUE='74LVC1G08W5-7',
 PRIM_FILE='./archive_libs/logical/74lvc1g08w57/chips/chips.prt';

PART_NAME
 U336 'APX80929SAG7-APX809-29SAG-7,SMA':;

SECTION_NUMBER 1
 '@S9S_MB_2U_LIB.S9S_MB_2U(SCH_1):PAGE297_I329@PURE_QUANTA.APX80929SAG7(CHIPS)':
 C_PATH='@s9s_mb_2u_lib.s9s_mb_2u(sch_1):page297_i329@pure_quanta.apx80929sag7(c~
hips)',
 P_PATH='@s9s_mb_2u_lib.s9s_mb_2u(sch_1):page191_i329@pure_quanta.apx80929sag7(c~
hips)',
 PATH='I329',
 DRAWING='@S9S_MB_2U_LIB.S9S_MB_2U(SCH_1):PAGE297',
 PHYS_PAGE='191',
 XY='(-2650,1250)',
 ROT='2',
 VER='1',
 CDS_LIB='pure_quanta',
 CDS_PART_NAME='APX80929SAG7-APX809-29SAG-7,SMA',
 PART_TYPE='SMLF',
 MATERIAL='IC',
 VALUE='APX809-29SAG-7',
 PRIM_FILE='./archive_libs/logical/apx80929sag7/chips/chips.prt';

PART_NAME
 U337 'LM4040AIM3X25NOPB-LM4040AIM3X-A':;

SECTION_NUMBER 1
 '@S9S_MB_2U_LIB.S9S_MB_2U(SCH_1):PAGE329_I3@PURE_QUANTA.LM4040AIM3X25NOPB(CHIPS)':
 C_PATH='@s9s_mb_2u_lib.s9s_mb_2u(sch_1):page329_i3@pure_quanta.lm4040aim3x25nop~
b(chips)',
 P_PATH='@s9s_mb_2u_lib.s9s_mb_2u(sch_1):page307_i3@pure_quanta.lm4040aim3x25nop~
b(chips)',
 PATH='I3',
 DRAWING='@S9S_MB_2U_LIB.S9S_MB_2U(SCH_1):PAGE329',
 PIN_NAMES_ROTATE='True',
 PHYS_PAGE='307',
 XY='(-1700,2625)',
 ROT='0',
 VER='1',
 CDS_LIB='pure_quanta',
 CDS_PART_NAME='LM4040AIM3X25NOPB-LM4040AIM3X-A',
 PART_TYPE='SMLF',
 MATERIAL='EMPTY',
 VALUE='LM4040AIM3X-2.5/NOPB',
 PRIM_FILE='./archive_libs/logical/lm4040aim3x25nopb/chips/chips.prt';

PART_NAME
 U338 'LM4040AIM3X25NOPB-LM4040AIM3X-A':;

SECTION_NUMBER 1
 '@S9S_MB_2U_LIB.S9S_MB_2U(SCH_1):PAGE329_I43@PURE_QUANTA.LM4040AIM3X25NOPB(CHIPS)':
 C_PATH='@s9s_mb_2u_lib.s9s_mb_2u(sch_1):page329_i43@pure_quanta.lm4040aim3x25no~
pb(chips)',
 P_PATH='@s9s_mb_2u_lib.s9s_mb_2u(sch_1):page307_i43@pure_quanta.lm4040aim3x25no~
pb(chips)',
 PATH='I43',
 DRAWING='@S9S_MB_2U_LIB.S9S_MB_2U(SCH_1):PAGE329',
 PIN_NAMES_ROTATE='True',
 PHYS_PAGE='307',
 XY='(-1675,500)',
 ROT='0',
 VER='1',
 CDS_LIB='pure_quanta',
 CDS_PART_NAME='LM4040AIM3X25NOPB-LM4040AIM3X-A',
 PART_TYPE='SMLF',
 MATERIAL='EMPTY',
 VALUE='LM4040AIM3X-2.5/NOPB',
 PRIM_FILE='./archive_libs/logical/lm4040aim3x25nopb/chips/chips.prt';

PART_NAME
 U339 'AP331AWG7-AP331AWG-7,SMLF,EMPTA':;

SECTION_NUMBER 1
 '@S9S_MB_2U_LIB.S9S_MB_2U(SCH_1):PAGE329_I12@PURE_QUANTA.AP331AWG7(CHIPS)':
 C_PATH='@s9s_mb_2u_lib.s9s_mb_2u(sch_1):page329_i12@pure_quanta.ap331awg7(chips~
)',
 P_PATH='@s9s_mb_2u_lib.s9s_mb_2u(sch_1):page307_i12@pure_quanta.ap331awg7(chips~
)',
 PATH='I12',
 DRAWING='@S9S_MB_2U_LIB.S9S_MB_2U(SCH_1):PAGE329',
 PHYS_PAGE='307',
 XY='(75,3225)',
 ROT='0',
 VER='1',
 CDS_LIB='pure_quanta',
 CDS_PART_NAME='AP331AWG7-AP331AWG-7,SMLF,EMPTA',
 PART_TYPE='SMLF',
 MATERIAL='EMPTY',
 VALUE='AP331AWG-7',
 PRIM_FILE='./archive_libs/logical/ap331awg7/chips/chips.prt';

PART_NAME
 U340 'AP331AWG7-AP331AWG-7,SMLF,EMPTA':;

SECTION_NUMBER 1
 '@S9S_MB_2U_LIB.S9S_MB_2U(SCH_1):PAGE329_I23@PURE_QUANTA.AP331AWG7(CHIPS)':
 C_PATH='@s9s_mb_2u_lib.s9s_mb_2u(sch_1):page329_i23@pure_quanta.ap331awg7(chips~
)',
 P_PATH='@s9s_mb_2u_lib.s9s_mb_2u(sch_1):page307_i23@pure_quanta.ap331awg7(chips~
)',
 PATH='I23',
 DRAWING='@S9S_MB_2U_LIB.S9S_MB_2U(SCH_1):PAGE329',
 PHYS_PAGE='307',
 XY='(100,1100)',
 ROT='0',
 VER='1',
 CDS_LIB='pure_quanta',
 CDS_PART_NAME='AP331AWG7-AP331AWG-7,SMLF,EMPTA',
 PART_TYPE='SMLF',
 MATERIAL='EMPTY',
 VALUE='AP331AWG-7',
 PRIM_FILE='./archive_libs/logical/ap331awg7/chips/chips.prt';

PART_NAME
 U341 'LM4040AIM3X25NOPB-LM4040AIM3X-A':;

SECTION_NUMBER 1
 '@S9S_MB_2U_LIB.S9S_MB_2U(SCH_1):PAGE329_I63@PURE_QUANTA.LM4040AIM3X25NOPB(CHIPS)':
 C_PATH='@s9s_mb_2u_lib.s9s_mb_2u(sch_1):page329_i63@pure_quanta.lm4040aim3x25no~
pb(chips)',
 P_PATH='@s9s_mb_2u_lib.s9s_mb_2u(sch_1):page307_i63@pure_quanta.lm4040aim3x25no~
pb(chips)',
 PATH='I63',
 DRAWING='@S9S_MB_2U_LIB.S9S_MB_2U(SCH_1):PAGE329',
 PIN_NAMES_ROTATE='True',
 PHYS_PAGE='307',
 XY='(-1675,-1375)',
 ROT='0',
 VER='1',
 CDS_LIB='pure_quanta',
 CDS_PART_NAME='LM4040AIM3X25NOPB-LM4040AIM3X-A',
 PART_TYPE='SMLF',
 MATERIAL='EMPTY',
 VALUE='LM4040AIM3X-2.5/NOPB',
 PRIM_FILE='./archive_libs/logical/lm4040aim3x25nopb/chips/chips.prt';

PART_NAME
 U342 'AP331AWG7-AP331AWG-7,SMLF,EMPTA':;

SECTION_NUMBER 1
 '@S9S_MB_2U_LIB.S9S_MB_2U(SCH_1):PAGE329_I45@PURE_QUANTA.AP331AWG7(CHIPS)':
 C_PATH='@s9s_mb_2u_lib.s9s_mb_2u(sch_1):page329_i45@pure_quanta.ap331awg7(chips~
)',
 P_PATH='@s9s_mb_2u_lib.s9s_mb_2u(sch_1):page307_i45@pure_quanta.ap331awg7(chips~
)',
 PATH='I45',
 DRAWING='@S9S_MB_2U_LIB.S9S_MB_2U(SCH_1):PAGE329',
 PHYS_PAGE='307',
 XY='(100,-775)',
 ROT='0',
 VER='1',
 CDS_LIB='pure_quanta',
 CDS_PART_NAME='AP331AWG7-AP331AWG-7,SMLF,EMPTA',
 PART_TYPE='SMLF',
 MATERIAL='EMPTY',
 VALUE='AP331AWG-7',
 PRIM_FILE='./archive_libs/logical/ap331awg7/chips/chips.prt';

PART_NAME
 U343 'LM4040AIM3X25NOPB-LM4040AIM3X-A':;

SECTION_NUMBER 1
 '@S9S_MB_2U_LIB.S9S_MB_2U(SCH_1):PAGE326_I56@PURE_QUANTA.LM4040AIM3X25NOPB(CHIPS)':
 C_PATH='@s9s_mb_2u_lib.s9s_mb_2u(sch_1):page326_i56@pure_quanta.lm4040aim3x25no~
pb(chips)',
 P_PATH='@s9s_mb_2u_lib.s9s_mb_2u(sch_1):page306_i56@pure_quanta.lm4040aim3x25no~
pb(chips)',
 PATH='I56',
 DRAWING='@S9S_MB_2U_LIB.S9S_MB_2U(SCH_1):PAGE326',
 PIN_NAMES_ROTATE='True',
 PHYS_PAGE='306',
 XY='(-875,1150)',
 ROT='0',
 VER='1',
 CDS_LIB='pure_quanta',
 CDS_PART_NAME='LM4040AIM3X25NOPB-LM4040AIM3X-A',
 PART_TYPE='SMLF',
 MATERIAL='EMPTY',
 VALUE='LM4040AIM3X-2.5/NOPB',
 PRIM_FILE='./archive_libs/logical/lm4040aim3x25nopb/chips/chips.prt';

PART_NAME
 U344 'AP331AWG7-AP331AWG-7,SMLF,EMPTA':;

SECTION_NUMBER 1
 '@S9S_MB_2U_LIB.S9S_MB_2U(SCH_1):PAGE326_I66@PURE_QUANTA.AP331AWG7(CHIPS)':
 C_PATH='@s9s_mb_2u_lib.s9s_mb_2u(sch_1):page326_i66@pure_quanta.ap331awg7(chips~
)',
 P_PATH='@s9s_mb_2u_lib.s9s_mb_2u(sch_1):page306_i66@pure_quanta.ap331awg7(chips~
)',
 PATH='I66',
 DRAWING='@S9S_MB_2U_LIB.S9S_MB_2U(SCH_1):PAGE326',
 PHYS_PAGE='306',
 XY='(900,1750)',
 ROT='0',
 VER='1',
 CDS_LIB='pure_quanta',
 CDS_PART_NAME='AP331AWG7-AP331AWG-7,SMLF,EMPTA',
 PART_TYPE='SMLF',
 MATERIAL='EMPTY',
 VALUE='AP331AWG-7',
 PRIM_FILE='./archive_libs/logical/ap331awg7/chips/chips.prt';

PART_NAME
 U345 'NCT7718W-NCT7718W,SMLF,EMPTY,AA':
 ROOM='HSC1_BOM2';

SECTION_NUMBER 1
 '@S9S_MB_2U_LIB.S9S_MB_2U(SCH_1):PAGE327_I10@PURE_QUANTA.NCT7718W(CHIPS)':
 C_PATH='@s9s_mb_2u_lib.s9s_mb_2u(sch_1):page327_i10@pure_quanta.nct7718w(chips)~
',
 P_PATH='@s9s_mb_2u_lib.s9s_mb_2u(sch_1):page305_i10@pure_quanta.nct7718w(chips)~
',
 PATH='I10',
 DRAWING='@S9S_MB_2U_LIB.S9S_MB_2U(SCH_1):PAGE327',
 PHYS_PAGE='305',
 XY='(3200,250)',
 ROT='0',
 VER='1',
 LOCATION='U345',
 CDS_LIB='pure_quanta',
 CDS_PART_NAME='NCT7718W-NCT7718W,SMLF,EMPTY,AA',
 PART_TYPE='SMLF',
 MATERIAL='EMPTY',
 ROOM='HSC1_BOM2',
 VALUE='NCT7718W',
 PRIM_FILE='./archive_libs/logical/nct7718w/chips/chips.prt';

PART_NAME
 U365 'MMBT3904_SMLF-MMBT3904    ,EMPA':
 ROOM='HSC1_BOM2';

SECTION_NUMBER 1
 '@S9S_MB_2U_LIB.S9S_MB_2U(SCH_1):PAGE327_I49@PURE_QUANTA.MMBT3904(CHIPS)':
 C_PATH='@s9s_mb_2u_lib.s9s_mb_2u(sch_1):page327_i49@pure_quanta.mmbt3904(chips)~
',
 P_PATH='@s9s_mb_2u_lib.s9s_mb_2u(sch_1):page305_i49@pure_quanta.mmbt3904(chips)~
',
 PATH='I49',
 DRAWING='@S9S_MB_2U_LIB.S9S_MB_2U(SCH_1):PAGE327',
 PHYS_PAGE='305',
 XY='(925,125)',
 ROT='2',
 VER='1',
 PACK_TYPE='SMLF',
 LOCATION='U365',
 CDS_LIB='pure_quanta',
 CDS_PART_NAME='MMBT3904_SMLF-MMBT3904    ,EMPA',
 MATERIAL='EMPTY',
 ROOM='HSC1_BOM2',
 VALUE='MMBT3904    ',
 PRIM_FILE='./archive_libs/logical/mmbt3904/chips/chips.prt';

PART_NAME
 U369 'TPS3700DDCR-TPS3700DDCR,SMLF,EA':;

SECTION_NUMBER 1
 '@S9S_MB_2U_LIB.S9S_MB_2U(SCH_1):PAGE326_I30@PURE_QUANTA.TPS3700DDCR(CHIPS)':
 C_PATH='@s9s_mb_2u_lib.s9s_mb_2u(sch_1):page326_i30@pure_quanta.tps3700ddcr(chi~
ps)',
 P_PATH='@s9s_mb_2u_lib.s9s_mb_2u(sch_1):page306_i30@pure_quanta.tps3700ddcr(chi~
ps)',
 PATH='I30',
 DRAWING='@S9S_MB_2U_LIB.S9S_MB_2U(SCH_1):PAGE326',
 PHYS_PAGE='306',
 XY='(1075,3700)',
 ROT='0',
 VER='1',
 LOCATION='U369',
 CDS_LIB='pure_quanta',
 CDS_PART_NAME='TPS3700DDCR-TPS3700DDCR,SMLF,EA',
 PART_TYPE='SMLF',
 MATERIAL='EMPTY',
 VALUE='TPS3700DDCR',
 PRIM_FILE='./archive_libs/logical/tps3700ddcr/chips/chips.prt';

PART_NAME
 U5201 'TUSB211IRWBR-TUSB211IRWBR,SMLFA':
 ROOM='USB1_BOM2';

SECTION_NUMBER 1
 '@S9S_MB_2U_LIB.S9S_MB_2U(SCH_1):PAGE155_I84@PURE_QUANTA.TUSB211IRWBR(CHIPS)':
 C_PATH='@s9s_mb_2u_lib.s9s_mb_2u(sch_1):page155_i84@pure_quanta.tusb211irwbr(ch~
ips)',
 P_PATH='@s9s_mb_2u_lib.s9s_mb_2u(sch_1):page152_i84@pure_quanta.tusb211irwbr(ch~
ips)',
 PATH='I84',
 DRAWING='@S9S_MB_2U_LIB.S9S_MB_2U(SCH_1):PAGE155',
 PHYS_PAGE='152',
 XY='(-125,100)',
 ROT='0',
 VER='1',
 CDS_LIB='pure_quanta',
 CDS_PART_NAME='TUSB211IRWBR-TUSB211IRWBR,SMLFA',
 PART_TYPE='SMLF',
 MATERIAL='EMPTY',
 ROOM='USB1_BOM2',
 VALUE='TUSB211IRWBR',
 PRIM_FILE='./archive_libs/logical/tusb211irwbr/chips/chips.prt';

PART_NAME
 X1 'TP_TDR_4P_FTS_TH-TP_TDR_4P_DIPA':;

SECTION_NUMBER 1
 '@S9S_MB_2U_LIB.S9S_MB_2U(SCH_1):PAGE288_I28@PURE_QUANTA.TP_TDR_4P_FTS(CHIPS)':
 C_PATH='@s9s_mb_2u_lib.s9s_mb_2u(sch_1):page288_i28@pure_quanta.tp_tdr_4p_fts(c~
hips)',
 P_PATH='@s9s_mb_2u_lib.s9s_mb_2u(sch_1):page309_i28@pure_quanta.tp_tdr_4p_fts(c~
hips)',
 PATH='I28',
 DRAWING='@S9S_MB_2U_LIB.S9S_MB_2U(SCH_1):PAGE288',
 PHYS_PAGE='309',
 XY='(700,4250)',
 ROT='0',
 VER='1',
 PACK_TYPE='TH',
 CDS_LIB='pure_quanta',
 CDS_PART_NAME='TP_TDR_4P_FTS_TH-TP_TDR_4P_DIPA',
 MATERIAL='EMPTY',
 VALUE='TP_TDR_4P_DIP',
 PRIM_FILE='./archive_libs/logical/tp_tdr_4p_fts/chips/chips.prt';

PART_NAME
 X2 'TP_TDR_4P_FTS_TH-TP_TDR_4P_DIPA':;

SECTION_NUMBER 1
 '@S9S_MB_2U_LIB.S9S_MB_2U(SCH_1):PAGE288_I30@PURE_QUANTA.TP_TDR_4P_FTS(CHIPS)':
 C_PATH='@s9s_mb_2u_lib.s9s_mb_2u(sch_1):page288_i30@pure_quanta.tp_tdr_4p_fts(c~
hips)',
 P_PATH='@s9s_mb_2u_lib.s9s_mb_2u(sch_1):page309_i30@pure_quanta.tp_tdr_4p_fts(c~
hips)',
 PATH='I30',
 DRAWING='@S9S_MB_2U_LIB.S9S_MB_2U(SCH_1):PAGE288',
 PHYS_PAGE='309',
 XY='(700,3475)',
 ROT='0',
 VER='1',
 PACK_TYPE='TH',
 CDS_LIB='pure_quanta',
 CDS_PART_NAME='TP_TDR_4P_FTS_TH-TP_TDR_4P_DIPA',
 MATERIAL='EMPTY',
 VALUE='TP_TDR_4P_DIP',
 PRIM_FILE='./archive_libs/logical/tp_tdr_4p_fts/chips/chips.prt';

PART_NAME
 X3 'TP_TDR_4P_FTS_TH-TP_TDR_4P_DIPA':;

SECTION_NUMBER 1
 '@S9S_MB_2U_LIB.S9S_MB_2U(SCH_1):PAGE288_I35@PURE_QUANTA.TP_TDR_4P_FTS(CHIPS)':
 C_PATH='@s9s_mb_2u_lib.s9s_mb_2u(sch_1):page288_i35@pure_quanta.tp_tdr_4p_fts(c~
hips)',
 P_PATH='@s9s_mb_2u_lib.s9s_mb_2u(sch_1):page309_i35@pure_quanta.tp_tdr_4p_fts(c~
hips)',
 PATH='I35',
 DRAWING='@S9S_MB_2U_LIB.S9S_MB_2U(SCH_1):PAGE288',
 PHYS_PAGE='309',
 XY='(700,2700)',
 ROT='0',
 VER='1',
 PACK_TYPE='TH',
 CDS_LIB='pure_quanta',
 CDS_PART_NAME='TP_TDR_4P_FTS_TH-TP_TDR_4P_DIPA',
 MATERIAL='EMPTY',
 VALUE='TP_TDR_4P_DIP',
 PRIM_FILE='./archive_libs/logical/tp_tdr_4p_fts/chips/chips.prt';

PART_NAME
 X4 'TP_TDR_4P_FTS_TH-TP_TDR_4P_DIPA':;

SECTION_NUMBER 1
 '@S9S_MB_2U_LIB.S9S_MB_2U(SCH_1):PAGE288_I37@PURE_QUANTA.TP_TDR_4P_FTS(CHIPS)':
 C_PATH='@s9s_mb_2u_lib.s9s_mb_2u(sch_1):page288_i37@pure_quanta.tp_tdr_4p_fts(c~
hips)',
 P_PATH='@s9s_mb_2u_lib.s9s_mb_2u(sch_1):page309_i37@pure_quanta.tp_tdr_4p_fts(c~
hips)',
 PATH='I37',
 DRAWING='@S9S_MB_2U_LIB.S9S_MB_2U(SCH_1):PAGE288',
 PHYS_PAGE='309',
 XY='(700,1925)',
 ROT='0',
 VER='1',
 PACK_TYPE='TH',
 CDS_LIB='pure_quanta',
 CDS_PART_NAME='TP_TDR_4P_FTS_TH-TP_TDR_4P_DIPA',
 MATERIAL='EMPTY',
 VALUE='TP_TDR_4P_DIP',
 PRIM_FILE='./archive_libs/logical/tp_tdr_4p_fts/chips/chips.prt';

PART_NAME
 X5 'TP_TDR_4P_FTS_TH-TP_TDR_4P_DIPA':;

SECTION_NUMBER 1
 '@S9S_MB_2U_LIB.S9S_MB_2U(SCH_1):PAGE288_I39@PURE_QUANTA.TP_TDR_4P_FTS(CHIPS)':
 C_PATH='@s9s_mb_2u_lib.s9s_mb_2u(sch_1):page288_i39@pure_quanta.tp_tdr_4p_fts(c~
hips)',
 P_PATH='@s9s_mb_2u_lib.s9s_mb_2u(sch_1):page309_i39@pure_quanta.tp_tdr_4p_fts(c~
hips)',
 PATH='I39',
 DRAWING='@S9S_MB_2U_LIB.S9S_MB_2U(SCH_1):PAGE288',
 PHYS_PAGE='309',
 XY='(700,1150)',
 ROT='0',
 VER='1',
 PACK_TYPE='TH',
 CDS_LIB='pure_quanta',
 CDS_PART_NAME='TP_TDR_4P_FTS_TH-TP_TDR_4P_DIPA',
 MATERIAL='EMPTY',
 VALUE='TP_TDR_4P_DIP',
 PRIM_FILE='./archive_libs/logical/tp_tdr_4p_fts/chips/chips.prt';

PART_NAME
 X6 'TP_TDR_4P_FTS_TH-TP_TDR_4P_DIPA':;

SECTION_NUMBER 1
 '@S9S_MB_2U_LIB.S9S_MB_2U(SCH_1):PAGE288_I47@PURE_QUANTA.TP_TDR_4P_FTS(CHIPS)':
 C_PATH='@s9s_mb_2u_lib.s9s_mb_2u(sch_1):page288_i47@pure_quanta.tp_tdr_4p_fts(c~
hips)',
 P_PATH='@s9s_mb_2u_lib.s9s_mb_2u(sch_1):page309_i47@pure_quanta.tp_tdr_4p_fts(c~
hips)',
 PATH='I47',
 DRAWING='@S9S_MB_2U_LIB.S9S_MB_2U(SCH_1):PAGE288',
 PHYS_PAGE='309',
 XY='(700,-950)',
 ROT='0',
 VER='1',
 PACK_TYPE='TH',
 CDS_LIB='pure_quanta',
 CDS_PART_NAME='TP_TDR_4P_FTS_TH-TP_TDR_4P_DIPA',
 MATERIAL='EMPTY',
 VALUE='TP_TDR_4P_DIP',
 PRIM_FILE='./archive_libs/logical/tp_tdr_4p_fts/chips/chips.prt';

PART_NAME
 X7 'TP_TDR_4P_FTS_TH-TP_TDR_4P_DIPA':;

SECTION_NUMBER 1
 '@S9S_MB_2U_LIB.S9S_MB_2U(SCH_1):PAGE288_I26@PURE_QUANTA.TP_TDR_4P_FTS(CHIPS)':
 C_PATH='@s9s_mb_2u_lib.s9s_mb_2u(sch_1):page288_i26@pure_quanta.tp_tdr_4p_fts(c~
hips)',
 P_PATH='@s9s_mb_2u_lib.s9s_mb_2u(sch_1):page309_i26@pure_quanta.tp_tdr_4p_fts(c~
hips)',
 PATH='I26',
 DRAWING='@S9S_MB_2U_LIB.S9S_MB_2U(SCH_1):PAGE288',
 PHYS_PAGE='309',
 XY='(2025,4250)',
 ROT='4',
 VER='1',
 PACK_TYPE='TH',
 CDS_LIB='pure_quanta',
 CDS_PART_NAME='TP_TDR_4P_FTS_TH-TP_TDR_4P_DIPA',
 MATERIAL='EMPTY',
 VALUE='TP_TDR_4P_DIP',
 PRIM_FILE='./archive_libs/logical/tp_tdr_4p_fts/chips/chips.prt';

PART_NAME
 X8 'TP_TDR_4P_FTS_TH-TP_TDR_4P_DIPA':;

SECTION_NUMBER 1
 '@S9S_MB_2U_LIB.S9S_MB_2U(SCH_1):PAGE288_I27@PURE_QUANTA.TP_TDR_4P_FTS(CHIPS)':
 C_PATH='@s9s_mb_2u_lib.s9s_mb_2u(sch_1):page288_i27@pure_quanta.tp_tdr_4p_fts(c~
hips)',
 P_PATH='@s9s_mb_2u_lib.s9s_mb_2u(sch_1):page309_i27@pure_quanta.tp_tdr_4p_fts(c~
hips)',
 PATH='I27',
 DRAWING='@S9S_MB_2U_LIB.S9S_MB_2U(SCH_1):PAGE288',
 PHYS_PAGE='309',
 XY='(2025,3475)',
 ROT='4',
 VER='1',
 PACK_TYPE='TH',
 CDS_LIB='pure_quanta',
 CDS_PART_NAME='TP_TDR_4P_FTS_TH-TP_TDR_4P_DIPA',
 MATERIAL='EMPTY',
 VALUE='TP_TDR_4P_DIP',
 PRIM_FILE='./archive_libs/logical/tp_tdr_4p_fts/chips/chips.prt';

PART_NAME
 X9 'TP_TDR_4P_FTS_TH-TP_TDR_4P_DIPA':;

SECTION_NUMBER 1
 '@S9S_MB_2U_LIB.S9S_MB_2U(SCH_1):PAGE288_I32@PURE_QUANTA.TP_TDR_4P_FTS(CHIPS)':
 C_PATH='@s9s_mb_2u_lib.s9s_mb_2u(sch_1):page288_i32@pure_quanta.tp_tdr_4p_fts(c~
hips)',
 P_PATH='@s9s_mb_2u_lib.s9s_mb_2u(sch_1):page309_i32@pure_quanta.tp_tdr_4p_fts(c~
hips)',
 PATH='I32',
 DRAWING='@S9S_MB_2U_LIB.S9S_MB_2U(SCH_1):PAGE288',
 PHYS_PAGE='309',
 XY='(2025,2700)',
 ROT='4',
 VER='1',
 PACK_TYPE='TH',
 CDS_LIB='pure_quanta',
 CDS_PART_NAME='TP_TDR_4P_FTS_TH-TP_TDR_4P_DIPA',
 MATERIAL='EMPTY',
 VALUE='TP_TDR_4P_DIP',
 PRIM_FILE='./archive_libs/logical/tp_tdr_4p_fts/chips/chips.prt';

PART_NAME
 X10 'TP_TDR_4P_FTS_TH-TP_TDR_4P_DIPA':;

SECTION_NUMBER 1
 '@S9S_MB_2U_LIB.S9S_MB_2U(SCH_1):PAGE288_I33@PURE_QUANTA.TP_TDR_4P_FTS(CHIPS)':
 C_PATH='@s9s_mb_2u_lib.s9s_mb_2u(sch_1):page288_i33@pure_quanta.tp_tdr_4p_fts(c~
hips)',
 P_PATH='@s9s_mb_2u_lib.s9s_mb_2u(sch_1):page309_i33@pure_quanta.tp_tdr_4p_fts(c~
hips)',
 PATH='I33',
 DRAWING='@S9S_MB_2U_LIB.S9S_MB_2U(SCH_1):PAGE288',
 PHYS_PAGE='309',
 XY='(2025,1925)',
 ROT='4',
 VER='1',
 PACK_TYPE='TH',
 CDS_LIB='pure_quanta',
 CDS_PART_NAME='TP_TDR_4P_FTS_TH-TP_TDR_4P_DIPA',
 MATERIAL='EMPTY',
 VALUE='TP_TDR_4P_DIP',
 PRIM_FILE='./archive_libs/logical/tp_tdr_4p_fts/chips/chips.prt';

PART_NAME
 X11 'TP_TDR_4P_FTS_TH-TP_TDR_4P_DIPA':;

SECTION_NUMBER 1
 '@S9S_MB_2U_LIB.S9S_MB_2U(SCH_1):PAGE288_I34@PURE_QUANTA.TP_TDR_4P_FTS(CHIPS)':
 C_PATH='@s9s_mb_2u_lib.s9s_mb_2u(sch_1):page288_i34@pure_quanta.tp_tdr_4p_fts(c~
hips)',
 P_PATH='@s9s_mb_2u_lib.s9s_mb_2u(sch_1):page309_i34@pure_quanta.tp_tdr_4p_fts(c~
hips)',
 PATH='I34',
 DRAWING='@S9S_MB_2U_LIB.S9S_MB_2U(SCH_1):PAGE288',
 PHYS_PAGE='309',
 XY='(2025,1150)',
 ROT='4',
 VER='1',
 PACK_TYPE='TH',
 CDS_LIB='pure_quanta',
 CDS_PART_NAME='TP_TDR_4P_FTS_TH-TP_TDR_4P_DIPA',
 MATERIAL='EMPTY',
 VALUE='TP_TDR_4P_DIP',
 PRIM_FILE='./archive_libs/logical/tp_tdr_4p_fts/chips/chips.prt';

PART_NAME
 X12 'TP_TDR_4P_FTS_TH-TP_TDR_4P_DIPA':;

SECTION_NUMBER 1
 '@S9S_MB_2U_LIB.S9S_MB_2U(SCH_1):PAGE288_I46@PURE_QUANTA.TP_TDR_4P_FTS(CHIPS)':
 C_PATH='@s9s_mb_2u_lib.s9s_mb_2u(sch_1):page288_i46@pure_quanta.tp_tdr_4p_fts(c~
hips)',
 P_PATH='@s9s_mb_2u_lib.s9s_mb_2u(sch_1):page309_i46@pure_quanta.tp_tdr_4p_fts(c~
hips)',
 PATH='I46',
 DRAWING='@S9S_MB_2U_LIB.S9S_MB_2U(SCH_1):PAGE288',
 PHYS_PAGE='309',
 XY='(2025,-950)',
 ROT='4',
 VER='1',
 PACK_TYPE='TH',
 CDS_LIB='pure_quanta',
 CDS_PART_NAME='TP_TDR_4P_FTS_TH-TP_TDR_4P_DIPA',
 MATERIAL='EMPTY',
 VALUE='TP_TDR_4P_DIP',
 PRIM_FILE='./archive_libs/logical/tp_tdr_4p_fts/chips/chips.prt';

PART_NAME
 X13 'TP_TDR_4P_FTS_TH-TP_TDR_4P_DIPA':;

SECTION_NUMBER 1
 '@S9S_MB_2U_LIB.S9S_MB_2U(SCH_1):PAGE288_I11@PURE_QUANTA.TP_TDR_4P_FTS(CHIPS)':
 C_PATH='@s9s_mb_2u_lib.s9s_mb_2u(sch_1):page288_i11@pure_quanta.tp_tdr_4p_fts(c~
hips)',
 P_PATH='@s9s_mb_2u_lib.s9s_mb_2u(sch_1):page309_i11@pure_quanta.tp_tdr_4p_fts(c~
hips)',
 PATH='I11',
 DRAWING='@S9S_MB_2U_LIB.S9S_MB_2U(SCH_1):PAGE288',
 PHYS_PAGE='309',
 XY='(3400,4250)',
 ROT='0',
 VER='1',
 PACK_TYPE='TH',
 CDS_LIB='pure_quanta',
 CDS_PART_NAME='TP_TDR_4P_FTS_TH-TP_TDR_4P_DIPA',
 MATERIAL='EMPTY',
 VALUE='TP_TDR_4P_DIP',
 PRIM_FILE='./archive_libs/logical/tp_tdr_4p_fts/chips/chips.prt';

PART_NAME
 X14 'TP_TDR_4P_FTS_TH-TP_TDR_4P_DIPA':;

SECTION_NUMBER 1
 '@S9S_MB_2U_LIB.S9S_MB_2U(SCH_1):PAGE288_I12@PURE_QUANTA.TP_TDR_4P_FTS(CHIPS)':
 C_PATH='@s9s_mb_2u_lib.s9s_mb_2u(sch_1):page288_i12@pure_quanta.tp_tdr_4p_fts(c~
hips)',
 P_PATH='@s9s_mb_2u_lib.s9s_mb_2u(sch_1):page309_i12@pure_quanta.tp_tdr_4p_fts(c~
hips)',
 PATH='I12',
 DRAWING='@S9S_MB_2U_LIB.S9S_MB_2U(SCH_1):PAGE288',
 PHYS_PAGE='309',
 XY='(3400,3475)',
 ROT='0',
 VER='1',
 PACK_TYPE='TH',
 CDS_LIB='pure_quanta',
 CDS_PART_NAME='TP_TDR_4P_FTS_TH-TP_TDR_4P_DIPA',
 MATERIAL='EMPTY',
 VALUE='TP_TDR_4P_DIP',
 PRIM_FILE='./archive_libs/logical/tp_tdr_4p_fts/chips/chips.prt';

PART_NAME
 X15 'TP_TDR_4P_FTS_TH-TP_TDR_4P_DIPA':;

SECTION_NUMBER 1
 '@S9S_MB_2U_LIB.S9S_MB_2U(SCH_1):PAGE288_I17@PURE_QUANTA.TP_TDR_4P_FTS(CHIPS)':
 C_PATH='@s9s_mb_2u_lib.s9s_mb_2u(sch_1):page288_i17@pure_quanta.tp_tdr_4p_fts(c~
hips)',
 P_PATH='@s9s_mb_2u_lib.s9s_mb_2u(sch_1):page309_i17@pure_quanta.tp_tdr_4p_fts(c~
hips)',
 PATH='I17',
 DRAWING='@S9S_MB_2U_LIB.S9S_MB_2U(SCH_1):PAGE288',
 PHYS_PAGE='309',
 XY='(3400,2700)',
 ROT='0',
 VER='1',
 PACK_TYPE='TH',
 CDS_LIB='pure_quanta',
 CDS_PART_NAME='TP_TDR_4P_FTS_TH-TP_TDR_4P_DIPA',
 MATERIAL='EMPTY',
 VALUE='TP_TDR_4P_DIP',
 PRIM_FILE='./archive_libs/logical/tp_tdr_4p_fts/chips/chips.prt';

PART_NAME
 X16 'TP_TDR_4P_FTS_TH-TP_TDR_4P_DIPA':;

SECTION_NUMBER 1
 '@S9S_MB_2U_LIB.S9S_MB_2U(SCH_1):PAGE288_I18@PURE_QUANTA.TP_TDR_4P_FTS(CHIPS)':
 C_PATH='@s9s_mb_2u_lib.s9s_mb_2u(sch_1):page288_i18@pure_quanta.tp_tdr_4p_fts(c~
hips)',
 P_PATH='@s9s_mb_2u_lib.s9s_mb_2u(sch_1):page309_i18@pure_quanta.tp_tdr_4p_fts(c~
hips)',
 PATH='I18',
 DRAWING='@S9S_MB_2U_LIB.S9S_MB_2U(SCH_1):PAGE288',
 PHYS_PAGE='309',
 XY='(3400,1925)',
 ROT='0',
 VER='1',
 PACK_TYPE='TH',
 CDS_LIB='pure_quanta',
 CDS_PART_NAME='TP_TDR_4P_FTS_TH-TP_TDR_4P_DIPA',
 MATERIAL='EMPTY',
 VALUE='TP_TDR_4P_DIP',
 PRIM_FILE='./archive_libs/logical/tp_tdr_4p_fts/chips/chips.prt';

PART_NAME
 X17 'TP_TDR_4P_FTS_TH-TP_TDR_4P_DIPA':;

SECTION_NUMBER 1
 '@S9S_MB_2U_LIB.S9S_MB_2U(SCH_1):PAGE288_I19@PURE_QUANTA.TP_TDR_4P_FTS(CHIPS)':
 C_PATH='@s9s_mb_2u_lib.s9s_mb_2u(sch_1):page288_i19@pure_quanta.tp_tdr_4p_fts(c~
hips)',
 P_PATH='@s9s_mb_2u_lib.s9s_mb_2u(sch_1):page309_i19@pure_quanta.tp_tdr_4p_fts(c~
hips)',
 PATH='I19',
 DRAWING='@S9S_MB_2U_LIB.S9S_MB_2U(SCH_1):PAGE288',
 PHYS_PAGE='309',
 XY='(3400,1150)',
 ROT='0',
 VER='1',
 PACK_TYPE='TH',
 CDS_LIB='pure_quanta',
 CDS_PART_NAME='TP_TDR_4P_FTS_TH-TP_TDR_4P_DIPA',
 MATERIAL='EMPTY',
 VALUE='TP_TDR_4P_DIP',
 PRIM_FILE='./archive_libs/logical/tp_tdr_4p_fts/chips/chips.prt';

PART_NAME
 X18 'TP_TDR_4P_FTS_TH-TP_TDR_4P_DIPA':;

SECTION_NUMBER 1
 '@S9S_MB_2U_LIB.S9S_MB_2U(SCH_1):PAGE288_I43@PURE_QUANTA.TP_TDR_4P_FTS(CHIPS)':
 C_PATH='@s9s_mb_2u_lib.s9s_mb_2u(sch_1):page288_i43@pure_quanta.tp_tdr_4p_fts(c~
hips)',
 P_PATH='@s9s_mb_2u_lib.s9s_mb_2u(sch_1):page309_i43@pure_quanta.tp_tdr_4p_fts(c~
hips)',
 PATH='I43',
 DRAWING='@S9S_MB_2U_LIB.S9S_MB_2U(SCH_1):PAGE288',
 PHYS_PAGE='309',
 XY='(3375,-950)',
 ROT='0',
 VER='1',
 PACK_TYPE='TH',
 CDS_LIB='pure_quanta',
 CDS_PART_NAME='TP_TDR_4P_FTS_TH-TP_TDR_4P_DIPA',
 MATERIAL='EMPTY',
 VALUE='TP_TDR_4P_DIP',
 PRIM_FILE='./archive_libs/logical/tp_tdr_4p_fts/chips/chips.prt';

PART_NAME
 X19 'TP_TDR_4P_FTS_TH-TP_TDR_4P_DIPA':;

SECTION_NUMBER 1
 '@S9S_MB_2U_LIB.S9S_MB_2U(SCH_1):PAGE288_I3@PURE_QUANTA.TP_TDR_4P_FTS(CHIPS)':
 C_PATH='@s9s_mb_2u_lib.s9s_mb_2u(sch_1):page288_i3@pure_quanta.tp_tdr_4p_fts(ch~
ips)',
 P_PATH='@s9s_mb_2u_lib.s9s_mb_2u(sch_1):page309_i3@pure_quanta.tp_tdr_4p_fts(ch~
ips)',
 PATH='I3',
 DRAWING='@S9S_MB_2U_LIB.S9S_MB_2U(SCH_1):PAGE288',
 PHYS_PAGE='309',
 XY='(4725,4250)',
 ROT='4',
 VER='1',
 PACK_TYPE='TH',
 CDS_LIB='pure_quanta',
 CDS_PART_NAME='TP_TDR_4P_FTS_TH-TP_TDR_4P_DIPA',
 MATERIAL='EMPTY',
 VALUE='TP_TDR_4P_DIP',
 PRIM_FILE='./archive_libs/logical/tp_tdr_4p_fts/chips/chips.prt';

PART_NAME
 X20 'TP_TDR_4P_FTS_TH-TP_TDR_4P_DIPA':;

SECTION_NUMBER 1
 '@S9S_MB_2U_LIB.S9S_MB_2U(SCH_1):PAGE288_I4@PURE_QUANTA.TP_TDR_4P_FTS(CHIPS)':
 C_PATH='@s9s_mb_2u_lib.s9s_mb_2u(sch_1):page288_i4@pure_quanta.tp_tdr_4p_fts(ch~
ips)',
 P_PATH='@s9s_mb_2u_lib.s9s_mb_2u(sch_1):page309_i4@pure_quanta.tp_tdr_4p_fts(ch~
ips)',
 PATH='I4',
 DRAWING='@S9S_MB_2U_LIB.S9S_MB_2U(SCH_1):PAGE288',
 PHYS_PAGE='309',
 XY='(4725,3475)',
 ROT='4',
 VER='1',
 PACK_TYPE='TH',
 CDS_LIB='pure_quanta',
 CDS_PART_NAME='TP_TDR_4P_FTS_TH-TP_TDR_4P_DIPA',
 MATERIAL='EMPTY',
 VALUE='TP_TDR_4P_DIP',
 PRIM_FILE='./archive_libs/logical/tp_tdr_4p_fts/chips/chips.prt';

PART_NAME
 X21 'TP_TDR_4P_FTS_TH-TP_TDR_4P_DIPA':;

SECTION_NUMBER 1
 '@S9S_MB_2U_LIB.S9S_MB_2U(SCH_1):PAGE288_I9@PURE_QUANTA.TP_TDR_4P_FTS(CHIPS)':
 C_PATH='@s9s_mb_2u_lib.s9s_mb_2u(sch_1):page288_i9@pure_quanta.tp_tdr_4p_fts(ch~
ips)',
 P_PATH='@s9s_mb_2u_lib.s9s_mb_2u(sch_1):page309_i9@pure_quanta.tp_tdr_4p_fts(ch~
ips)',
 PATH='I9',
 DRAWING='@S9S_MB_2U_LIB.S9S_MB_2U(SCH_1):PAGE288',
 PHYS_PAGE='309',
 XY='(4725,2700)',
 ROT='4',
 VER='1',
 PACK_TYPE='TH',
 CDS_LIB='pure_quanta',
 CDS_PART_NAME='TP_TDR_4P_FTS_TH-TP_TDR_4P_DIPA',
 MATERIAL='EMPTY',
 VALUE='TP_TDR_4P_DIP',
 PRIM_FILE='./archive_libs/logical/tp_tdr_4p_fts/chips/chips.prt';

PART_NAME
 X22 'TP_TDR_4P_FTS_TH-TP_TDR_4P_DIPA':;

SECTION_NUMBER 1
 '@S9S_MB_2U_LIB.S9S_MB_2U(SCH_1):PAGE288_I8@PURE_QUANTA.TP_TDR_4P_FTS(CHIPS)':
 C_PATH='@s9s_mb_2u_lib.s9s_mb_2u(sch_1):page288_i8@pure_quanta.tp_tdr_4p_fts(ch~
ips)',
 P_PATH='@s9s_mb_2u_lib.s9s_mb_2u(sch_1):page309_i8@pure_quanta.tp_tdr_4p_fts(ch~
ips)',
 PATH='I8',
 DRAWING='@S9S_MB_2U_LIB.S9S_MB_2U(SCH_1):PAGE288',
 PHYS_PAGE='309',
 XY='(4725,1925)',
 ROT='4',
 VER='1',
 PACK_TYPE='TH',
 CDS_LIB='pure_quanta',
 CDS_PART_NAME='TP_TDR_4P_FTS_TH-TP_TDR_4P_DIPA',
 MATERIAL='EMPTY',
 VALUE='TP_TDR_4P_DIP',
 PRIM_FILE='./archive_libs/logical/tp_tdr_4p_fts/chips/chips.prt';

PART_NAME
 X23 'TP_TDR_4P_FTS_TH-TP_TDR_4P_DIPA':;

SECTION_NUMBER 1
 '@S9S_MB_2U_LIB.S9S_MB_2U(SCH_1):PAGE288_I10@PURE_QUANTA.TP_TDR_4P_FTS(CHIPS)':
 C_PATH='@s9s_mb_2u_lib.s9s_mb_2u(sch_1):page288_i10@pure_quanta.tp_tdr_4p_fts(c~
hips)',
 P_PATH='@s9s_mb_2u_lib.s9s_mb_2u(sch_1):page309_i10@pure_quanta.tp_tdr_4p_fts(c~
hips)',
 PATH='I10',
 DRAWING='@S9S_MB_2U_LIB.S9S_MB_2U(SCH_1):PAGE288',
 PHYS_PAGE='309',
 XY='(4725,1150)',
 ROT='4',
 VER='1',
 PACK_TYPE='TH',
 CDS_LIB='pure_quanta',
 CDS_PART_NAME='TP_TDR_4P_FTS_TH-TP_TDR_4P_DIPA',
 MATERIAL='EMPTY',
 VALUE='TP_TDR_4P_DIP',
 PRIM_FILE='./archive_libs/logical/tp_tdr_4p_fts/chips/chips.prt';

PART_NAME
 X24 'TP_TDR_4P_FTS_TH-TP_TDR_4P_DIPA':;

SECTION_NUMBER 1
 '@S9S_MB_2U_LIB.S9S_MB_2U(SCH_1):PAGE288_I42@PURE_QUANTA.TP_TDR_4P_FTS(CHIPS)':
 C_PATH='@s9s_mb_2u_lib.s9s_mb_2u(sch_1):page288_i42@pure_quanta.tp_tdr_4p_fts(c~
hips)',
 P_PATH='@s9s_mb_2u_lib.s9s_mb_2u(sch_1):page309_i42@pure_quanta.tp_tdr_4p_fts(c~
hips)',
 PATH='I42',
 DRAWING='@S9S_MB_2U_LIB.S9S_MB_2U(SCH_1):PAGE288',
 PHYS_PAGE='309',
 XY='(4700,-950)',
 ROT='4',
 VER='1',
 PACK_TYPE='TH',
 CDS_LIB='pure_quanta',
 CDS_PART_NAME='TP_TDR_4P_FTS_TH-TP_TDR_4P_DIPA',
 MATERIAL='EMPTY',
 VALUE='TP_TDR_4P_DIP',
 PRIM_FILE='./archive_libs/logical/tp_tdr_4p_fts/chips/chips.prt';

PART_NAME
 X25 'TP_TDR_4P_FTS_TH-TP_TDR_4P_DIPA':;

SECTION_NUMBER 1
 '@S9S_MB_2U_LIB.S9S_MB_2U(SCH_1):PAGE288_I108@PURE_QUANTA.TP_TDR_4P_FTS(CHIPS)':
 C_PATH='@s9s_mb_2u_lib.s9s_mb_2u(sch_1):page288_i108@pure_quanta.tp_tdr_4p_fts(~
chips)',
 P_PATH='@s9s_mb_2u_lib.s9s_mb_2u(sch_1):page309_i108@pure_quanta.tp_tdr_4p_fts(~
chips)',
 PATH='I108',
 DRAWING='@S9S_MB_2U_LIB.S9S_MB_2U(SCH_1):PAGE288',
 PHYS_PAGE='309',
 XY='(700,475)',
 ROT='0',
 VER='1',
 PACK_TYPE='TH',
 CDS_LIB='pure_quanta',
 CDS_PART_NAME='TP_TDR_4P_FTS_TH-TP_TDR_4P_DIPA',
 MATERIAL='EMPTY',
 VALUE='TP_TDR_4P_DIP',
 PRIM_FILE='./archive_libs/logical/tp_tdr_4p_fts/chips/chips.prt';

PART_NAME
 X26 'TP_TDR_4P_FTS_TH-TP_TDR_4P_DIPA':;

SECTION_NUMBER 1
 '@S9S_MB_2U_LIB.S9S_MB_2U(SCH_1):PAGE288_I110@PURE_QUANTA.TP_TDR_4P_FTS(CHIPS)':
 C_PATH='@s9s_mb_2u_lib.s9s_mb_2u(sch_1):page288_i110@pure_quanta.tp_tdr_4p_fts(~
chips)',
 P_PATH='@s9s_mb_2u_lib.s9s_mb_2u(sch_1):page309_i110@pure_quanta.tp_tdr_4p_fts(~
chips)',
 PATH='I110',
 DRAWING='@S9S_MB_2U_LIB.S9S_MB_2U(SCH_1):PAGE288',
 PHYS_PAGE='309',
 XY='(700,-300)',
 ROT='0',
 VER='1',
 PACK_TYPE='TH',
 CDS_LIB='pure_quanta',
 CDS_PART_NAME='TP_TDR_4P_FTS_TH-TP_TDR_4P_DIPA',
 MATERIAL='EMPTY',
 VALUE='TP_TDR_4P_DIP',
 PRIM_FILE='./archive_libs/logical/tp_tdr_4p_fts/chips/chips.prt';

PART_NAME
 X27 'TP_TDR_4P_FTS_TH-TP_TDR_4P_DIPA':;

SECTION_NUMBER 1
 '@S9S_MB_2U_LIB.S9S_MB_2U(SCH_1):PAGE288_I106@PURE_QUANTA.TP_TDR_4P_FTS(CHIPS)':
 C_PATH='@s9s_mb_2u_lib.s9s_mb_2u(sch_1):page288_i106@pure_quanta.tp_tdr_4p_fts(~
chips)',
 P_PATH='@s9s_mb_2u_lib.s9s_mb_2u(sch_1):page309_i106@pure_quanta.tp_tdr_4p_fts(~
chips)',
 PATH='I106',
 DRAWING='@S9S_MB_2U_LIB.S9S_MB_2U(SCH_1):PAGE288',
 PHYS_PAGE='309',
 XY='(2025,475)',
 ROT='4',
 VER='1',
 PACK_TYPE='TH',
 CDS_LIB='pure_quanta',
 CDS_PART_NAME='TP_TDR_4P_FTS_TH-TP_TDR_4P_DIPA',
 MATERIAL='EMPTY',
 VALUE='TP_TDR_4P_DIP',
 PRIM_FILE='./archive_libs/logical/tp_tdr_4p_fts/chips/chips.prt';

PART_NAME
 X28 'TP_TDR_4P_FTS_TH-TP_TDR_4P_DIPA':;

SECTION_NUMBER 1
 '@S9S_MB_2U_LIB.S9S_MB_2U(SCH_1):PAGE288_I107@PURE_QUANTA.TP_TDR_4P_FTS(CHIPS)':
 C_PATH='@s9s_mb_2u_lib.s9s_mb_2u(sch_1):page288_i107@pure_quanta.tp_tdr_4p_fts(~
chips)',
 P_PATH='@s9s_mb_2u_lib.s9s_mb_2u(sch_1):page309_i107@pure_quanta.tp_tdr_4p_fts(~
chips)',
 PATH='I107',
 DRAWING='@S9S_MB_2U_LIB.S9S_MB_2U(SCH_1):PAGE288',
 PHYS_PAGE='309',
 XY='(2025,-300)',
 ROT='4',
 VER='1',
 PACK_TYPE='TH',
 CDS_LIB='pure_quanta',
 CDS_PART_NAME='TP_TDR_4P_FTS_TH-TP_TDR_4P_DIPA',
 MATERIAL='EMPTY',
 VALUE='TP_TDR_4P_DIP',
 PRIM_FILE='./archive_libs/logical/tp_tdr_4p_fts/chips/chips.prt';

PART_NAME
 X29 'TP_TDR_4P_FTS_TH-TP_TDR_4P_DIPA':;

SECTION_NUMBER 1
 '@S9S_MB_2U_LIB.S9S_MB_2U(SCH_1):PAGE288_I116@PURE_QUANTA.TP_TDR_4P_FTS(CHIPS)':
 C_PATH='@s9s_mb_2u_lib.s9s_mb_2u(sch_1):page288_i116@pure_quanta.tp_tdr_4p_fts(~
chips)',
 P_PATH='@s9s_mb_2u_lib.s9s_mb_2u(sch_1):page309_i116@pure_quanta.tp_tdr_4p_fts(~
chips)',
 PATH='I116',
 DRAWING='@S9S_MB_2U_LIB.S9S_MB_2U(SCH_1):PAGE288',
 PHYS_PAGE='309',
 XY='(3375,475)',
 ROT='0',
 VER='1',
 PACK_TYPE='TH',
 CDS_LIB='pure_quanta',
 CDS_PART_NAME='TP_TDR_4P_FTS_TH-TP_TDR_4P_DIPA',
 MATERIAL='EMPTY',
 VALUE='TP_TDR_4P_DIP',
 PRIM_FILE='./archive_libs/logical/tp_tdr_4p_fts/chips/chips.prt';

PART_NAME
 X30 'TP_TDR_4P_FTS_TH-TP_TDR_4P_DIPA':;

SECTION_NUMBER 1
 '@S9S_MB_2U_LIB.S9S_MB_2U(SCH_1):PAGE288_I117@PURE_QUANTA.TP_TDR_4P_FTS(CHIPS)':
 C_PATH='@s9s_mb_2u_lib.s9s_mb_2u(sch_1):page288_i117@pure_quanta.tp_tdr_4p_fts(~
chips)',
 P_PATH='@s9s_mb_2u_lib.s9s_mb_2u(sch_1):page309_i117@pure_quanta.tp_tdr_4p_fts(~
chips)',
 PATH='I117',
 DRAWING='@S9S_MB_2U_LIB.S9S_MB_2U(SCH_1):PAGE288',
 PHYS_PAGE='309',
 XY='(3375,-300)',
 ROT='0',
 VER='1',
 PACK_TYPE='TH',
 CDS_LIB='pure_quanta',
 CDS_PART_NAME='TP_TDR_4P_FTS_TH-TP_TDR_4P_DIPA',
 MATERIAL='EMPTY',
 VALUE='TP_TDR_4P_DIP',
 PRIM_FILE='./archive_libs/logical/tp_tdr_4p_fts/chips/chips.prt';

PART_NAME
 X31 'TP_TDR_4P_FTS_TH-TP_TDR_4P_DIPA':;

SECTION_NUMBER 1
 '@S9S_MB_2U_LIB.S9S_MB_2U(SCH_1):PAGE288_I112@PURE_QUANTA.TP_TDR_4P_FTS(CHIPS)':
 C_PATH='@s9s_mb_2u_lib.s9s_mb_2u(sch_1):page288_i112@pure_quanta.tp_tdr_4p_fts(~
chips)',
 P_PATH='@s9s_mb_2u_lib.s9s_mb_2u(sch_1):page309_i112@pure_quanta.tp_tdr_4p_fts(~
chips)',
 PATH='I112',
 DRAWING='@S9S_MB_2U_LIB.S9S_MB_2U(SCH_1):PAGE288',
 PHYS_PAGE='309',
 XY='(4700,475)',
 ROT='4',
 VER='1',
 PACK_TYPE='TH',
 CDS_LIB='pure_quanta',
 CDS_PART_NAME='TP_TDR_4P_FTS_TH-TP_TDR_4P_DIPA',
 MATERIAL='EMPTY',
 VALUE='TP_TDR_4P_DIP',
 PRIM_FILE='./archive_libs/logical/tp_tdr_4p_fts/chips/chips.prt';

PART_NAME
 X32 'TP_TDR_4P_FTS_TH-TP_TDR_4P_DIPA':;

SECTION_NUMBER 1
 '@S9S_MB_2U_LIB.S9S_MB_2U(SCH_1):PAGE288_I115@PURE_QUANTA.TP_TDR_4P_FTS(CHIPS)':
 C_PATH='@s9s_mb_2u_lib.s9s_mb_2u(sch_1):page288_i115@pure_quanta.tp_tdr_4p_fts(~
chips)',
 P_PATH='@s9s_mb_2u_lib.s9s_mb_2u(sch_1):page309_i115@pure_quanta.tp_tdr_4p_fts(~
chips)',
 PATH='I115',
 DRAWING='@S9S_MB_2U_LIB.S9S_MB_2U(SCH_1):PAGE288',
 PHYS_PAGE='309',
 XY='(4700,-300)',
 ROT='4',
 VER='1',
 PACK_TYPE='TH',
 CDS_LIB='pure_quanta',
 CDS_PART_NAME='TP_TDR_4P_FTS_TH-TP_TDR_4P_DIPA',
 MATERIAL='EMPTY',
 VALUE='TP_TDR_4P_DIP',
 PRIM_FILE='./archive_libs/logical/tp_tdr_4p_fts/chips/chips.prt';

PART_NAME
 X33 'TP_TDR_4P_FTS_TH-TP_TDR_4P_DIPA':;

SECTION_NUMBER 1
 '@S9S_MB_2U_LIB.S9S_MB_2U(SCH_1):PAGE310_I20@PURE_QUANTA.TP_TDR_4P_FTS(CHIPS)':
 C_PATH='@s9s_mb_2u_lib.s9s_mb_2u(sch_1):page310_i20@pure_quanta.tp_tdr_4p_fts(c~
hips)',
 P_PATH='@s9s_mb_2u_lib.s9s_mb_2u(sch_1):page310_i20@pure_quanta.tp_tdr_4p_fts(c~
hips)',
 PATH='I20',
 DRAWING='@S9S_MB_2U_LIB.S9S_MB_2U(SCH_1):PAGE310',
 PHYS_PAGE='310',
 XY='(-1900,3350)',
 ROT='0',
 VER='1',
 PACK_TYPE='TH',
 CDS_LIB='pure_quanta',
 CDS_PART_NAME='TP_TDR_4P_FTS_TH-TP_TDR_4P_DIPA',
 MATERIAL='EMPTY',
 VALUE='TP_TDR_4P_DIP',
 PRIM_FILE='./archive_libs/logical/tp_tdr_4p_fts/chips/chips.prt';

PART_NAME
 X34 'TP_TDR_4P_FTS_TH-TP_TDR_4P_DIPA':;

SECTION_NUMBER 1
 '@S9S_MB_2U_LIB.S9S_MB_2U(SCH_1):PAGE310_I19@PURE_QUANTA.TP_TDR_4P_FTS(CHIPS)':
 C_PATH='@s9s_mb_2u_lib.s9s_mb_2u(sch_1):page310_i19@pure_quanta.tp_tdr_4p_fts(c~
hips)',
 P_PATH='@s9s_mb_2u_lib.s9s_mb_2u(sch_1):page310_i19@pure_quanta.tp_tdr_4p_fts(c~
hips)',
 PATH='I19',
 DRAWING='@S9S_MB_2U_LIB.S9S_MB_2U(SCH_1):PAGE310',
 PHYS_PAGE='310',
 XY='(-1900,2575)',
 ROT='0',
 VER='1',
 PACK_TYPE='TH',
 CDS_LIB='pure_quanta',
 CDS_PART_NAME='TP_TDR_4P_FTS_TH-TP_TDR_4P_DIPA',
 MATERIAL='EMPTY',
 VALUE='TP_TDR_4P_DIP',
 PRIM_FILE='./archive_libs/logical/tp_tdr_4p_fts/chips/chips.prt';

PART_NAME
 X35 'TP_TDR_4P_FTS_TH-TP_TDR_4P_DIPA':;

SECTION_NUMBER 1
 '@S9S_MB_2U_LIB.S9S_MB_2U(SCH_1):PAGE310_I16@PURE_QUANTA.TP_TDR_4P_FTS(CHIPS)':
 C_PATH='@s9s_mb_2u_lib.s9s_mb_2u(sch_1):page310_i16@pure_quanta.tp_tdr_4p_fts(c~
hips)',
 P_PATH='@s9s_mb_2u_lib.s9s_mb_2u(sch_1):page310_i16@pure_quanta.tp_tdr_4p_fts(c~
hips)',
 PATH='I16',
 DRAWING='@S9S_MB_2U_LIB.S9S_MB_2U(SCH_1):PAGE310',
 PHYS_PAGE='310',
 XY='(-1900,1800)',
 ROT='0',
 VER='1',
 PACK_TYPE='TH',
 CDS_LIB='pure_quanta',
 CDS_PART_NAME='TP_TDR_4P_FTS_TH-TP_TDR_4P_DIPA',
 MATERIAL='EMPTY',
 VALUE='TP_TDR_4P_DIP',
 PRIM_FILE='./archive_libs/logical/tp_tdr_4p_fts/chips/chips.prt';

PART_NAME
 X36 'TP_TDR_4P_FTS_TH-TP_TDR_4P_DIPA':;

SECTION_NUMBER 1
 '@S9S_MB_2U_LIB.S9S_MB_2U(SCH_1):PAGE310_I8@PURE_QUANTA.TP_TDR_4P_FTS(CHIPS)':
 C_PATH='@s9s_mb_2u_lib.s9s_mb_2u(sch_1):page310_i8@pure_quanta.tp_tdr_4p_fts(ch~
ips)',
 P_PATH='@s9s_mb_2u_lib.s9s_mb_2u(sch_1):page310_i8@pure_quanta.tp_tdr_4p_fts(ch~
ips)',
 PATH='I8',
 DRAWING='@S9S_MB_2U_LIB.S9S_MB_2U(SCH_1):PAGE310',
 PHYS_PAGE='310',
 XY='(-1900,1025)',
 ROT='0',
 VER='1',
 PACK_TYPE='TH',
 CDS_LIB='pure_quanta',
 CDS_PART_NAME='TP_TDR_4P_FTS_TH-TP_TDR_4P_DIPA',
 MATERIAL='EMPTY',
 VALUE='TP_TDR_4P_DIP',
 PRIM_FILE='./archive_libs/logical/tp_tdr_4p_fts/chips/chips.prt';

PART_NAME
 X37 'TP_TDR_4P_FTS_TH-TP_TDR_4P_DIPA':;

SECTION_NUMBER 1
 '@S9S_MB_2U_LIB.S9S_MB_2U(SCH_1):PAGE310_I7@PURE_QUANTA.TP_TDR_4P_FTS(CHIPS)':
 C_PATH='@s9s_mb_2u_lib.s9s_mb_2u(sch_1):page310_i7@pure_quanta.tp_tdr_4p_fts(ch~
ips)',
 P_PATH='@s9s_mb_2u_lib.s9s_mb_2u(sch_1):page310_i7@pure_quanta.tp_tdr_4p_fts(ch~
ips)',
 PATH='I7',
 DRAWING='@S9S_MB_2U_LIB.S9S_MB_2U(SCH_1):PAGE310',
 PHYS_PAGE='310',
 XY='(-1900,350)',
 ROT='0',
 VER='1',
 PACK_TYPE='TH',
 CDS_LIB='pure_quanta',
 CDS_PART_NAME='TP_TDR_4P_FTS_TH-TP_TDR_4P_DIPA',
 MATERIAL='EMPTY',
 VALUE='TP_TDR_4P_DIP',
 PRIM_FILE='./archive_libs/logical/tp_tdr_4p_fts/chips/chips.prt';

PART_NAME
 X38 'TP_TDR_4P_FTS_TH-TP_TDR_4P_DIPA':;

SECTION_NUMBER 1
 '@S9S_MB_2U_LIB.S9S_MB_2U(SCH_1):PAGE310_I5@PURE_QUANTA.TP_TDR_4P_FTS(CHIPS)':
 C_PATH='@s9s_mb_2u_lib.s9s_mb_2u(sch_1):page310_i5@pure_quanta.tp_tdr_4p_fts(ch~
ips)',
 P_PATH='@s9s_mb_2u_lib.s9s_mb_2u(sch_1):page310_i5@pure_quanta.tp_tdr_4p_fts(ch~
ips)',
 PATH='I5',
 DRAWING='@S9S_MB_2U_LIB.S9S_MB_2U(SCH_1):PAGE310',
 PHYS_PAGE='310',
 XY='(-1900,-425)',
 ROT='0',
 VER='1',
 PACK_TYPE='TH',
 CDS_LIB='pure_quanta',
 CDS_PART_NAME='TP_TDR_4P_FTS_TH-TP_TDR_4P_DIPA',
 MATERIAL='EMPTY',
 VALUE='TP_TDR_4P_DIP',
 PRIM_FILE='./archive_libs/logical/tp_tdr_4p_fts/chips/chips.prt';

PART_NAME
 X39 'TP_TDR_4P_FTS_TH-TP_TDR_4P_DIPA':;

SECTION_NUMBER 1
 '@S9S_MB_2U_LIB.S9S_MB_2U(SCH_1):PAGE310_I22@PURE_QUANTA.TP_TDR_4P_FTS(CHIPS)':
 C_PATH='@s9s_mb_2u_lib.s9s_mb_2u(sch_1):page310_i22@pure_quanta.tp_tdr_4p_fts(c~
hips)',
 P_PATH='@s9s_mb_2u_lib.s9s_mb_2u(sch_1):page310_i22@pure_quanta.tp_tdr_4p_fts(c~
hips)',
 PATH='I22',
 DRAWING='@S9S_MB_2U_LIB.S9S_MB_2U(SCH_1):PAGE310',
 PHYS_PAGE='310',
 XY='(-575,3350)',
 ROT='4',
 VER='1',
 PACK_TYPE='TH',
 CDS_LIB='pure_quanta',
 CDS_PART_NAME='TP_TDR_4P_FTS_TH-TP_TDR_4P_DIPA',
 MATERIAL='EMPTY',
 VALUE='TP_TDR_4P_DIP',
 PRIM_FILE='./archive_libs/logical/tp_tdr_4p_fts/chips/chips.prt';

PART_NAME
 X40 'TP_TDR_4P_FTS_TH-TP_TDR_4P_DIPA':;

SECTION_NUMBER 1
 '@S9S_MB_2U_LIB.S9S_MB_2U(SCH_1):PAGE310_I21@PURE_QUANTA.TP_TDR_4P_FTS(CHIPS)':
 C_PATH='@s9s_mb_2u_lib.s9s_mb_2u(sch_1):page310_i21@pure_quanta.tp_tdr_4p_fts(c~
hips)',
 P_PATH='@s9s_mb_2u_lib.s9s_mb_2u(sch_1):page310_i21@pure_quanta.tp_tdr_4p_fts(c~
hips)',
 PATH='I21',
 DRAWING='@S9S_MB_2U_LIB.S9S_MB_2U(SCH_1):PAGE310',
 PHYS_PAGE='310',
 XY='(-575,2575)',
 ROT='4',
 VER='1',
 PACK_TYPE='TH',
 CDS_LIB='pure_quanta',
 CDS_PART_NAME='TP_TDR_4P_FTS_TH-TP_TDR_4P_DIPA',
 MATERIAL='EMPTY',
 VALUE='TP_TDR_4P_DIP',
 PRIM_FILE='./archive_libs/logical/tp_tdr_4p_fts/chips/chips.prt';

PART_NAME
 X41 'TP_TDR_4P_FTS_TH-TP_TDR_4P_DIPA':;

SECTION_NUMBER 1
 '@S9S_MB_2U_LIB.S9S_MB_2U(SCH_1):PAGE310_I15@PURE_QUANTA.TP_TDR_4P_FTS(CHIPS)':
 C_PATH='@s9s_mb_2u_lib.s9s_mb_2u(sch_1):page310_i15@pure_quanta.tp_tdr_4p_fts(c~
hips)',
 P_PATH='@s9s_mb_2u_lib.s9s_mb_2u(sch_1):page310_i15@pure_quanta.tp_tdr_4p_fts(c~
hips)',
 PATH='I15',
 DRAWING='@S9S_MB_2U_LIB.S9S_MB_2U(SCH_1):PAGE310',
 PHYS_PAGE='310',
 XY='(-575,1800)',
 ROT='4',
 VER='1',
 PACK_TYPE='TH',
 CDS_LIB='pure_quanta',
 CDS_PART_NAME='TP_TDR_4P_FTS_TH-TP_TDR_4P_DIPA',
 MATERIAL='EMPTY',
 VALUE='TP_TDR_4P_DIP',
 PRIM_FILE='./archive_libs/logical/tp_tdr_4p_fts/chips/chips.prt';

PART_NAME
 X42 'TP_TDR_4P_FTS_TH-TP_TDR_4P_DIPA':;

SECTION_NUMBER 1
 '@S9S_MB_2U_LIB.S9S_MB_2U(SCH_1):PAGE310_I10@PURE_QUANTA.TP_TDR_4P_FTS(CHIPS)':
 C_PATH='@s9s_mb_2u_lib.s9s_mb_2u(sch_1):page310_i10@pure_quanta.tp_tdr_4p_fts(c~
hips)',
 P_PATH='@s9s_mb_2u_lib.s9s_mb_2u(sch_1):page310_i10@pure_quanta.tp_tdr_4p_fts(c~
hips)',
 PATH='I10',
 DRAWING='@S9S_MB_2U_LIB.S9S_MB_2U(SCH_1):PAGE310',
 PHYS_PAGE='310',
 XY='(-575,1025)',
 ROT='4',
 VER='1',
 PACK_TYPE='TH',
 CDS_LIB='pure_quanta',
 CDS_PART_NAME='TP_TDR_4P_FTS_TH-TP_TDR_4P_DIPA',
 MATERIAL='EMPTY',
 VALUE='TP_TDR_4P_DIP',
 PRIM_FILE='./archive_libs/logical/tp_tdr_4p_fts/chips/chips.prt';

PART_NAME
 X43 'TP_TDR_4P_FTS_TH-TP_TDR_4P_DIPA':;

SECTION_NUMBER 1
 '@S9S_MB_2U_LIB.S9S_MB_2U(SCH_1):PAGE310_I9@PURE_QUANTA.TP_TDR_4P_FTS(CHIPS)':
 C_PATH='@s9s_mb_2u_lib.s9s_mb_2u(sch_1):page310_i9@pure_quanta.tp_tdr_4p_fts(ch~
ips)',
 P_PATH='@s9s_mb_2u_lib.s9s_mb_2u(sch_1):page310_i9@pure_quanta.tp_tdr_4p_fts(ch~
ips)',
 PATH='I9',
 DRAWING='@S9S_MB_2U_LIB.S9S_MB_2U(SCH_1):PAGE310',
 PHYS_PAGE='310',
 XY='(-575,350)',
 ROT='4',
 VER='1',
 PACK_TYPE='TH',
 CDS_LIB='pure_quanta',
 CDS_PART_NAME='TP_TDR_4P_FTS_TH-TP_TDR_4P_DIPA',
 MATERIAL='EMPTY',
 VALUE='TP_TDR_4P_DIP',
 PRIM_FILE='./archive_libs/logical/tp_tdr_4p_fts/chips/chips.prt';

PART_NAME
 X44 'TP_TDR_4P_FTS_TH-TP_TDR_4P_DIPA':;

SECTION_NUMBER 1
 '@S9S_MB_2U_LIB.S9S_MB_2U(SCH_1):PAGE310_I6@PURE_QUANTA.TP_TDR_4P_FTS(CHIPS)':
 C_PATH='@s9s_mb_2u_lib.s9s_mb_2u(sch_1):page310_i6@pure_quanta.tp_tdr_4p_fts(ch~
ips)',
 P_PATH='@s9s_mb_2u_lib.s9s_mb_2u(sch_1):page310_i6@pure_quanta.tp_tdr_4p_fts(ch~
ips)',
 PATH='I6',
 DRAWING='@S9S_MB_2U_LIB.S9S_MB_2U(SCH_1):PAGE310',
 PHYS_PAGE='310',
 XY='(-575,-425)',
 ROT='4',
 VER='1',
 PACK_TYPE='TH',
 CDS_LIB='pure_quanta',
 CDS_PART_NAME='TP_TDR_4P_FTS_TH-TP_TDR_4P_DIPA',
 MATERIAL='EMPTY',
 VALUE='TP_TDR_4P_DIP',
 PRIM_FILE='./archive_libs/logical/tp_tdr_4p_fts/chips/chips.prt';

PART_NAME
 Y1 'Q_CRYSTAL_SMLF-32.768KHZ,IC,BGA':;

SECTION_NUMBER 1
 '@S9S_MB_2U_LIB.S9S_MB_2U(SCH_1):PAGE171_I11@PURE_QUANTA.Q_CRYSTAL(CHIPS)':
 C_PATH='@s9s_mb_2u_lib.s9s_mb_2u(sch_1):page171_i11@pure_quanta.q_crystal(chips~
)',
 P_PATH='@s9s_mb_2u_lib.s9s_mb_2u(sch_1):page179_i11@pure_quanta.q_crystal(chips~
)',
 PATH='I11',
 DRAWING='@S9S_MB_2U_LIB.S9S_MB_2U(SCH_1):PAGE171',
 PHYS_PAGE='179',
 XY='(1700,-475)',
 ROT='0',
 VER='1',
 PACK_TYPE='SMLF',
 SEC='1',
 CDS_LIB='pure_quanta',
 CDS_PART_NAME='Q_CRYSTAL_SMLF-32.768KHZ,IC,BGA',
 SEC_TYPE='SMLF',
 MATERIAL='IC',
 VALUE='32.768KHZ',
 PRIM_FILE='./archive_libs/logical/q_crystal/chips/chips.prt';

PART_NAME
 Y2 'Q_XTAL_4P_13BI_24GND-25MHZ,SMLB':;

SECTION_NUMBER 1
 '@S9S_MB_2U_LIB.S9S_MB_2U(SCH_1):PAGE197_I391@PURE_QUANTA.Q_XTAL_4P_13BI_24GND(CHIPS)':
 C_PATH='@s9s_mb_2u_lib.s9s_mb_2u(sch_1):page197_i391@pure_quanta.q_xtal_4p_13bi~
_24gnd(chips)',
 P_PATH='@s9s_mb_2u_lib.s9s_mb_2u(sch_1):page208_i391@pure_quanta.q_xtal_4p_13bi~
_24gnd(chips)',
 PATH='I391',
 DRAWING='@S9S_MB_2U_LIB.S9S_MB_2U(SCH_1):PAGE197',
 PIN_NAMES_ROTATE='True',
 PHYS_PAGE='208',
 XY='(-4725,5725)',
 ROT='0',
 VER='1',
 LOCATION='Y2',
 CDS_LIB='pure_quanta',
 CDS_PART_NAME='Q_XTAL_4P_13BI_24GND-25MHZ,SMLB',
 PART_TYPE='SMLF',
 MATERIAL='MISC',
 VALUE='25MHZ',
 PRIM_FILE='./archive_libs/logical/q_xtal_4p_13bi_24gnd/chips/chips.prt';

PART_NAME
 Y3 'Q_XTAL_4P_13BI_24GND-25MHZ,SMLB':;

SECTION_NUMBER 1
 '@S9S_MB_2U_LIB.S9S_MB_2U(SCH_1):PAGE201_I159@PURE_QUANTA.Q_XTAL_4P_13BI_24GND(CHIPS)':
 C_PATH='@s9s_mb_2u_lib.s9s_mb_2u(sch_1):page201_i159@pure_quanta.q_xtal_4p_13bi~
_24gnd(chips)',
 P_PATH='@s9s_mb_2u_lib.s9s_mb_2u(sch_1):page212_i159@pure_quanta.q_xtal_4p_13bi~
_24gnd(chips)',
 PATH='I159',
 DRAWING='@S9S_MB_2U_LIB.S9S_MB_2U(SCH_1):PAGE201',
 PIN_NAMES_ROTATE='True',
 PHYS_PAGE='212',
 XY='(-3900,3825)',
 ROT='0',
 VER='1',
 LOCATION='Y3',
 CDS_LIB='pure_quanta',
 CDS_PART_NAME='Q_XTAL_4P_13BI_24GND-25MHZ,SMLB',
 PART_TYPE='SMLF',
 MATERIAL='MISC',
 VALUE='25MHZ',
 PRIM_FILE='./archive_libs/logical/q_xtal_4p_13bi_24gnd/chips/chips.prt';

PART_NAME
 Y4 'Q_XTAL_4P_13BI_24GND-12MHZ,SMLA':
 ROOM='USB1_BOM1';

SECTION_NUMBER 1
 '@S9S_MB_2U_LIB.S9S_MB_2U(SCH_1):PAGE155_I200@PURE_QUANTA.Q_XTAL_4P_13BI_24GND(CHIPS)':
 C_PATH='@s9s_mb_2u_lib.s9s_mb_2u(sch_1):page155_i200@pure_quanta.q_xtal_4p_13bi~
_24gnd(chips)',
 P_PATH='@s9s_mb_2u_lib.s9s_mb_2u(sch_1):page152_i200@pure_quanta.q_xtal_4p_13bi~
_24gnd(chips)',
 PATH='I200',
 DRAWING='@S9S_MB_2U_LIB.S9S_MB_2U(SCH_1):PAGE155',
 PIN_NAMES_ROTATE='True',
 PHYS_PAGE='152',
 XY='(4025,4550)',
 ROT='0',
 VER='1',
 LOCATION='Y4',
 CDS_LIB='pure_quanta',
 CDS_PART_NAME='Q_XTAL_4P_13BI_24GND-12MHZ,SMLA',
 PART_TYPE='SMLF',
 MATERIAL='MISC',
 ROOM='USB1_BOM1',
 VALUE='12MHZ',
 PRIM_FILE='./archive_libs/logical/q_xtal_4p_13bi_24gnd/chips/chips.prt';

PART_NAME
 Y7 'Q_XTAL_4P_13BI_24GND-25MHZ,SMLA':;

SECTION_NUMBER 1
 '@S9S_MB_2U_LIB.S9S_MB_2U(SCH_1):PAGE171_I75@PURE_QUANTA.Q_XTAL_4P_13BI_24GND(CHIPS)':
 C_PATH='@s9s_mb_2u_lib.s9s_mb_2u(sch_1):page171_i75@pure_quanta.q_xtal_4p_13bi_~
24gnd(chips)',
 P_PATH='@s9s_mb_2u_lib.s9s_mb_2u(sch_1):page179_i75@pure_quanta.q_xtal_4p_13bi_~
24gnd(chips)',
 PATH='I75',
 DRAWING='@S9S_MB_2U_LIB.S9S_MB_2U(SCH_1):PAGE171',
 PIN_NAMES_ROTATE='True',
 PHYS_PAGE='179',
 XY='(-825,-450)',
 ROT='0',
 VER='1',
 CDS_LIB='pure_quanta',
 CDS_PART_NAME='Q_XTAL_4P_13BI_24GND-25MHZ,SMLA',
 PART_TYPE='SMLF',
 MATERIAL='EMPTY',
 VALUE='25MHZ',
 PRIM_FILE='./archive_libs/logical/q_xtal_4p_13bi_24gnd/chips/chips.prt';

PART_NAME
 Y9 'Q_XTAL_4P_13BI_24GND-12MHZ,SMLB':;

SECTION_NUMBER 1
 '@S9S_MB_2U_LIB.S9S_MB_2U(SCH_1):PAGE194_I83@PURE_QUANTA.Q_XTAL_4P_13BI_24GND(CHIPS)':
 C_PATH='@s9s_mb_2u_lib.s9s_mb_2u(sch_1):page194_i83@pure_quanta.q_xtal_4p_13bi_~
24gnd(chips)',
 P_PATH='@s9s_mb_2u_lib.s9s_mb_2u(sch_1):page196_i83@pure_quanta.q_xtal_4p_13bi_~
24gnd(chips)',
 PATH='I83',
 DRAWING='@S9S_MB_2U_LIB.S9S_MB_2U(SCH_1):PAGE194',
 PIN_NAMES_ROTATE='True',
 PHYS_PAGE='196',
 XY='(4675,2100)',
 ROT='0',
 VER='1',
 CDS_LIB='pure_quanta',
 CDS_PART_NAME='Q_XTAL_4P_13BI_24GND-12MHZ,SMLB',
 PART_TYPE='SMLF',
 MATERIAL='EMPTY',
 VALUE='12MHZ',
 PRIM_FILE='./archive_libs/logical/q_xtal_4p_13bi_24gnd/chips/chips.prt';

END.
